G04 ================== begin FILE IDENTIFICATION RECORD ==================*
G04 Layout Name:  13130-1b.brd*
G04 Film Name:    TMASK*
G04 File Format:  Gerber RS274X*
G04 File Origin:  Cadence Allegro 16.5-S037*
G04 Origin Date:  Thu Nov 13 17:26:24 2014*
G04 *
G04 Layer:  VIA CLASS/SOLDERMASK_TOP*
G04 Layer:  PIN/SOLDERMASK_TOP*
G04 Layer:  PACKAGE GEOMETRY/SOLDERMASK_TOP*
G04 Layer:  DRAWING FORMAT/LAYER_PCB_STORY*
G04 Layer:  DRAWING FORMAT/LAYER_SOLDER_T*
G04 Layer:  BOARD GEOMETRY/SOLDERMASK_TOP*
G04 *
G04 Offset:    (0.00 0.00)*
G04 Mirror:    No*
G04 Mode:      Positive*
G04 Rotation:  0*
G04 FullContactRelief:  No*
G04 UndefLineWidth:     6.00*
G04 ================== end FILE IDENTIFICATION RECORD ====================*
%FSLAX35Y35*MOIN*%
%IR0*IPPOS*OFA0.00000B0.00000*MIA0B0*SFA1.00000B1.00000*%
%ADD141R,.01X.007*%
%ADD109R,.062X.114*%
%ADD125R,.114X.062*%
%ADD47R,.03X.008*%
%ADD46R,.008X.03*%
%ADD32C,.02*%
%ADD92C,.012*%
%AMMACRO17*
4,1,40,-.009,-.01,
.009,-.01,
.009347,-.00997,
.009684,-.009879,
.01,-.009732,
.010286,-.009532,
.010532,-.009286,
.010732,-.009,
.010879,-.008684,
.01097,-.008347,
.011,-.008,
.011,.008,
.01097,.008347,
.010879,.008684,
.010732,.009,
.010532,.009286,
.010286,.009532,
.01,.009732,
.009684,.009879,
.009347,.00997,
.009,.01,
-.009,.01,
-.009347,.00997,
-.009684,.009879,
-.01,.009732,
-.010286,.009532,
-.010532,.009286,
-.010732,.009,
-.010879,.008684,
-.01097,.008347,
-.011,.008,
-.011,-.008,
-.01097,-.008347,
-.010879,-.008684,
-.010732,-.009,
-.010532,-.009286,
-.010286,-.009532,
-.01,-.009732,
-.009684,-.009879,
-.009347,-.00997,
-.009,-.01,
0.0*
%
%ADD17MACRO17*%
%ADD67R,.08X.136*%
%ADD63C,.04*%
%AMMACRO25*
4,1,40,-.01,.009,
-.01,-.009,
-.00997,-.009347,
-.009879,-.009684,
-.009732,-.01,
-.009532,-.010286,
-.009286,-.010532,
-.009,-.010732,
-.008684,-.010879,
-.008347,-.01097,
-.008,-.011,
.008,-.011,
.008347,-.01097,
.008684,-.010879,
.009,-.010732,
.009286,-.010532,
.009532,-.010286,
.009732,-.01,
.009879,-.009684,
.00997,-.009347,
.01,-.009,
.01,.009,
.00997,.009347,
.009879,.009684,
.009732,.01,
.009532,.010286,
.009286,.010532,
.009,.010732,
.008684,.010879,
.008347,.01097,
.008,.011,
-.008,.011,
-.008347,.01097,
-.008684,.010879,
-.009,.010732,
-.009286,.010532,
-.009532,.010286,
-.009732,.01,
-.009879,.009684,
-.00997,.009347,
-.01,.009,
0.0*
%
%ADD25MACRO25*%
%ADD111C,.032*%
%ADD137C,.06*%
%ADD96R,.028X.126*%
%ADD95C,.015*%
%ADD57R,.047X.108*%
%ADD128R,.026X.008*%
%ADD127R,.008X.026*%
%ADD90C,.016*%
%ADD65R,.037X.164*%
%AMMACRO53*
4,1,40,-.0155,.016,
-.0155,-.016,
-.015439,-.016695,
-.015259,-.017368,
-.014964,-.018,
-.014564,-.018571,
-.014071,-.019064,
-.0135,-.019464,
-.012868,-.019759,
-.012195,-.019939,
-.0115,-.02,
.0115,-.02,
.012195,-.019939,
.012868,-.019759,
.0135,-.019464,
.014071,-.019064,
.014564,-.018571,
.014964,-.018,
.015259,-.017368,
.015439,-.016695,
.0155,-.016,
.0155,.016,
.015439,.016695,
.015259,.017368,
.014964,.018,
.014564,.018571,
.014071,.019064,
.0135,.019464,
.012868,.019759,
.012195,.019939,
.0115,.02,
-.0115,.02,
-.012195,.019939,
-.012868,.019759,
-.0135,.019464,
-.014071,.019064,
-.014564,.018571,
-.014964,.018,
-.015259,.017368,
-.015439,.016695,
-.0155,.016,
0.0*
%
%ADD53MACRO53*%
%ADD43R,.075X.135*%
%ADD132R,.164X.037*%
%ADD36C,.044*%
%AMMACRO20*
4,1,40,.016,.0155,
-.016,.0155,
-.016695,.015439,
-.017368,.015259,
-.018,.014964,
-.018571,.014564,
-.019064,.014071,
-.019464,.0135,
-.019759,.012868,
-.019939,.012195,
-.02,.0115,
-.02,-.0115,
-.019939,-.012195,
-.019759,-.012868,
-.019464,-.0135,
-.019064,-.014071,
-.018571,-.014564,
-.018,-.014964,
-.017368,-.015259,
-.016695,-.015439,
-.016,-.0155,
.016,-.0155,
.016695,-.015439,
.017368,-.015259,
.018,-.014964,
.018571,-.014564,
.019064,-.014071,
.019464,-.0135,
.019759,-.012868,
.019939,-.012195,
.02,-.0115,
.02,.0115,
.019939,.012195,
.019759,.012868,
.019464,.0135,
.019064,.014071,
.018571,.014564,
.018,.014964,
.017368,.015259,
.016695,.015439,
.016,.0155,
0.0*
%
%ADD20MACRO20*%
%ADD11C,.08*%
%ADD130R,.028X.008*%
%ADD129R,.008X.028*%
%ADD80C,.063*%
%ADD37R,.028X.165*%
%AMMACRO134*
4,1,6,.0895,.0505,
.0895,-.0505,
-.0895,-.0505,
-.0895,.0055,
-.0415,.0055,
-.0415,.0505,
.0895,.0505,
0.0*
%
%ADD134MACRO134*%
%ADD16C,.028*%
%ADD89C,.056*%
%ADD75R,.125X.098*%
%ADD44R,.095X.128*%
%ADD34C,.065*%
%ADD140R,.098X.125*%
%ADD12C,.086*%
%AMMACRO82*
4,1,40,.02,-.005,
.019878,-.006389,
.019518,-.007736,
.018928,-.009,
.018128,-.010142,
.017142,-.011128,
.016,-.011928,
.014736,-.012518,
.013389,-.012878,
.012,-.013,
-.012,-.013,
-.013389,-.012878,
-.014736,-.012518,
-.016,-.011928,
-.017142,-.011128,
-.018128,-.010142,
-.018928,-.009,
-.019518,-.007736,
-.019878,-.006389,
-.02,-.005,
-.02,.005,
-.019878,.006389,
-.019518,.007736,
-.018928,.009,
-.018128,.010142,
-.017142,.011128,
-.016,.011928,
-.014736,.012518,
-.013389,.012878,
-.012,.013,
.012,.013,
.013389,.012878,
.014736,.012518,
.016,.011928,
.017142,.011128,
.018128,.010142,
.018928,.009,
.019518,.007736,
.019878,.006389,
.02,.005,
.02,-.005,
0.0*
%
%ADD82MACRO82*%
%AMMACRO40*
4,1,40,.009,.008,
.009,-.008,
.00897,-.008347,
.008879,-.008684,
.008732,-.009,
.008532,-.009286,
.008286,-.009532,
.008,-.009732,
.007684,-.009879,
.007347,-.00997,
.007,-.01,
-.007,-.01,
-.007347,-.00997,
-.007684,-.009879,
-.008,-.009732,
-.008286,-.009532,
-.008532,-.009286,
-.008732,-.009,
-.008879,-.008684,
-.00897,-.008347,
-.009,-.008,
-.009,.008,
-.00897,.008347,
-.008879,.008684,
-.008732,.009,
-.008532,.009286,
-.008286,.009532,
-.008,.009732,
-.007684,.009879,
-.007347,.00997,
-.007,.01,
.007,.01,
.007347,.00997,
.007684,.009879,
.008,.009732,
.008286,.009532,
.008532,.009286,
.008732,.009,
.008879,.008684,
.00897,.008347,
.009,.008,
0.0*
%
%ADD40MACRO40*%
%AMMACRO14*
4,1,40,.008,-.009,
-.008,-.009,
-.008347,-.00897,
-.008684,-.008879,
-.009,-.008732,
-.009286,-.008532,
-.009532,-.008286,
-.009732,-.008,
-.009879,-.007684,
-.00997,-.007347,
-.01,-.007,
-.01,.007,
-.00997,.007347,
-.009879,.007684,
-.009732,.008,
-.009532,.008286,
-.009286,.008532,
-.009,.008732,
-.008684,.008879,
-.008347,.00897,
-.008,.009,
.008,.009,
.008347,.00897,
.008684,.008879,
.009,.008732,
.009286,.008532,
.009532,.008286,
.009732,.008,
.009879,.007684,
.00997,.007347,
.01,.007,
.01,-.007,
.00997,-.007347,
.009879,-.007684,
.009732,-.008,
.009532,-.008286,
.009286,-.008532,
.009,-.008732,
.008684,-.008879,
.008347,-.00897,
.008,-.009,
0.0*
%
%ADD14MACRO14*%
%AMMACRO87*
4,1,40,.0145,-.0055,
.014378,-.006889,
.014018,-.008236,
.013428,-.0095,
.012628,-.010642,
.011642,-.011628,
.0105,-.012428,
.009236,-.013018,
.007889,-.013378,
.0065,-.0135,
-.0065,-.0135,
-.007889,-.013378,
-.009236,-.013018,
-.0105,-.012428,
-.011642,-.011628,
-.012628,-.010642,
-.013428,-.0095,
-.014018,-.008236,
-.014378,-.006889,
-.0145,-.0055,
-.0145,.0055,
-.014378,.006889,
-.014018,.008236,
-.013428,.0095,
-.012628,.010642,
-.011642,.011628,
-.0105,.012428,
-.009236,.013018,
-.007889,.013378,
-.0065,.0135,
.0065,.0135,
.007889,.013378,
.009236,.013018,
.0105,.012428,
.011642,.011628,
.012628,.010642,
.013428,.0095,
.014018,.008236,
.014378,.006889,
.0145,.0055,
.0145,-.0055,
0.0*
%
%ADD87MACRO87*%
%AMMACRO39*
4,1,6,.0135,-.025,
-.0065,-.005,
-.0135,-.005,
-.0135,.005,
-.0065,.005,
.0135,.025,
.0135,-.025,
0.0*
%
%ADD39MACRO39*%
%AMMACRO29*
4,1,6,-.0135,.005,
-.0065,.005,
.0135,.025,
.0135,-.025,
-.0065,-.005,
-.0135,-.005,
-.0135,.005,
0.0*
%
%ADD29MACRO29*%
%AMMACRO35*
4,1,40,.009,.008,
.009,-.008,
.00897,-.008347,
.008879,-.008684,
.008732,-.009,
.008532,-.009286,
.008286,-.009532,
.008,-.009732,
.007684,-.009879,
.007347,-.00997,
.007,-.01,
-.007,-.01,
-.007347,-.00997,
-.007684,-.009879,
-.008,-.009732,
-.008286,-.009532,
-.008532,-.009286,
-.008732,-.009,
-.008879,-.008684,
-.00897,-.008347,
-.009,-.008,
-.009,.008,
-.00897,.008347,
-.008879,.008684,
-.008732,.009,
-.008532,.009286,
-.008286,.009532,
-.008,.009732,
-.007684,.009879,
-.007347,.00997,
-.007,.01,
.007,.01,
.007347,.00997,
.007684,.009879,
.008,.009732,
.008286,.009532,
.008532,.009286,
.008732,.009,
.008879,.008684,
.00897,.008347,
.009,.008,
0.0*
%
%ADD35MACRO35*%
%AMMACRO15*
4,1,40,.008,-.009,
-.008,-.009,
-.008347,-.00897,
-.008684,-.008879,
-.009,-.008732,
-.009286,-.008532,
-.009532,-.008286,
-.009732,-.008,
-.009879,-.007684,
-.00997,-.007347,
-.01,-.007,
-.01,.007,
-.00997,.007347,
-.009879,.007684,
-.009732,.008,
-.009532,.008286,
-.009286,.008532,
-.009,.008732,
-.008684,.008879,
-.008347,.00897,
-.008,.009,
.008,.009,
.008347,.00897,
.008684,.008879,
.009,.008732,
.009286,.008532,
.009532,.008286,
.009732,.008,
.009879,.007684,
.00997,.007347,
.01,.007,
.01,-.007,
.00997,-.007347,
.009879,-.007684,
.009732,-.008,
.009532,-.008286,
.009286,-.008532,
.009,-.008732,
.008684,-.008879,
.008347,-.00897,
.008,-.009,
0.0*
%
%ADD15MACRO15*%
%ADD93O,.01X.0135*%
%ADD91O,.0135X.01*%
%ADD68R,.03X.014*%
%ADD110R,.033X.012*%
%ADD108R,.012X.05*%
%ADD107R,.05X.012*%
%ADD64R,.014X.03*%
%ADD49R,.032X.022*%
%ADD126R,.012X.033*%
%ADD81R,.012X.034*%
%ADD28R,.034X.012*%
%ADD116R,.032X.042*%
%ADD112R,.042X.032*%
%ADD70R,.04X.026*%
%AMMACRO21*
4,1,40,.01,-.009,
.01,.009,
.00997,.009347,
.009879,.009684,
.009732,.01,
.009532,.010286,
.009286,.010532,
.009,.010732,
.008684,.010879,
.008347,.01097,
.008,.011,
-.008,.011,
-.008347,.01097,
-.008684,.010879,
-.009,.010732,
-.009286,.010532,
-.009532,.010286,
-.009732,.01,
-.009879,.009684,
-.00997,.009347,
-.01,.009,
-.01,-.009,
-.00997,-.009347,
-.009879,-.009684,
-.009732,-.01,
-.009532,-.010286,
-.009286,-.010532,
-.009,-.010732,
-.008684,-.010879,
-.008347,-.01097,
-.008,-.011,
.008,-.011,
.008347,-.01097,
.008684,-.010879,
.009,-.010732,
.009286,-.010532,
.009532,-.010286,
.009732,-.01,
.009879,-.009684,
.00997,-.009347,
.01,-.009,
0.0*
%
%ADD21MACRO21*%
%AMMACRO18*
4,1,40,.009,.01,
-.009,.01,
-.009347,.00997,
-.009684,.009879,
-.01,.009732,
-.010286,.009532,
-.010532,.009286,
-.010732,.009,
-.010879,.008684,
-.01097,.008347,
-.011,.008,
-.011,-.008,
-.01097,-.008347,
-.010879,-.008684,
-.010732,-.009,
-.010532,-.009286,
-.010286,-.009532,
-.01,-.009732,
-.009684,-.009879,
-.009347,-.00997,
-.009,-.01,
.009,-.01,
.009347,-.00997,
.009684,-.009879,
.01,-.009732,
.010286,-.009532,
.010532,-.009286,
.010732,-.009,
.010879,-.008684,
.01097,-.008347,
.011,-.008,
.011,.008,
.01097,.008347,
.010879,.008684,
.010732,.009,
.010532,.009286,
.010286,.009532,
.01,.009732,
.009684,.009879,
.009347,.00997,
.009,.01,
0.0*
%
%ADD18MACRO18*%
%ADD139R,.026X.04*%
%ADD114R,.012X.028*%
%ADD113R,.028X.012*%
%ADD74R,.06X.025*%
%ADD124R,.025X.06*%
%AMMACRO121*
4,1,12,.0725,-.069,
.0725,-.015,
-.0725,-.015,
-.0725,-.025,
-.1475,-.025,
-.1475,.025,
-.0725,.025,
-.0725,.015,
.0725,.015,
.0725,.069,
.1475,.069,
.1475,-.069,
.0725,-.069,
0.0*
%
%ADD121MACRO121*%
%ADD84R,.012X.055*%
%ADD52R,.04X.073*%
%ADD10C,.14*%
%ADD120R,.05X.036*%
%ADD88R,.055X.014*%
%ADD73R,.026X.016*%
%ADD48R,.073X.04*%
%ADD123R,.037X.024*%
%ADD119R,.054X.025*%
%ADD85R,.038X.014*%
%AMMACRO55*
4,1,40,.0155,-.016,
.0155,.016,
.015439,.016695,
.015259,.017368,
.014964,.018,
.014564,.018571,
.014071,.019064,
.0135,.019464,
.012868,.019759,
.012195,.019939,
.0115,.02,
-.0115,.02,
-.012195,.019939,
-.012868,.019759,
-.0135,.019464,
-.014071,.019064,
-.014564,.018571,
-.014964,.018,
-.015259,.017368,
-.015439,.016695,
-.0155,.016,
-.0155,-.016,
-.015439,-.016695,
-.015259,-.017368,
-.014964,-.018,
-.014564,-.018571,
-.014071,-.019064,
-.0135,-.019464,
-.012868,-.019759,
-.012195,-.019939,
-.0115,-.02,
.0115,-.02,
.012195,-.019939,
.012868,-.019759,
.0135,-.019464,
.014071,-.019064,
.014564,-.018571,
.014964,-.018,
.015259,-.017368,
.015439,-.016695,
.0155,-.016,
0.0*
%
%ADD55MACRO55*%
%ADD24R,.014X.055*%
%AMMACRO19*
4,1,40,-.016,-.0155,
.016,-.0155,
.016695,-.015439,
.017368,-.015259,
.018,-.014964,
.018571,-.014564,
.019064,-.014071,
.019464,-.0135,
.019759,-.012868,
.019939,-.012195,
.02,-.0115,
.02,.0115,
.019939,.012195,
.019759,.012868,
.019464,.0135,
.019064,.014071,
.018571,.014564,
.018,.014964,
.017368,.015259,
.016695,.015439,
.016,.0155,
-.016,.0155,
-.016695,.015439,
-.017368,.015259,
-.018,.014964,
-.018571,.014564,
-.019064,.014071,
-.019464,.0135,
-.019759,.012868,
-.019939,.012195,
-.02,.0115,
-.02,-.0115,
-.019939,-.012195,
-.019759,-.012868,
-.019464,-.0135,
-.019064,-.014071,
-.018571,-.014564,
-.018,-.014964,
-.017368,-.015259,
-.016695,-.015439,
-.016,-.0155,
0.0*
%
%ADD19MACRO19*%
%ADD122R,.075X.05*%
%ADD76R,.073X.025*%
%ADD66R,.036X.026*%
%ADD56R,.014X.038*%
%ADD22R,.037X.061*%
%ADD133R,.026X.036*%
%ADD98R,.138X.181*%
%ADD62R,.016X.028*%
%ADD27C,.126*%
%ADD23R,.037X.053*%
%ADD13R,.061X.037*%
%ADD118R,.134X.169*%
%AMMACRO83*
4,1,40,.002,.016,
.003389,.015878,
.004736,.015518,
.006,.014928,
.007142,.014128,
.008128,.013142,
.008928,.012,
.009518,.010736,
.009878,.009389,
.01,.008,
.01,-.008,
.009878,-.009389,
.009518,-.010736,
.008928,-.012,
.008128,-.013142,
.007142,-.014128,
.006,-.014928,
.004736,-.015518,
.003389,-.015878,
.002,-.016,
-.002,-.016,
-.003389,-.015878,
-.004736,-.015518,
-.006,-.014928,
-.007142,-.014128,
-.008128,-.013142,
-.008928,-.012,
-.009518,-.010736,
-.009878,-.009389,
-.01,-.008,
-.01,.008,
-.009878,.009389,
-.009518,.010736,
-.008928,.012,
-.008128,.013142,
-.007142,.014128,
-.006,.014928,
-.004736,.015518,
-.003389,.015878,
-.002,.016,
.002,.016,
0.0*
%
%ADD83MACRO83*%
%ADD59R,.089X.011*%
%AMMACRO54*
4,1,40,-.016,.002,
-.015878,.003389,
-.015518,.004736,
-.014928,.006,
-.014128,.007142,
-.013142,.008128,
-.012,.008928,
-.010736,.009518,
-.009389,.009878,
-.008,.01,
.008,.01,
.009389,.009878,
.010736,.009518,
.012,.008928,
.013142,.008128,
.014128,.007142,
.014928,.006,
.015518,.004736,
.015878,.003389,
.016,.002,
.016,-.002,
.015878,-.003389,
.015518,-.004736,
.014928,-.006,
.014128,-.007142,
.013142,-.008128,
.012,-.008928,
.010736,-.009518,
.009389,-.009878,
.008,-.01,
-.008,-.01,
-.009389,-.009878,
-.010736,-.009518,
-.012,-.008928,
-.013142,-.008128,
-.014128,-.007142,
-.014928,-.006,
-.015518,-.004736,
-.015878,-.003389,
-.016,-.002,
-.016,.002,
0.0*
%
%ADD54MACRO54*%
%ADD138R,.074X.053*%
%ADD94O,.189X.126*%
%ADD77C,.119*%
%ADD86R,.069X.05*%
%ADD72R,.085X.026*%
%ADD61R,.092X.018*%
%ADD50R,.037X.055*%
%ADD135R,.026X.085*%
%ADD60R,.092X.037*%
%ADD117R,.043X.079*%
%AMMACRO71*
4,1,6,.0505,-.0895,
-.0505,-.0895,
-.0505,.0895,
.0055,.0895,
.0055,.0415,
.0505,.0415,
.0505,-.0895,
0.0*
%
%ADD71MACRO71*%
%AMMACRO69*
4,1,40,.005,.02,
.006389,.019878,
.007736,.019518,
.009,.018928,
.010142,.018128,
.011128,.017142,
.011928,.016,
.012518,.014736,
.012878,.013389,
.013,.012,
.013,-.012,
.012878,-.013389,
.012518,-.014736,
.011928,-.016,
.011128,-.017142,
.010142,-.018128,
.009,-.018928,
.007736,-.019518,
.006389,-.019878,
.005,-.02,
-.005,-.02,
-.006389,-.019878,
-.007736,-.019518,
-.009,-.018928,
-.010142,-.018128,
-.011128,-.017142,
-.011928,-.016,
-.012518,-.014736,
-.012878,-.013389,
-.013,-.012,
-.013,.012,
-.012878,.013389,
-.012518,.014736,
-.011928,.016,
-.011128,.017142,
-.010142,.018128,
-.009,.018928,
-.007736,.019518,
-.006389,.019878,
-.005,.02,
.005,.02,
0.0*
%
%ADD69MACRO69*%
%ADD136R,.075X.095*%
%ADD115R,.066X.086*%
%ADD97R,.185X.268*%
%ADD58R,.097X.072*%
%ADD51R,.095X.075*%
%ADD45R,.173X.173*%
%ADD131R,.138X.138*%
%AMMACRO79*
4,1,40,-.0145,.0055,
-.014378,.006889,
-.014018,.008236,
-.013428,.0095,
-.012628,.010642,
-.011642,.011628,
-.0105,.012428,
-.009236,.013018,
-.007889,.013378,
-.0065,.0135,
.0065,.0135,
.007889,.013378,
.009236,.013018,
.0105,.012428,
.011642,.011628,
.012628,.010642,
.013428,.0095,
.014018,.008236,
.014378,.006889,
.0145,.0055,
.0145,-.0055,
.014378,-.006889,
.014018,-.008236,
.013428,-.0095,
.012628,-.010642,
.011642,-.011628,
.0105,-.012428,
.009236,-.013018,
.007889,-.013378,
.0065,-.0135,
-.0065,-.0135,
-.007889,-.013378,
-.009236,-.013018,
-.0105,-.012428,
-.011642,-.011628,
-.012628,-.010642,
-.013428,-.0095,
-.014018,-.008236,
-.014378,-.006889,
-.0145,-.0055,
-.0145,.0055,
0.0*
%
%ADD79MACRO79*%
%AMMACRO78*
4,1,40,.0055,.0145,
.006889,.014378,
.008236,.014018,
.0095,.013428,
.010642,.012628,
.011628,.011642,
.012428,.0105,
.013018,.009236,
.013378,.007889,
.0135,.0065,
.0135,-.0065,
.013378,-.007889,
.013018,-.009236,
.012428,-.0105,
.011628,-.011642,
.010642,-.012628,
.0095,-.013428,
.008236,-.014018,
.006889,-.014378,
.0055,-.0145,
-.0055,-.0145,
-.006889,-.014378,
-.008236,-.014018,
-.0095,-.013428,
-.010642,-.012628,
-.011628,-.011642,
-.012428,-.0105,
-.013018,-.009236,
-.013378,-.007889,
-.0135,-.0065,
-.0135,.0065,
-.013378,.007889,
-.013018,.009236,
-.012428,.0105,
-.011628,.011642,
-.010642,.012628,
-.0095,.013428,
-.008236,.014018,
-.006889,.014378,
-.0055,.0145,
.0055,.0145,
0.0*
%
%ADD78MACRO78*%
%AMMACRO26*
4,1,40,-.009,-.008,
-.009,.008,
-.00897,.008347,
-.008879,.008684,
-.008732,.009,
-.008532,.009286,
-.008286,.009532,
-.008,.009732,
-.007684,.009879,
-.007347,.00997,
-.007,.01,
.007,.01,
.007347,.00997,
.007684,.009879,
.008,.009732,
.008286,.009532,
.008532,.009286,
.008732,.009,
.008879,.008684,
.00897,.008347,
.009,.008,
.009,-.008,
.00897,-.008347,
.008879,-.008684,
.008732,-.009,
.008532,-.009286,
.008286,-.009532,
.008,-.009732,
.007684,-.009879,
.007347,-.00997,
.007,-.01,
-.007,-.01,
-.007347,-.00997,
-.007684,-.009879,
-.008,-.009732,
-.008286,-.009532,
-.008532,-.009286,
-.008732,-.009,
-.008879,-.008684,
-.00897,-.008347,
-.009,-.008,
0.0*
%
%ADD26MACRO26*%
%AMMACRO41*
4,1,40,-.008,.009,
.008,.009,
.008347,.00897,
.008684,.008879,
.009,.008732,
.009286,.008532,
.009532,.008286,
.009732,.008,
.009879,.007684,
.00997,.007347,
.01,.007,
.01,-.007,
.00997,-.007347,
.009879,-.007684,
.009732,-.008,
.009532,-.008286,
.009286,-.008532,
.009,-.008732,
.008684,-.008879,
.008347,-.00897,
.008,-.009,
-.008,-.009,
-.008347,-.00897,
-.008684,-.008879,
-.009,-.008732,
-.009286,-.008532,
-.009532,-.008286,
-.009732,-.008,
-.009879,-.007684,
-.00997,-.007347,
-.01,-.007,
-.01,.007,
-.00997,.007347,
-.009879,.007684,
-.009732,.008,
-.009532,.008286,
-.009286,.008532,
-.009,.008732,
-.008684,.008879,
-.008347,.00897,
-.008,.009,
0.0*
%
%ADD41MACRO41*%
%AMMACRO30*
4,1,6,-.0135,.025,
.0065,.005,
.0135,.005,
.0135,-.005,
.0065,-.005,
-.0135,-.025,
-.0135,.025,
0.0*
%
%ADD30MACRO30*%
%AMMACRO38*
4,1,6,.0135,-.005,
.0065,-.005,
-.0135,-.025,
-.0135,.025,
.0065,.005,
.0135,.005,
.0135,-.005,
0.0*
%
%ADD38MACRO38*%
%AMMACRO31*
4,1,20,-.0635,.1075,
-.049,.1075,
-.049,.118,
-.0395,.118,
-.0395,.1075,
.0395,.1075,
.0395,.118,
.049,.118,
.049,.1075,
.0635,.1075,
.0635,-.1075,
.049,-.1075,
.049,-.118,
.0395,-.118,
.0395,-.1075,
-.0395,-.1075,
-.0395,-.118,
-.049,-.118,
-.049,-.1075,
-.0635,-.1075,
-.0635,.1075,
0.0*
%
%ADD31MACRO31*%
%AMMACRO33*
4,1,40,-.009,-.008,
-.009,.008,
-.00897,.008347,
-.008879,.008684,
-.008732,.009,
-.008532,.009286,
-.008286,.009532,
-.008,.009732,
-.007684,.009879,
-.007347,.00997,
-.007,.01,
.007,.01,
.007347,.00997,
.007684,.009879,
.008,.009732,
.008286,.009532,
.008532,.009286,
.008732,.009,
.008879,.008684,
.00897,.008347,
.009,.008,
.009,-.008,
.00897,-.008347,
.008879,-.008684,
.008732,-.009,
.008532,-.009286,
.008286,-.009532,
.008,-.009732,
.007684,-.009879,
.007347,-.00997,
.007,-.01,
-.007,-.01,
-.007347,-.00997,
-.007684,-.009879,
-.008,-.009732,
-.008286,-.009532,
-.008532,-.009286,
-.008732,-.009,
-.008879,-.008684,
-.00897,-.008347,
-.009,-.008,
0.0*
%
%ADD33MACRO33*%
%AMMACRO42*
4,1,40,-.008,.009,
.008,.009,
.008347,.00897,
.008684,.008879,
.009,.008732,
.009286,.008532,
.009532,.008286,
.009732,.008,
.009879,.007684,
.00997,.007347,
.01,.007,
.01,-.007,
.00997,-.007347,
.009879,-.007684,
.009732,-.008,
.009532,-.008286,
.009286,-.008532,
.009,-.008732,
.008684,-.008879,
.008347,-.00897,
.008,-.009,
-.008,-.009,
-.008347,-.00897,
-.008684,-.008879,
-.009,-.008732,
-.009286,-.008532,
-.009532,-.008286,
-.009732,-.008,
-.009879,-.007684,
-.00997,-.007347,
-.01,-.007,
-.01,.007,
-.00997,.007347,
-.009879,.007684,
-.009732,.008,
-.009532,.008286,
-.009286,.008532,
-.009,.008732,
-.008684,.008879,
-.008347,.00897,
-.008,.009,
0.0*
%
%ADD42MACRO42*%
%ADD142C,.006*%
%ADD143C,.15098*%
G75*
%LPD*%
G75*
G36*
G01X56730Y77185D02*
G03I-11061J0D01*
G37*
G36*
G01Y172460D02*
G03I-11061J0D01*
G37*
G36*
G01X57574Y10330D02*
X390064D01*
Y32642D01*
X57574D01*
Y10330D01*
G37*
G36*
G01X550200Y124200D02*
X560700D01*
Y134700D01*
X550200D01*
Y124200D01*
G37*
G36*
G01Y137300D02*
X560700D01*
Y147800D01*
X550200D01*
Y137300D01*
G37*
G36*
G01X563300Y124200D02*
X573800D01*
Y134700D01*
X563300D01*
Y124200D01*
G37*
G36*
G01Y137300D02*
X573800D01*
Y147800D01*
X563300D01*
Y137300D01*
G37*
%LPC*%
G75*
G54D143*
X45669Y77185D03*
Y172460D03*
%LPD*%
G75*
G36*
G01X510039Y3080D02*
X509914Y3090D01*
X509789Y3130D01*
X509679Y3190D01*
X509579Y3270D01*
X509499Y3370D01*
X509439Y3480D01*
X509399Y3605D01*
X509389Y3730D01*
Y7160D01*
X509359Y7190D01*
X509259Y7330D01*
X509239Y7370D01*
X509224Y7405D01*
X509204Y7445D01*
X509189Y7485D01*
X509179Y7525D01*
X509164Y7570D01*
X509159Y7610D01*
X509149Y7650D01*
X509144Y7695D01*
Y7735D01*
X509139Y7780D01*
X509144Y7825D01*
Y7865D01*
X509149Y7910D01*
X509159Y7950D01*
X509164Y7990D01*
X509179Y8035D01*
X509189Y8075D01*
X509204Y8115D01*
X509224Y8155D01*
X509239Y8190D01*
X509259Y8230D01*
X509359Y8370D01*
X509389Y8400D01*
Y9530D01*
X509399Y9655D01*
X509439Y9780D01*
X509499Y9890D01*
X509579Y9990D01*
X509679Y10070D01*
X509789Y10130D01*
X509914Y10170D01*
X510039Y10180D01*
X510164Y10170D01*
X510289Y10130D01*
X510399Y10070D01*
X510499Y9990D01*
X510579Y9890D01*
X510639Y9780D01*
X510679Y9655D01*
X510689Y9530D01*
Y8400D01*
X510719Y8370D01*
X510819Y8230D01*
X510839Y8190D01*
X510854Y8155D01*
X510874Y8115D01*
X510889Y8075D01*
X510899Y8035D01*
X510914Y7990D01*
X510919Y7950D01*
X510929Y7910D01*
X510934Y7865D01*
Y7825D01*
X510939Y7780D01*
X510934Y7735D01*
Y7695D01*
X510929Y7650D01*
X510919Y7610D01*
X510914Y7570D01*
X510899Y7525D01*
X510889Y7485D01*
X510874Y7445D01*
X510854Y7405D01*
X510839Y7370D01*
X510819Y7330D01*
X510719Y7190D01*
X510689Y7160D01*
Y3730D01*
X510679Y3605D01*
X510639Y3480D01*
X510579Y3370D01*
X510499Y3270D01*
X510399Y3190D01*
X510289Y3130D01*
X510164Y3090D01*
X510039Y3080D01*
G37*
G36*
G01X505315D02*
X505190Y3090D01*
X505065Y3130D01*
X504955Y3190D01*
X504855Y3270D01*
X504775Y3370D01*
X504715Y3480D01*
X504675Y3605D01*
X504665Y3730D01*
Y7160D01*
X504635Y7190D01*
X504535Y7330D01*
X504515Y7370D01*
X504500Y7405D01*
X504480Y7445D01*
X504465Y7485D01*
X504455Y7525D01*
X504440Y7570D01*
X504435Y7610D01*
X504425Y7650D01*
X504420Y7695D01*
Y7735D01*
X504415Y7780D01*
X504420Y7825D01*
Y7865D01*
X504425Y7910D01*
X504435Y7950D01*
X504440Y7990D01*
X504455Y8035D01*
X504465Y8075D01*
X504480Y8115D01*
X504500Y8155D01*
X504515Y8190D01*
X504535Y8230D01*
X504635Y8370D01*
X504665Y8400D01*
Y9530D01*
X504675Y9655D01*
X504715Y9780D01*
X504775Y9890D01*
X504855Y9990D01*
X504955Y10070D01*
X505065Y10130D01*
X505190Y10170D01*
X505315Y10180D01*
X505440Y10170D01*
X505565Y10130D01*
X505675Y10070D01*
X505775Y9990D01*
X505855Y9890D01*
X505915Y9780D01*
X505955Y9655D01*
X505965Y9530D01*
Y8400D01*
X505995Y8370D01*
X506095Y8230D01*
X506115Y8190D01*
X506130Y8155D01*
X506150Y8115D01*
X506165Y8075D01*
X506175Y8035D01*
X506190Y7990D01*
X506195Y7950D01*
X506205Y7910D01*
X506210Y7865D01*
Y7825D01*
X506215Y7780D01*
X506210Y7735D01*
Y7695D01*
X506205Y7650D01*
X506195Y7610D01*
X506190Y7570D01*
X506175Y7525D01*
X506165Y7485D01*
X506150Y7445D01*
X506130Y7405D01*
X506115Y7370D01*
X506095Y7330D01*
X505995Y7190D01*
X505965Y7160D01*
Y3730D01*
X505955Y3605D01*
X505915Y3480D01*
X505855Y3370D01*
X505775Y3270D01*
X505675Y3190D01*
X505565Y3130D01*
X505440Y3090D01*
X505315Y3080D01*
G37*
G36*
G01X524212D02*
X524087Y3090D01*
X523962Y3130D01*
X523852Y3190D01*
X523752Y3270D01*
X523672Y3370D01*
X523612Y3480D01*
X523572Y3605D01*
X523562Y3730D01*
Y7160D01*
X523532Y7190D01*
X523432Y7330D01*
X523412Y7370D01*
X523397Y7405D01*
X523377Y7445D01*
X523362Y7485D01*
X523352Y7525D01*
X523337Y7570D01*
X523332Y7610D01*
X523322Y7650D01*
X523317Y7695D01*
Y7735D01*
X523312Y7780D01*
X523317Y7825D01*
Y7865D01*
X523322Y7910D01*
X523332Y7950D01*
X523337Y7990D01*
X523352Y8035D01*
X523362Y8075D01*
X523377Y8115D01*
X523397Y8155D01*
X523412Y8190D01*
X523432Y8230D01*
X523532Y8370D01*
X523562Y8400D01*
Y9530D01*
X523572Y9655D01*
X523612Y9780D01*
X523672Y9890D01*
X523752Y9990D01*
X523852Y10070D01*
X523962Y10130D01*
X524087Y10170D01*
X524212Y10180D01*
X524337Y10170D01*
X524462Y10130D01*
X524572Y10070D01*
X524672Y9990D01*
X524752Y9890D01*
X524812Y9780D01*
X524852Y9655D01*
X524862Y9530D01*
Y8400D01*
X524892Y8370D01*
X524992Y8230D01*
X525012Y8190D01*
X525027Y8155D01*
X525047Y8115D01*
X525062Y8075D01*
X525072Y8035D01*
X525087Y7990D01*
X525092Y7950D01*
X525102Y7910D01*
X525107Y7865D01*
Y7825D01*
X525112Y7780D01*
X525107Y7735D01*
Y7695D01*
X525102Y7650D01*
X525092Y7610D01*
X525087Y7570D01*
X525072Y7525D01*
X525062Y7485D01*
X525047Y7445D01*
X525027Y7405D01*
X525012Y7370D01*
X524992Y7330D01*
X524892Y7190D01*
X524862Y7160D01*
Y3730D01*
X524852Y3605D01*
X524812Y3480D01*
X524752Y3370D01*
X524672Y3270D01*
X524572Y3190D01*
X524462Y3130D01*
X524337Y3090D01*
X524212Y3080D01*
G37*
G36*
G01X519488D02*
X519363Y3090D01*
X519238Y3130D01*
X519128Y3190D01*
X519028Y3270D01*
X518948Y3370D01*
X518888Y3480D01*
X518848Y3605D01*
X518838Y3730D01*
Y7160D01*
X518808Y7190D01*
X518708Y7330D01*
X518688Y7370D01*
X518673Y7405D01*
X518653Y7445D01*
X518638Y7485D01*
X518628Y7525D01*
X518613Y7570D01*
X518608Y7610D01*
X518598Y7650D01*
X518593Y7695D01*
Y7735D01*
X518588Y7780D01*
X518593Y7825D01*
Y7865D01*
X518598Y7910D01*
X518608Y7950D01*
X518613Y7990D01*
X518628Y8035D01*
X518638Y8075D01*
X518653Y8115D01*
X518673Y8155D01*
X518688Y8190D01*
X518708Y8230D01*
X518808Y8370D01*
X518838Y8400D01*
Y9530D01*
X518848Y9655D01*
X518888Y9780D01*
X518948Y9890D01*
X519028Y9990D01*
X519128Y10070D01*
X519238Y10130D01*
X519363Y10170D01*
X519488Y10180D01*
X519613Y10170D01*
X519738Y10130D01*
X519848Y10070D01*
X519948Y9990D01*
X520028Y9890D01*
X520088Y9780D01*
X520128Y9655D01*
X520138Y9530D01*
Y8400D01*
X520168Y8370D01*
X520268Y8230D01*
X520288Y8190D01*
X520303Y8155D01*
X520323Y8115D01*
X520338Y8075D01*
X520348Y8035D01*
X520363Y7990D01*
X520368Y7950D01*
X520378Y7910D01*
X520383Y7865D01*
Y7825D01*
X520388Y7780D01*
X520383Y7735D01*
Y7695D01*
X520378Y7650D01*
X520368Y7610D01*
X520363Y7570D01*
X520348Y7525D01*
X520338Y7485D01*
X520323Y7445D01*
X520303Y7405D01*
X520288Y7370D01*
X520268Y7330D01*
X520168Y7190D01*
X520138Y7160D01*
Y3730D01*
X520128Y3605D01*
X520088Y3480D01*
X520028Y3370D01*
X519948Y3270D01*
X519848Y3190D01*
X519738Y3130D01*
X519613Y3090D01*
X519488Y3080D01*
G37*
G36*
G01X514764D02*
X514639Y3090D01*
X514514Y3130D01*
X514404Y3190D01*
X514304Y3270D01*
X514224Y3370D01*
X514164Y3480D01*
X514124Y3605D01*
X514114Y3730D01*
Y7160D01*
X514084Y7190D01*
X513984Y7330D01*
X513964Y7370D01*
X513949Y7405D01*
X513929Y7445D01*
X513914Y7485D01*
X513904Y7525D01*
X513889Y7570D01*
X513884Y7610D01*
X513874Y7650D01*
X513869Y7695D01*
Y7735D01*
X513864Y7780D01*
X513869Y7825D01*
Y7865D01*
X513874Y7910D01*
X513884Y7950D01*
X513889Y7990D01*
X513904Y8035D01*
X513914Y8075D01*
X513929Y8115D01*
X513949Y8155D01*
X513964Y8190D01*
X513984Y8230D01*
X514084Y8370D01*
X514114Y8400D01*
Y9530D01*
X514124Y9655D01*
X514164Y9780D01*
X514224Y9890D01*
X514304Y9990D01*
X514404Y10070D01*
X514514Y10130D01*
X514639Y10170D01*
X514764Y10180D01*
X514889Y10170D01*
X515014Y10130D01*
X515124Y10070D01*
X515224Y9990D01*
X515304Y9890D01*
X515364Y9780D01*
X515404Y9655D01*
X515414Y9530D01*
Y8400D01*
X515444Y8370D01*
X515544Y8230D01*
X515564Y8190D01*
X515579Y8155D01*
X515599Y8115D01*
X515614Y8075D01*
X515624Y8035D01*
X515639Y7990D01*
X515644Y7950D01*
X515654Y7910D01*
X515659Y7865D01*
Y7825D01*
X515664Y7780D01*
X515659Y7735D01*
Y7695D01*
X515654Y7650D01*
X515644Y7610D01*
X515639Y7570D01*
X515624Y7525D01*
X515614Y7485D01*
X515599Y7445D01*
X515579Y7405D01*
X515564Y7370D01*
X515544Y7330D01*
X515444Y7190D01*
X515414Y7160D01*
Y3730D01*
X515404Y3605D01*
X515364Y3480D01*
X515304Y3370D01*
X515224Y3270D01*
X515124Y3190D01*
X515014Y3130D01*
X514889Y3090D01*
X514764Y3080D01*
G37*
G36*
G01X538386D02*
X538261Y3090D01*
X538136Y3130D01*
X538026Y3190D01*
X537926Y3270D01*
X537846Y3370D01*
X537786Y3480D01*
X537746Y3605D01*
X537736Y3730D01*
Y7160D01*
X537706Y7190D01*
X537606Y7330D01*
X537586Y7370D01*
X537571Y7405D01*
X537551Y7445D01*
X537536Y7485D01*
X537526Y7525D01*
X537511Y7570D01*
X537506Y7610D01*
X537496Y7650D01*
X537491Y7695D01*
Y7735D01*
X537486Y7780D01*
X537491Y7825D01*
Y7865D01*
X537496Y7910D01*
X537506Y7950D01*
X537511Y7990D01*
X537526Y8035D01*
X537536Y8075D01*
X537551Y8115D01*
X537571Y8155D01*
X537586Y8190D01*
X537606Y8230D01*
X537706Y8370D01*
X537736Y8400D01*
Y9530D01*
X537746Y9655D01*
X537786Y9780D01*
X537846Y9890D01*
X537926Y9990D01*
X538026Y10070D01*
X538136Y10130D01*
X538261Y10170D01*
X538386Y10180D01*
X538511Y10170D01*
X538636Y10130D01*
X538746Y10070D01*
X538846Y9990D01*
X538926Y9890D01*
X538986Y9780D01*
X539026Y9655D01*
X539036Y9530D01*
Y8400D01*
X539066Y8370D01*
X539166Y8230D01*
X539186Y8190D01*
X539201Y8155D01*
X539221Y8115D01*
X539236Y8075D01*
X539246Y8035D01*
X539261Y7990D01*
X539266Y7950D01*
X539276Y7910D01*
X539281Y7865D01*
Y7825D01*
X539286Y7780D01*
X539281Y7735D01*
Y7695D01*
X539276Y7650D01*
X539266Y7610D01*
X539261Y7570D01*
X539246Y7525D01*
X539236Y7485D01*
X539221Y7445D01*
X539201Y7405D01*
X539186Y7370D01*
X539166Y7330D01*
X539066Y7190D01*
X539036Y7160D01*
Y3730D01*
X539026Y3605D01*
X538986Y3480D01*
X538926Y3370D01*
X538846Y3270D01*
X538746Y3190D01*
X538636Y3130D01*
X538511Y3090D01*
X538386Y3080D01*
G37*
G36*
G01X533661D02*
X533536Y3090D01*
X533411Y3130D01*
X533301Y3190D01*
X533201Y3270D01*
X533121Y3370D01*
X533061Y3480D01*
X533021Y3605D01*
X533011Y3730D01*
Y7160D01*
X532981Y7190D01*
X532881Y7330D01*
X532861Y7370D01*
X532846Y7405D01*
X532826Y7445D01*
X532811Y7485D01*
X532801Y7525D01*
X532786Y7570D01*
X532781Y7610D01*
X532771Y7650D01*
X532766Y7695D01*
Y7735D01*
X532761Y7780D01*
X532766Y7825D01*
Y7865D01*
X532771Y7910D01*
X532781Y7950D01*
X532786Y7990D01*
X532801Y8035D01*
X532811Y8075D01*
X532826Y8115D01*
X532846Y8155D01*
X532861Y8190D01*
X532881Y8230D01*
X532981Y8370D01*
X533011Y8400D01*
Y9530D01*
X533021Y9655D01*
X533061Y9780D01*
X533121Y9890D01*
X533201Y9990D01*
X533301Y10070D01*
X533411Y10130D01*
X533536Y10170D01*
X533661Y10180D01*
X533786Y10170D01*
X533911Y10130D01*
X534021Y10070D01*
X534121Y9990D01*
X534201Y9890D01*
X534261Y9780D01*
X534301Y9655D01*
X534311Y9530D01*
Y8400D01*
X534341Y8370D01*
X534441Y8230D01*
X534461Y8190D01*
X534476Y8155D01*
X534496Y8115D01*
X534511Y8075D01*
X534521Y8035D01*
X534536Y7990D01*
X534541Y7950D01*
X534551Y7910D01*
X534556Y7865D01*
Y7825D01*
X534561Y7780D01*
X534556Y7735D01*
Y7695D01*
X534551Y7650D01*
X534541Y7610D01*
X534536Y7570D01*
X534521Y7525D01*
X534511Y7485D01*
X534496Y7445D01*
X534476Y7405D01*
X534461Y7370D01*
X534441Y7330D01*
X534341Y7190D01*
X534311Y7160D01*
Y3730D01*
X534301Y3605D01*
X534261Y3480D01*
X534201Y3370D01*
X534121Y3270D01*
X534021Y3190D01*
X533911Y3130D01*
X533786Y3090D01*
X533661Y3080D01*
G37*
G36*
G01X528937D02*
X528812Y3090D01*
X528687Y3130D01*
X528577Y3190D01*
X528477Y3270D01*
X528397Y3370D01*
X528337Y3480D01*
X528297Y3605D01*
X528287Y3730D01*
Y7160D01*
X528257Y7190D01*
X528157Y7330D01*
X528137Y7370D01*
X528122Y7405D01*
X528102Y7445D01*
X528087Y7485D01*
X528077Y7525D01*
X528062Y7570D01*
X528057Y7610D01*
X528047Y7650D01*
X528042Y7695D01*
Y7735D01*
X528037Y7780D01*
X528042Y7825D01*
Y7865D01*
X528047Y7910D01*
X528057Y7950D01*
X528062Y7990D01*
X528077Y8035D01*
X528087Y8075D01*
X528102Y8115D01*
X528122Y8155D01*
X528137Y8190D01*
X528157Y8230D01*
X528257Y8370D01*
X528287Y8400D01*
Y9530D01*
X528297Y9655D01*
X528337Y9780D01*
X528397Y9890D01*
X528477Y9990D01*
X528577Y10070D01*
X528687Y10130D01*
X528812Y10170D01*
X528937Y10180D01*
X529062Y10170D01*
X529187Y10130D01*
X529297Y10070D01*
X529397Y9990D01*
X529477Y9890D01*
X529537Y9780D01*
X529577Y9655D01*
X529587Y9530D01*
Y8400D01*
X529617Y8370D01*
X529717Y8230D01*
X529737Y8190D01*
X529752Y8155D01*
X529772Y8115D01*
X529787Y8075D01*
X529797Y8035D01*
X529812Y7990D01*
X529817Y7950D01*
X529827Y7910D01*
X529832Y7865D01*
Y7825D01*
X529837Y7780D01*
X529832Y7735D01*
Y7695D01*
X529827Y7650D01*
X529817Y7610D01*
X529812Y7570D01*
X529797Y7525D01*
X529787Y7485D01*
X529772Y7445D01*
X529752Y7405D01*
X529737Y7370D01*
X529717Y7330D01*
X529617Y7190D01*
X529587Y7160D01*
Y3730D01*
X529577Y3605D01*
X529537Y3480D01*
X529477Y3370D01*
X529397Y3270D01*
X529297Y3190D01*
X529187Y3130D01*
X529062Y3090D01*
X528937Y3080D01*
G37*
G36*
G01X557283D02*
X557158Y3090D01*
X557033Y3130D01*
X556923Y3190D01*
X556823Y3270D01*
X556743Y3370D01*
X556683Y3480D01*
X556643Y3605D01*
X556633Y3730D01*
Y7160D01*
X556603Y7190D01*
X556503Y7330D01*
X556483Y7370D01*
X556468Y7405D01*
X556448Y7445D01*
X556433Y7485D01*
X556423Y7525D01*
X556408Y7570D01*
X556403Y7610D01*
X556393Y7650D01*
X556388Y7695D01*
Y7735D01*
X556383Y7780D01*
X556388Y7825D01*
Y7865D01*
X556393Y7910D01*
X556403Y7950D01*
X556408Y7990D01*
X556423Y8035D01*
X556433Y8075D01*
X556448Y8115D01*
X556468Y8155D01*
X556483Y8190D01*
X556503Y8230D01*
X556603Y8370D01*
X556633Y8400D01*
Y9530D01*
X556643Y9655D01*
X556683Y9780D01*
X556743Y9890D01*
X556823Y9990D01*
X556923Y10070D01*
X557033Y10130D01*
X557158Y10170D01*
X557283Y10180D01*
X557408Y10170D01*
X557533Y10130D01*
X557643Y10070D01*
X557743Y9990D01*
X557823Y9890D01*
X557883Y9780D01*
X557923Y9655D01*
X557933Y9530D01*
Y8400D01*
X557963Y8370D01*
X558063Y8230D01*
X558083Y8190D01*
X558098Y8155D01*
X558118Y8115D01*
X558133Y8075D01*
X558143Y8035D01*
X558158Y7990D01*
X558163Y7950D01*
X558173Y7910D01*
X558178Y7865D01*
Y7825D01*
X558183Y7780D01*
X558178Y7735D01*
Y7695D01*
X558173Y7650D01*
X558163Y7610D01*
X558158Y7570D01*
X558143Y7525D01*
X558133Y7485D01*
X558118Y7445D01*
X558098Y7405D01*
X558083Y7370D01*
X558063Y7330D01*
X557963Y7190D01*
X557933Y7160D01*
Y3730D01*
X557923Y3605D01*
X557883Y3480D01*
X557823Y3370D01*
X557743Y3270D01*
X557643Y3190D01*
X557533Y3130D01*
X557408Y3090D01*
X557283Y3080D01*
G37*
G36*
G01X552559D02*
X552434Y3090D01*
X552309Y3130D01*
X552199Y3190D01*
X552099Y3270D01*
X552019Y3370D01*
X551959Y3480D01*
X551919Y3605D01*
X551909Y3730D01*
Y7160D01*
X551879Y7190D01*
X551779Y7330D01*
X551759Y7370D01*
X551744Y7405D01*
X551724Y7445D01*
X551709Y7485D01*
X551699Y7525D01*
X551684Y7570D01*
X551679Y7610D01*
X551669Y7650D01*
X551664Y7695D01*
Y7735D01*
X551659Y7780D01*
X551664Y7825D01*
Y7865D01*
X551669Y7910D01*
X551679Y7950D01*
X551684Y7990D01*
X551699Y8035D01*
X551709Y8075D01*
X551724Y8115D01*
X551744Y8155D01*
X551759Y8190D01*
X551779Y8230D01*
X551879Y8370D01*
X551909Y8400D01*
Y9530D01*
X551919Y9655D01*
X551959Y9780D01*
X552019Y9890D01*
X552099Y9990D01*
X552199Y10070D01*
X552309Y10130D01*
X552434Y10170D01*
X552559Y10180D01*
X552684Y10170D01*
X552809Y10130D01*
X552919Y10070D01*
X553019Y9990D01*
X553099Y9890D01*
X553159Y9780D01*
X553199Y9655D01*
X553209Y9530D01*
Y8400D01*
X553239Y8370D01*
X553339Y8230D01*
X553359Y8190D01*
X553374Y8155D01*
X553394Y8115D01*
X553409Y8075D01*
X553419Y8035D01*
X553434Y7990D01*
X553439Y7950D01*
X553449Y7910D01*
X553454Y7865D01*
Y7825D01*
X553459Y7780D01*
X553454Y7735D01*
Y7695D01*
X553449Y7650D01*
X553439Y7610D01*
X553434Y7570D01*
X553419Y7525D01*
X553409Y7485D01*
X553394Y7445D01*
X553374Y7405D01*
X553359Y7370D01*
X553339Y7330D01*
X553239Y7190D01*
X553209Y7160D01*
Y3730D01*
X553199Y3605D01*
X553159Y3480D01*
X553099Y3370D01*
X553019Y3270D01*
X552919Y3190D01*
X552809Y3130D01*
X552684Y3090D01*
X552559Y3080D01*
G37*
G36*
G01X547834D02*
X547709Y3090D01*
X547584Y3130D01*
X547474Y3190D01*
X547374Y3270D01*
X547294Y3370D01*
X547234Y3480D01*
X547194Y3605D01*
X547184Y3730D01*
Y7160D01*
X547154Y7190D01*
X547054Y7330D01*
X547034Y7370D01*
X547019Y7405D01*
X546999Y7445D01*
X546984Y7485D01*
X546974Y7525D01*
X546959Y7570D01*
X546954Y7610D01*
X546944Y7650D01*
X546939Y7695D01*
Y7735D01*
X546934Y7780D01*
X546939Y7825D01*
Y7865D01*
X546944Y7910D01*
X546954Y7950D01*
X546959Y7990D01*
X546974Y8035D01*
X546984Y8075D01*
X546999Y8115D01*
X547019Y8155D01*
X547034Y8190D01*
X547054Y8230D01*
X547154Y8370D01*
X547184Y8400D01*
Y9530D01*
X547194Y9655D01*
X547234Y9780D01*
X547294Y9890D01*
X547374Y9990D01*
X547474Y10070D01*
X547584Y10130D01*
X547709Y10170D01*
X547834Y10180D01*
X547959Y10170D01*
X548084Y10130D01*
X548194Y10070D01*
X548294Y9990D01*
X548374Y9890D01*
X548434Y9780D01*
X548474Y9655D01*
X548484Y9530D01*
Y8400D01*
X548514Y8370D01*
X548614Y8230D01*
X548634Y8190D01*
X548649Y8155D01*
X548669Y8115D01*
X548684Y8075D01*
X548694Y8035D01*
X548709Y7990D01*
X548714Y7950D01*
X548724Y7910D01*
X548729Y7865D01*
Y7825D01*
X548734Y7780D01*
X548729Y7735D01*
Y7695D01*
X548724Y7650D01*
X548714Y7610D01*
X548709Y7570D01*
X548694Y7525D01*
X548684Y7485D01*
X548669Y7445D01*
X548649Y7405D01*
X548634Y7370D01*
X548614Y7330D01*
X548514Y7190D01*
X548484Y7160D01*
Y3730D01*
X548474Y3605D01*
X548434Y3480D01*
X548374Y3370D01*
X548294Y3270D01*
X548194Y3190D01*
X548084Y3130D01*
X547959Y3090D01*
X547834Y3080D01*
G37*
G36*
G01X543110D02*
X542985Y3090D01*
X542860Y3130D01*
X542750Y3190D01*
X542650Y3270D01*
X542570Y3370D01*
X542510Y3480D01*
X542470Y3605D01*
X542460Y3730D01*
Y7160D01*
X542430Y7190D01*
X542330Y7330D01*
X542310Y7370D01*
X542295Y7405D01*
X542275Y7445D01*
X542260Y7485D01*
X542250Y7525D01*
X542235Y7570D01*
X542230Y7610D01*
X542220Y7650D01*
X542215Y7695D01*
Y7735D01*
X542210Y7780D01*
X542215Y7825D01*
Y7865D01*
X542220Y7910D01*
X542230Y7950D01*
X542235Y7990D01*
X542250Y8035D01*
X542260Y8075D01*
X542275Y8115D01*
X542295Y8155D01*
X542310Y8190D01*
X542330Y8230D01*
X542430Y8370D01*
X542460Y8400D01*
Y9530D01*
X542470Y9655D01*
X542510Y9780D01*
X542570Y9890D01*
X542650Y9990D01*
X542750Y10070D01*
X542860Y10130D01*
X542985Y10170D01*
X543110Y10180D01*
X543235Y10170D01*
X543360Y10130D01*
X543470Y10070D01*
X543570Y9990D01*
X543650Y9890D01*
X543710Y9780D01*
X543750Y9655D01*
X543760Y9530D01*
Y8400D01*
X543790Y8370D01*
X543890Y8230D01*
X543910Y8190D01*
X543925Y8155D01*
X543945Y8115D01*
X543960Y8075D01*
X543970Y8035D01*
X543985Y7990D01*
X543990Y7950D01*
X544000Y7910D01*
X544005Y7865D01*
Y7825D01*
X544010Y7780D01*
X544005Y7735D01*
Y7695D01*
X544000Y7650D01*
X543990Y7610D01*
X543985Y7570D01*
X543970Y7525D01*
X543960Y7485D01*
X543945Y7445D01*
X543925Y7405D01*
X543910Y7370D01*
X543890Y7330D01*
X543790Y7190D01*
X543760Y7160D01*
Y3730D01*
X543750Y3605D01*
X543710Y3480D01*
X543650Y3370D01*
X543570Y3270D01*
X543470Y3190D01*
X543360Y3130D01*
X543235Y3090D01*
X543110Y3080D01*
G37*
G36*
G01X571456D02*
X571331Y3090D01*
X571206Y3130D01*
X571096Y3190D01*
X570996Y3270D01*
X570916Y3370D01*
X570856Y3480D01*
X570816Y3605D01*
X570806Y3730D01*
Y7160D01*
X570776Y7190D01*
X570676Y7330D01*
X570656Y7370D01*
X570641Y7405D01*
X570621Y7445D01*
X570606Y7485D01*
X570596Y7525D01*
X570581Y7570D01*
X570576Y7610D01*
X570566Y7650D01*
X570561Y7695D01*
Y7735D01*
X570556Y7780D01*
X570561Y7825D01*
Y7865D01*
X570566Y7910D01*
X570576Y7950D01*
X570581Y7990D01*
X570596Y8035D01*
X570606Y8075D01*
X570621Y8115D01*
X570641Y8155D01*
X570656Y8190D01*
X570676Y8230D01*
X570776Y8370D01*
X570806Y8400D01*
Y9530D01*
X570816Y9655D01*
X570856Y9780D01*
X570916Y9890D01*
X570996Y9990D01*
X571096Y10070D01*
X571206Y10130D01*
X571331Y10170D01*
X571456Y10180D01*
X571581Y10170D01*
X571706Y10130D01*
X571816Y10070D01*
X571916Y9990D01*
X571996Y9890D01*
X572056Y9780D01*
X572096Y9655D01*
X572106Y9530D01*
Y8400D01*
X572136Y8370D01*
X572236Y8230D01*
X572256Y8190D01*
X572271Y8155D01*
X572291Y8115D01*
X572306Y8075D01*
X572316Y8035D01*
X572331Y7990D01*
X572336Y7950D01*
X572346Y7910D01*
X572351Y7865D01*
Y7825D01*
X572356Y7780D01*
X572351Y7735D01*
Y7695D01*
X572346Y7650D01*
X572336Y7610D01*
X572331Y7570D01*
X572316Y7525D01*
X572306Y7485D01*
X572291Y7445D01*
X572271Y7405D01*
X572256Y7370D01*
X572236Y7330D01*
X572136Y7190D01*
X572106Y7160D01*
Y3730D01*
X572096Y3605D01*
X572056Y3480D01*
X571996Y3370D01*
X571916Y3270D01*
X571816Y3190D01*
X571706Y3130D01*
X571581Y3090D01*
X571456Y3080D01*
G37*
G36*
G01X566732D02*
X566607Y3090D01*
X566482Y3130D01*
X566372Y3190D01*
X566272Y3270D01*
X566192Y3370D01*
X566132Y3480D01*
X566092Y3605D01*
X566082Y3730D01*
Y7160D01*
X566052Y7190D01*
X565952Y7330D01*
X565932Y7370D01*
X565917Y7405D01*
X565897Y7445D01*
X565882Y7485D01*
X565872Y7525D01*
X565857Y7570D01*
X565852Y7610D01*
X565842Y7650D01*
X565837Y7695D01*
Y7735D01*
X565832Y7780D01*
X565837Y7825D01*
Y7865D01*
X565842Y7910D01*
X565852Y7950D01*
X565857Y7990D01*
X565872Y8035D01*
X565882Y8075D01*
X565897Y8115D01*
X565917Y8155D01*
X565932Y8190D01*
X565952Y8230D01*
X566052Y8370D01*
X566082Y8400D01*
Y9530D01*
X566092Y9655D01*
X566132Y9780D01*
X566192Y9890D01*
X566272Y9990D01*
X566372Y10070D01*
X566482Y10130D01*
X566607Y10170D01*
X566732Y10180D01*
X566857Y10170D01*
X566982Y10130D01*
X567092Y10070D01*
X567192Y9990D01*
X567272Y9890D01*
X567332Y9780D01*
X567372Y9655D01*
X567382Y9530D01*
Y8400D01*
X567412Y8370D01*
X567512Y8230D01*
X567532Y8190D01*
X567547Y8155D01*
X567567Y8115D01*
X567582Y8075D01*
X567592Y8035D01*
X567607Y7990D01*
X567612Y7950D01*
X567622Y7910D01*
X567627Y7865D01*
Y7825D01*
X567632Y7780D01*
X567627Y7735D01*
Y7695D01*
X567622Y7650D01*
X567612Y7610D01*
X567607Y7570D01*
X567592Y7525D01*
X567582Y7485D01*
X567567Y7445D01*
X567547Y7405D01*
X567532Y7370D01*
X567512Y7330D01*
X567412Y7190D01*
X567382Y7160D01*
Y3730D01*
X567372Y3605D01*
X567332Y3480D01*
X567272Y3370D01*
X567192Y3270D01*
X567092Y3190D01*
X566982Y3130D01*
X566857Y3090D01*
X566732Y3080D01*
G37*
G36*
G01X562008D02*
X561883Y3090D01*
X561758Y3130D01*
X561648Y3190D01*
X561548Y3270D01*
X561468Y3370D01*
X561408Y3480D01*
X561368Y3605D01*
X561358Y3730D01*
Y7160D01*
X561328Y7190D01*
X561228Y7330D01*
X561208Y7370D01*
X561193Y7405D01*
X561173Y7445D01*
X561158Y7485D01*
X561148Y7525D01*
X561133Y7570D01*
X561128Y7610D01*
X561118Y7650D01*
X561113Y7695D01*
Y7735D01*
X561108Y7780D01*
X561113Y7825D01*
Y7865D01*
X561118Y7910D01*
X561128Y7950D01*
X561133Y7990D01*
X561148Y8035D01*
X561158Y8075D01*
X561173Y8115D01*
X561193Y8155D01*
X561208Y8190D01*
X561228Y8230D01*
X561328Y8370D01*
X561358Y8400D01*
Y9530D01*
X561368Y9655D01*
X561408Y9780D01*
X561468Y9890D01*
X561548Y9990D01*
X561648Y10070D01*
X561758Y10130D01*
X561883Y10170D01*
X562008Y10180D01*
X562133Y10170D01*
X562258Y10130D01*
X562368Y10070D01*
X562468Y9990D01*
X562548Y9890D01*
X562608Y9780D01*
X562648Y9655D01*
X562658Y9530D01*
Y8400D01*
X562688Y8370D01*
X562788Y8230D01*
X562808Y8190D01*
X562823Y8155D01*
X562843Y8115D01*
X562858Y8075D01*
X562868Y8035D01*
X562883Y7990D01*
X562888Y7950D01*
X562898Y7910D01*
X562903Y7865D01*
Y7825D01*
X562908Y7780D01*
X562903Y7735D01*
Y7695D01*
X562898Y7650D01*
X562888Y7610D01*
X562883Y7570D01*
X562868Y7525D01*
X562858Y7485D01*
X562843Y7445D01*
X562823Y7405D01*
X562808Y7370D01*
X562788Y7330D01*
X562688Y7190D01*
X562658Y7160D01*
Y3730D01*
X562648Y3605D01*
X562608Y3480D01*
X562548Y3370D01*
X562468Y3270D01*
X562368Y3190D01*
X562258Y3130D01*
X562133Y3090D01*
X562008Y3080D01*
G37*
G36*
G01X585630D02*
X585505Y3090D01*
X585380Y3130D01*
X585270Y3190D01*
X585170Y3270D01*
X585090Y3370D01*
X585030Y3480D01*
X584990Y3605D01*
X584980Y3730D01*
Y7160D01*
X584950Y7190D01*
X584850Y7330D01*
X584830Y7370D01*
X584815Y7405D01*
X584795Y7445D01*
X584780Y7485D01*
X584770Y7525D01*
X584755Y7570D01*
X584750Y7610D01*
X584740Y7650D01*
X584735Y7695D01*
Y7735D01*
X584730Y7780D01*
X584735Y7825D01*
Y7865D01*
X584740Y7910D01*
X584750Y7950D01*
X584755Y7990D01*
X584770Y8035D01*
X584780Y8075D01*
X584795Y8115D01*
X584815Y8155D01*
X584830Y8190D01*
X584850Y8230D01*
X584950Y8370D01*
X584980Y8400D01*
Y9530D01*
X584990Y9655D01*
X585030Y9780D01*
X585090Y9890D01*
X585170Y9990D01*
X585270Y10070D01*
X585380Y10130D01*
X585505Y10170D01*
X585630Y10180D01*
X585755Y10170D01*
X585880Y10130D01*
X585990Y10070D01*
X586090Y9990D01*
X586170Y9890D01*
X586230Y9780D01*
X586270Y9655D01*
X586280Y9530D01*
Y8400D01*
X586310Y8370D01*
X586410Y8230D01*
X586430Y8190D01*
X586445Y8155D01*
X586465Y8115D01*
X586480Y8075D01*
X586490Y8035D01*
X586505Y7990D01*
X586510Y7950D01*
X586520Y7910D01*
X586525Y7865D01*
Y7825D01*
X586530Y7780D01*
X586525Y7735D01*
Y7695D01*
X586520Y7650D01*
X586510Y7610D01*
X586505Y7570D01*
X586490Y7525D01*
X586480Y7485D01*
X586465Y7445D01*
X586445Y7405D01*
X586430Y7370D01*
X586410Y7330D01*
X586310Y7190D01*
X586280Y7160D01*
Y3730D01*
X586270Y3605D01*
X586230Y3480D01*
X586170Y3370D01*
X586090Y3270D01*
X585990Y3190D01*
X585880Y3130D01*
X585755Y3090D01*
X585630Y3080D01*
G37*
G36*
G01X580905D02*
X580780Y3090D01*
X580655Y3130D01*
X580545Y3190D01*
X580445Y3270D01*
X580365Y3370D01*
X580305Y3480D01*
X580265Y3605D01*
X580255Y3730D01*
Y7160D01*
X580225Y7190D01*
X580125Y7330D01*
X580105Y7370D01*
X580090Y7405D01*
X580070Y7445D01*
X580055Y7485D01*
X580045Y7525D01*
X580030Y7570D01*
X580025Y7610D01*
X580015Y7650D01*
X580010Y7695D01*
Y7735D01*
X580005Y7780D01*
X580010Y7825D01*
Y7865D01*
X580015Y7910D01*
X580025Y7950D01*
X580030Y7990D01*
X580045Y8035D01*
X580055Y8075D01*
X580070Y8115D01*
X580090Y8155D01*
X580105Y8190D01*
X580125Y8230D01*
X580225Y8370D01*
X580255Y8400D01*
Y9530D01*
X580265Y9655D01*
X580305Y9780D01*
X580365Y9890D01*
X580445Y9990D01*
X580545Y10070D01*
X580655Y10130D01*
X580780Y10170D01*
X580905Y10180D01*
X581030Y10170D01*
X581155Y10130D01*
X581265Y10070D01*
X581365Y9990D01*
X581445Y9890D01*
X581505Y9780D01*
X581545Y9655D01*
X581555Y9530D01*
Y8400D01*
X581585Y8370D01*
X581685Y8230D01*
X581705Y8190D01*
X581720Y8155D01*
X581740Y8115D01*
X581755Y8075D01*
X581765Y8035D01*
X581780Y7990D01*
X581785Y7950D01*
X581795Y7910D01*
X581800Y7865D01*
Y7825D01*
X581805Y7780D01*
X581800Y7735D01*
Y7695D01*
X581795Y7650D01*
X581785Y7610D01*
X581780Y7570D01*
X581765Y7525D01*
X581755Y7485D01*
X581740Y7445D01*
X581720Y7405D01*
X581705Y7370D01*
X581685Y7330D01*
X581585Y7190D01*
X581555Y7160D01*
Y3730D01*
X581545Y3605D01*
X581505Y3480D01*
X581445Y3370D01*
X581365Y3270D01*
X581265Y3190D01*
X581155Y3130D01*
X581030Y3090D01*
X580905Y3080D01*
G37*
G36*
G01X576181D02*
X576056Y3090D01*
X575931Y3130D01*
X575821Y3190D01*
X575721Y3270D01*
X575641Y3370D01*
X575581Y3480D01*
X575541Y3605D01*
X575531Y3730D01*
Y7160D01*
X575501Y7190D01*
X575401Y7330D01*
X575381Y7370D01*
X575366Y7405D01*
X575346Y7445D01*
X575331Y7485D01*
X575321Y7525D01*
X575306Y7570D01*
X575301Y7610D01*
X575291Y7650D01*
X575286Y7695D01*
Y7735D01*
X575281Y7780D01*
X575286Y7825D01*
Y7865D01*
X575291Y7910D01*
X575301Y7950D01*
X575306Y7990D01*
X575321Y8035D01*
X575331Y8075D01*
X575346Y8115D01*
X575366Y8155D01*
X575381Y8190D01*
X575401Y8230D01*
X575501Y8370D01*
X575531Y8400D01*
Y9530D01*
X575541Y9655D01*
X575581Y9780D01*
X575641Y9890D01*
X575721Y9990D01*
X575821Y10070D01*
X575931Y10130D01*
X576056Y10170D01*
X576181Y10180D01*
X576306Y10170D01*
X576431Y10130D01*
X576541Y10070D01*
X576641Y9990D01*
X576721Y9890D01*
X576781Y9780D01*
X576821Y9655D01*
X576831Y9530D01*
Y8400D01*
X576861Y8370D01*
X576961Y8230D01*
X576981Y8190D01*
X576996Y8155D01*
X577016Y8115D01*
X577031Y8075D01*
X577041Y8035D01*
X577056Y7990D01*
X577061Y7950D01*
X577071Y7910D01*
X577076Y7865D01*
Y7825D01*
X577081Y7780D01*
X577076Y7735D01*
Y7695D01*
X577071Y7650D01*
X577061Y7610D01*
X577056Y7570D01*
X577041Y7525D01*
X577031Y7485D01*
X577016Y7445D01*
X576996Y7405D01*
X576981Y7370D01*
X576961Y7330D01*
X576861Y7190D01*
X576831Y7160D01*
Y3730D01*
X576821Y3605D01*
X576781Y3480D01*
X576721Y3370D01*
X576641Y3270D01*
X576541Y3190D01*
X576431Y3130D01*
X576306Y3090D01*
X576181Y3080D01*
G37*
G36*
G01X599803D02*
X599678Y3090D01*
X599553Y3130D01*
X599443Y3190D01*
X599343Y3270D01*
X599263Y3370D01*
X599203Y3480D01*
X599163Y3605D01*
X599153Y3730D01*
Y7160D01*
X599123Y7190D01*
X599023Y7330D01*
X599003Y7370D01*
X598988Y7405D01*
X598968Y7445D01*
X598953Y7485D01*
X598943Y7525D01*
X598928Y7570D01*
X598923Y7610D01*
X598913Y7650D01*
X598908Y7695D01*
Y7735D01*
X598903Y7780D01*
X598908Y7825D01*
Y7865D01*
X598913Y7910D01*
X598923Y7950D01*
X598928Y7990D01*
X598943Y8035D01*
X598953Y8075D01*
X598968Y8115D01*
X598988Y8155D01*
X599003Y8190D01*
X599023Y8230D01*
X599123Y8370D01*
X599153Y8400D01*
Y9530D01*
X599163Y9655D01*
X599203Y9780D01*
X599263Y9890D01*
X599343Y9990D01*
X599443Y10070D01*
X599553Y10130D01*
X599678Y10170D01*
X599803Y10180D01*
X599928Y10170D01*
X600053Y10130D01*
X600163Y10070D01*
X600263Y9990D01*
X600343Y9890D01*
X600403Y9780D01*
X600443Y9655D01*
X600453Y9530D01*
Y8400D01*
X600483Y8370D01*
X600583Y8230D01*
X600603Y8190D01*
X600618Y8155D01*
X600638Y8115D01*
X600653Y8075D01*
X600663Y8035D01*
X600678Y7990D01*
X600683Y7950D01*
X600693Y7910D01*
X600698Y7865D01*
Y7825D01*
X600703Y7780D01*
X600698Y7735D01*
Y7695D01*
X600693Y7650D01*
X600683Y7610D01*
X600678Y7570D01*
X600663Y7525D01*
X600653Y7485D01*
X600638Y7445D01*
X600618Y7405D01*
X600603Y7370D01*
X600583Y7330D01*
X600483Y7190D01*
X600453Y7160D01*
Y3730D01*
X600443Y3605D01*
X600403Y3480D01*
X600343Y3370D01*
X600263Y3270D01*
X600163Y3190D01*
X600053Y3130D01*
X599928Y3090D01*
X599803Y3080D01*
G37*
G36*
G01X618701D02*
X618576Y3090D01*
X618451Y3130D01*
X618341Y3190D01*
X618241Y3270D01*
X618161Y3370D01*
X618101Y3480D01*
X618061Y3605D01*
X618051Y3730D01*
Y7160D01*
X618021Y7190D01*
X617921Y7330D01*
X617901Y7370D01*
X617886Y7405D01*
X617866Y7445D01*
X617851Y7485D01*
X617841Y7525D01*
X617826Y7570D01*
X617821Y7610D01*
X617811Y7650D01*
X617806Y7695D01*
Y7735D01*
X617801Y7780D01*
X617806Y7825D01*
Y7865D01*
X617811Y7910D01*
X617821Y7950D01*
X617826Y7990D01*
X617841Y8035D01*
X617851Y8075D01*
X617866Y8115D01*
X617886Y8155D01*
X617901Y8190D01*
X617921Y8230D01*
X618021Y8370D01*
X618051Y8400D01*
Y9530D01*
X618061Y9655D01*
X618101Y9780D01*
X618161Y9890D01*
X618241Y9990D01*
X618341Y10070D01*
X618451Y10130D01*
X618576Y10170D01*
X618701Y10180D01*
X618826Y10170D01*
X618951Y10130D01*
X619061Y10070D01*
X619161Y9990D01*
X619241Y9890D01*
X619301Y9780D01*
X619341Y9655D01*
X619351Y9530D01*
Y8400D01*
X619381Y8370D01*
X619481Y8230D01*
X619501Y8190D01*
X619516Y8155D01*
X619536Y8115D01*
X619551Y8075D01*
X619561Y8035D01*
X619576Y7990D01*
X619581Y7950D01*
X619591Y7910D01*
X619596Y7865D01*
Y7825D01*
X619601Y7780D01*
X619596Y7735D01*
Y7695D01*
X619591Y7650D01*
X619581Y7610D01*
X619576Y7570D01*
X619561Y7525D01*
X619551Y7485D01*
X619536Y7445D01*
X619516Y7405D01*
X619501Y7370D01*
X619481Y7330D01*
X619381Y7190D01*
X619351Y7160D01*
Y3730D01*
X619341Y3605D01*
X619301Y3480D01*
X619241Y3370D01*
X619161Y3270D01*
X619061Y3190D01*
X618951Y3130D01*
X618826Y3090D01*
X618701Y3080D01*
G37*
G36*
G01X613976D02*
X613851Y3090D01*
X613726Y3130D01*
X613616Y3190D01*
X613516Y3270D01*
X613436Y3370D01*
X613376Y3480D01*
X613336Y3605D01*
X613326Y3730D01*
Y7160D01*
X613296Y7190D01*
X613196Y7330D01*
X613176Y7370D01*
X613161Y7405D01*
X613141Y7445D01*
X613126Y7485D01*
X613116Y7525D01*
X613101Y7570D01*
X613096Y7610D01*
X613086Y7650D01*
X613081Y7695D01*
Y7735D01*
X613076Y7780D01*
X613081Y7825D01*
Y7865D01*
X613086Y7910D01*
X613096Y7950D01*
X613101Y7990D01*
X613116Y8035D01*
X613126Y8075D01*
X613141Y8115D01*
X613161Y8155D01*
X613176Y8190D01*
X613196Y8230D01*
X613296Y8370D01*
X613326Y8400D01*
Y9530D01*
X613336Y9655D01*
X613376Y9780D01*
X613436Y9890D01*
X613516Y9990D01*
X613616Y10070D01*
X613726Y10130D01*
X613851Y10170D01*
X613976Y10180D01*
X614101Y10170D01*
X614226Y10130D01*
X614336Y10070D01*
X614436Y9990D01*
X614516Y9890D01*
X614576Y9780D01*
X614616Y9655D01*
X614626Y9530D01*
Y8400D01*
X614656Y8370D01*
X614756Y8230D01*
X614776Y8190D01*
X614791Y8155D01*
X614811Y8115D01*
X614826Y8075D01*
X614836Y8035D01*
X614851Y7990D01*
X614856Y7950D01*
X614866Y7910D01*
X614871Y7865D01*
Y7825D01*
X614876Y7780D01*
X614871Y7735D01*
Y7695D01*
X614866Y7650D01*
X614856Y7610D01*
X614851Y7570D01*
X614836Y7525D01*
X614826Y7485D01*
X614811Y7445D01*
X614791Y7405D01*
X614776Y7370D01*
X614756Y7330D01*
X614656Y7190D01*
X614626Y7160D01*
Y3730D01*
X614616Y3605D01*
X614576Y3480D01*
X614516Y3370D01*
X614436Y3270D01*
X614336Y3190D01*
X614226Y3130D01*
X614101Y3090D01*
X613976Y3080D01*
G37*
G36*
G01X609252D02*
X609127Y3090D01*
X609002Y3130D01*
X608892Y3190D01*
X608792Y3270D01*
X608712Y3370D01*
X608652Y3480D01*
X608612Y3605D01*
X608602Y3730D01*
Y7160D01*
X608572Y7190D01*
X608472Y7330D01*
X608452Y7370D01*
X608437Y7405D01*
X608417Y7445D01*
X608402Y7485D01*
X608392Y7525D01*
X608377Y7570D01*
X608372Y7610D01*
X608362Y7650D01*
X608357Y7695D01*
Y7735D01*
X608352Y7780D01*
X608357Y7825D01*
Y7865D01*
X608362Y7910D01*
X608372Y7950D01*
X608377Y7990D01*
X608392Y8035D01*
X608402Y8075D01*
X608417Y8115D01*
X608437Y8155D01*
X608452Y8190D01*
X608472Y8230D01*
X608572Y8370D01*
X608602Y8400D01*
Y9530D01*
X608612Y9655D01*
X608652Y9780D01*
X608712Y9890D01*
X608792Y9990D01*
X608892Y10070D01*
X609002Y10130D01*
X609127Y10170D01*
X609252Y10180D01*
X609377Y10170D01*
X609502Y10130D01*
X609612Y10070D01*
X609712Y9990D01*
X609792Y9890D01*
X609852Y9780D01*
X609892Y9655D01*
X609902Y9530D01*
Y8400D01*
X609932Y8370D01*
X610032Y8230D01*
X610052Y8190D01*
X610067Y8155D01*
X610087Y8115D01*
X610102Y8075D01*
X610112Y8035D01*
X610127Y7990D01*
X610132Y7950D01*
X610142Y7910D01*
X610147Y7865D01*
Y7825D01*
X610152Y7780D01*
X610147Y7735D01*
Y7695D01*
X610142Y7650D01*
X610132Y7610D01*
X610127Y7570D01*
X610112Y7525D01*
X610102Y7485D01*
X610087Y7445D01*
X610067Y7405D01*
X610052Y7370D01*
X610032Y7330D01*
X609932Y7190D01*
X609902Y7160D01*
Y3730D01*
X609892Y3605D01*
X609852Y3480D01*
X609792Y3370D01*
X609712Y3270D01*
X609612Y3190D01*
X609502Y3130D01*
X609377Y3090D01*
X609252Y3080D01*
G37*
G36*
G01X604527D02*
X604402Y3090D01*
X604277Y3130D01*
X604167Y3190D01*
X604067Y3270D01*
X603987Y3370D01*
X603927Y3480D01*
X603887Y3605D01*
X603877Y3730D01*
Y7160D01*
X603847Y7190D01*
X603747Y7330D01*
X603727Y7370D01*
X603712Y7405D01*
X603692Y7445D01*
X603677Y7485D01*
X603667Y7525D01*
X603652Y7570D01*
X603647Y7610D01*
X603637Y7650D01*
X603632Y7695D01*
Y7735D01*
X603627Y7780D01*
X603632Y7825D01*
Y7865D01*
X603637Y7910D01*
X603647Y7950D01*
X603652Y7990D01*
X603667Y8035D01*
X603677Y8075D01*
X603692Y8115D01*
X603712Y8155D01*
X603727Y8190D01*
X603747Y8230D01*
X603847Y8370D01*
X603877Y8400D01*
Y9530D01*
X603887Y9655D01*
X603927Y9780D01*
X603987Y9890D01*
X604067Y9990D01*
X604167Y10070D01*
X604277Y10130D01*
X604402Y10170D01*
X604527Y10180D01*
X604652Y10170D01*
X604777Y10130D01*
X604887Y10070D01*
X604987Y9990D01*
X605067Y9890D01*
X605127Y9780D01*
X605167Y9655D01*
X605177Y9530D01*
Y8400D01*
X605207Y8370D01*
X605307Y8230D01*
X605327Y8190D01*
X605342Y8155D01*
X605362Y8115D01*
X605377Y8075D01*
X605387Y8035D01*
X605402Y7990D01*
X605407Y7950D01*
X605417Y7910D01*
X605422Y7865D01*
Y7825D01*
X605427Y7780D01*
X605422Y7735D01*
Y7695D01*
X605417Y7650D01*
X605407Y7610D01*
X605402Y7570D01*
X605387Y7525D01*
X605377Y7485D01*
X605362Y7445D01*
X605342Y7405D01*
X605327Y7370D01*
X605307Y7330D01*
X605207Y7190D01*
X605177Y7160D01*
Y3730D01*
X605167Y3605D01*
X605127Y3480D01*
X605067Y3370D01*
X604987Y3270D01*
X604887Y3190D01*
X604777Y3130D01*
X604652Y3090D01*
X604527Y3080D01*
G37*
G36*
G01X632874D02*
X632749Y3090D01*
X632624Y3130D01*
X632514Y3190D01*
X632414Y3270D01*
X632334Y3370D01*
X632274Y3480D01*
X632234Y3605D01*
X632224Y3730D01*
Y7160D01*
X632194Y7190D01*
X632094Y7330D01*
X632074Y7370D01*
X632059Y7405D01*
X632039Y7445D01*
X632024Y7485D01*
X632014Y7525D01*
X631999Y7570D01*
X631994Y7610D01*
X631984Y7650D01*
X631979Y7695D01*
Y7735D01*
X631974Y7780D01*
X631979Y7825D01*
Y7865D01*
X631984Y7910D01*
X631994Y7950D01*
X631999Y7990D01*
X632014Y8035D01*
X632024Y8075D01*
X632039Y8115D01*
X632059Y8155D01*
X632074Y8190D01*
X632094Y8230D01*
X632194Y8370D01*
X632224Y8400D01*
Y9530D01*
X632234Y9655D01*
X632274Y9780D01*
X632334Y9890D01*
X632414Y9990D01*
X632514Y10070D01*
X632624Y10130D01*
X632749Y10170D01*
X632874Y10180D01*
X632999Y10170D01*
X633124Y10130D01*
X633234Y10070D01*
X633334Y9990D01*
X633414Y9890D01*
X633474Y9780D01*
X633514Y9655D01*
X633524Y9530D01*
Y8400D01*
X633554Y8370D01*
X633654Y8230D01*
X633674Y8190D01*
X633689Y8155D01*
X633709Y8115D01*
X633724Y8075D01*
X633734Y8035D01*
X633749Y7990D01*
X633754Y7950D01*
X633764Y7910D01*
X633769Y7865D01*
Y7825D01*
X633774Y7780D01*
X633769Y7735D01*
Y7695D01*
X633764Y7650D01*
X633754Y7610D01*
X633749Y7570D01*
X633734Y7525D01*
X633724Y7485D01*
X633709Y7445D01*
X633689Y7405D01*
X633674Y7370D01*
X633654Y7330D01*
X633554Y7190D01*
X633524Y7160D01*
Y3730D01*
X633514Y3605D01*
X633474Y3480D01*
X633414Y3370D01*
X633334Y3270D01*
X633234Y3190D01*
X633124Y3130D01*
X632999Y3090D01*
X632874Y3080D01*
G37*
G36*
G01X628149D02*
X628024Y3090D01*
X627899Y3130D01*
X627789Y3190D01*
X627689Y3270D01*
X627609Y3370D01*
X627549Y3480D01*
X627509Y3605D01*
X627499Y3730D01*
Y7160D01*
X627469Y7190D01*
X627369Y7330D01*
X627349Y7370D01*
X627334Y7405D01*
X627314Y7445D01*
X627299Y7485D01*
X627289Y7525D01*
X627274Y7570D01*
X627269Y7610D01*
X627259Y7650D01*
X627254Y7695D01*
Y7735D01*
X627249Y7780D01*
X627254Y7825D01*
Y7865D01*
X627259Y7910D01*
X627269Y7950D01*
X627274Y7990D01*
X627289Y8035D01*
X627299Y8075D01*
X627314Y8115D01*
X627334Y8155D01*
X627349Y8190D01*
X627369Y8230D01*
X627469Y8370D01*
X627499Y8400D01*
Y9530D01*
X627509Y9655D01*
X627549Y9780D01*
X627609Y9890D01*
X627689Y9990D01*
X627789Y10070D01*
X627899Y10130D01*
X628024Y10170D01*
X628149Y10180D01*
X628274Y10170D01*
X628399Y10130D01*
X628509Y10070D01*
X628609Y9990D01*
X628689Y9890D01*
X628749Y9780D01*
X628789Y9655D01*
X628799Y9530D01*
Y8400D01*
X628829Y8370D01*
X628929Y8230D01*
X628949Y8190D01*
X628964Y8155D01*
X628984Y8115D01*
X628999Y8075D01*
X629009Y8035D01*
X629024Y7990D01*
X629029Y7950D01*
X629039Y7910D01*
X629044Y7865D01*
Y7825D01*
X629049Y7780D01*
X629044Y7735D01*
Y7695D01*
X629039Y7650D01*
X629029Y7610D01*
X629024Y7570D01*
X629009Y7525D01*
X628999Y7485D01*
X628984Y7445D01*
X628964Y7405D01*
X628949Y7370D01*
X628929Y7330D01*
X628829Y7190D01*
X628799Y7160D01*
Y3730D01*
X628789Y3605D01*
X628749Y3480D01*
X628689Y3370D01*
X628609Y3270D01*
X628509Y3190D01*
X628399Y3130D01*
X628274Y3090D01*
X628149Y3080D01*
G37*
G36*
G01X623425D02*
X623300Y3090D01*
X623175Y3130D01*
X623065Y3190D01*
X622965Y3270D01*
X622885Y3370D01*
X622825Y3480D01*
X622785Y3605D01*
X622775Y3730D01*
Y7160D01*
X622745Y7190D01*
X622645Y7330D01*
X622625Y7370D01*
X622610Y7405D01*
X622590Y7445D01*
X622575Y7485D01*
X622565Y7525D01*
X622550Y7570D01*
X622545Y7610D01*
X622535Y7650D01*
X622530Y7695D01*
Y7735D01*
X622525Y7780D01*
X622530Y7825D01*
Y7865D01*
X622535Y7910D01*
X622545Y7950D01*
X622550Y7990D01*
X622565Y8035D01*
X622575Y8075D01*
X622590Y8115D01*
X622610Y8155D01*
X622625Y8190D01*
X622645Y8230D01*
X622745Y8370D01*
X622775Y8400D01*
Y9530D01*
X622785Y9655D01*
X622825Y9780D01*
X622885Y9890D01*
X622965Y9990D01*
X623065Y10070D01*
X623175Y10130D01*
X623300Y10170D01*
X623425Y10180D01*
X623550Y10170D01*
X623675Y10130D01*
X623785Y10070D01*
X623885Y9990D01*
X623965Y9890D01*
X624025Y9780D01*
X624065Y9655D01*
X624075Y9530D01*
Y8400D01*
X624105Y8370D01*
X624205Y8230D01*
X624225Y8190D01*
X624240Y8155D01*
X624260Y8115D01*
X624275Y8075D01*
X624285Y8035D01*
X624300Y7990D01*
X624305Y7950D01*
X624315Y7910D01*
X624320Y7865D01*
Y7825D01*
X624325Y7780D01*
X624320Y7735D01*
Y7695D01*
X624315Y7650D01*
X624305Y7610D01*
X624300Y7570D01*
X624285Y7525D01*
X624275Y7485D01*
X624260Y7445D01*
X624240Y7405D01*
X624225Y7370D01*
X624205Y7330D01*
X624105Y7190D01*
X624075Y7160D01*
Y3730D01*
X624065Y3605D01*
X624025Y3480D01*
X623965Y3370D01*
X623885Y3270D01*
X623785Y3190D01*
X623675Y3130D01*
X623550Y3090D01*
X623425Y3080D01*
G37*
G36*
G01X647047D02*
X646922Y3090D01*
X646797Y3130D01*
X646687Y3190D01*
X646587Y3270D01*
X646507Y3370D01*
X646447Y3480D01*
X646407Y3605D01*
X646397Y3730D01*
Y7160D01*
X646367Y7190D01*
X646267Y7330D01*
X646247Y7370D01*
X646232Y7405D01*
X646212Y7445D01*
X646197Y7485D01*
X646187Y7525D01*
X646172Y7570D01*
X646167Y7610D01*
X646157Y7650D01*
X646152Y7695D01*
Y7735D01*
X646147Y7780D01*
X646152Y7825D01*
Y7865D01*
X646157Y7910D01*
X646167Y7950D01*
X646172Y7990D01*
X646187Y8035D01*
X646197Y8075D01*
X646212Y8115D01*
X646232Y8155D01*
X646247Y8190D01*
X646267Y8230D01*
X646367Y8370D01*
X646397Y8400D01*
Y9530D01*
X646407Y9655D01*
X646447Y9780D01*
X646507Y9890D01*
X646587Y9990D01*
X646687Y10070D01*
X646797Y10130D01*
X646922Y10170D01*
X647047Y10180D01*
X647172Y10170D01*
X647297Y10130D01*
X647407Y10070D01*
X647507Y9990D01*
X647587Y9890D01*
X647647Y9780D01*
X647687Y9655D01*
X647697Y9530D01*
Y8400D01*
X647727Y8370D01*
X647827Y8230D01*
X647847Y8190D01*
X647862Y8155D01*
X647882Y8115D01*
X647897Y8075D01*
X647907Y8035D01*
X647922Y7990D01*
X647927Y7950D01*
X647937Y7910D01*
X647942Y7865D01*
Y7825D01*
X647947Y7780D01*
X647942Y7735D01*
Y7695D01*
X647937Y7650D01*
X647927Y7610D01*
X647922Y7570D01*
X647907Y7525D01*
X647897Y7485D01*
X647882Y7445D01*
X647862Y7405D01*
X647847Y7370D01*
X647827Y7330D01*
X647727Y7190D01*
X647697Y7160D01*
Y3730D01*
X647687Y3605D01*
X647647Y3480D01*
X647587Y3370D01*
X647507Y3270D01*
X647407Y3190D01*
X647297Y3130D01*
X647172Y3090D01*
X647047Y3080D01*
G37*
G36*
G01X642323D02*
X642198Y3090D01*
X642073Y3130D01*
X641963Y3190D01*
X641863Y3270D01*
X641783Y3370D01*
X641723Y3480D01*
X641683Y3605D01*
X641673Y3730D01*
Y7160D01*
X641643Y7190D01*
X641543Y7330D01*
X641523Y7370D01*
X641508Y7405D01*
X641488Y7445D01*
X641473Y7485D01*
X641463Y7525D01*
X641448Y7570D01*
X641443Y7610D01*
X641433Y7650D01*
X641428Y7695D01*
Y7735D01*
X641423Y7780D01*
X641428Y7825D01*
Y7865D01*
X641433Y7910D01*
X641443Y7950D01*
X641448Y7990D01*
X641463Y8035D01*
X641473Y8075D01*
X641488Y8115D01*
X641508Y8155D01*
X641523Y8190D01*
X641543Y8230D01*
X641643Y8370D01*
X641673Y8400D01*
Y9530D01*
X641683Y9655D01*
X641723Y9780D01*
X641783Y9890D01*
X641863Y9990D01*
X641963Y10070D01*
X642073Y10130D01*
X642198Y10170D01*
X642323Y10180D01*
X642448Y10170D01*
X642573Y10130D01*
X642683Y10070D01*
X642783Y9990D01*
X642863Y9890D01*
X642923Y9780D01*
X642963Y9655D01*
X642973Y9530D01*
Y8400D01*
X643003Y8370D01*
X643103Y8230D01*
X643123Y8190D01*
X643138Y8155D01*
X643158Y8115D01*
X643173Y8075D01*
X643183Y8035D01*
X643198Y7990D01*
X643203Y7950D01*
X643213Y7910D01*
X643218Y7865D01*
Y7825D01*
X643223Y7780D01*
X643218Y7735D01*
Y7695D01*
X643213Y7650D01*
X643203Y7610D01*
X643198Y7570D01*
X643183Y7525D01*
X643173Y7485D01*
X643158Y7445D01*
X643138Y7405D01*
X643123Y7370D01*
X643103Y7330D01*
X643003Y7190D01*
X642973Y7160D01*
Y3730D01*
X642963Y3605D01*
X642923Y3480D01*
X642863Y3370D01*
X642783Y3270D01*
X642683Y3190D01*
X642573Y3130D01*
X642448Y3090D01*
X642323Y3080D01*
G37*
G36*
G01X637598D02*
X637473Y3090D01*
X637348Y3130D01*
X637238Y3190D01*
X637138Y3270D01*
X637058Y3370D01*
X636998Y3480D01*
X636958Y3605D01*
X636948Y3730D01*
Y7160D01*
X636918Y7190D01*
X636818Y7330D01*
X636798Y7370D01*
X636783Y7405D01*
X636763Y7445D01*
X636748Y7485D01*
X636738Y7525D01*
X636723Y7570D01*
X636718Y7610D01*
X636708Y7650D01*
X636703Y7695D01*
Y7735D01*
X636698Y7780D01*
X636703Y7825D01*
Y7865D01*
X636708Y7910D01*
X636718Y7950D01*
X636723Y7990D01*
X636738Y8035D01*
X636748Y8075D01*
X636763Y8115D01*
X636783Y8155D01*
X636798Y8190D01*
X636818Y8230D01*
X636918Y8370D01*
X636948Y8400D01*
Y9530D01*
X636958Y9655D01*
X636998Y9780D01*
X637058Y9890D01*
X637138Y9990D01*
X637238Y10070D01*
X637348Y10130D01*
X637473Y10170D01*
X637598Y10180D01*
X637723Y10170D01*
X637848Y10130D01*
X637958Y10070D01*
X638058Y9990D01*
X638138Y9890D01*
X638198Y9780D01*
X638238Y9655D01*
X638248Y9530D01*
Y8400D01*
X638278Y8370D01*
X638378Y8230D01*
X638398Y8190D01*
X638413Y8155D01*
X638433Y8115D01*
X638448Y8075D01*
X638458Y8035D01*
X638473Y7990D01*
X638478Y7950D01*
X638488Y7910D01*
X638493Y7865D01*
Y7825D01*
X638498Y7780D01*
X638493Y7735D01*
Y7695D01*
X638488Y7650D01*
X638478Y7610D01*
X638473Y7570D01*
X638458Y7525D01*
X638448Y7485D01*
X638433Y7445D01*
X638413Y7405D01*
X638398Y7370D01*
X638378Y7330D01*
X638278Y7190D01*
X638248Y7160D01*
Y3730D01*
X638238Y3605D01*
X638198Y3480D01*
X638138Y3370D01*
X638058Y3270D01*
X637958Y3190D01*
X637848Y3130D01*
X637723Y3090D01*
X637598Y3080D01*
G37*
G36*
G01X661220D02*
X661095Y3090D01*
X660970Y3130D01*
X660860Y3190D01*
X660760Y3270D01*
X660680Y3370D01*
X660620Y3480D01*
X660580Y3605D01*
X660570Y3730D01*
Y7160D01*
X660540Y7190D01*
X660440Y7330D01*
X660420Y7370D01*
X660405Y7405D01*
X660385Y7445D01*
X660370Y7485D01*
X660360Y7525D01*
X660345Y7570D01*
X660340Y7610D01*
X660330Y7650D01*
X660325Y7695D01*
Y7735D01*
X660320Y7780D01*
X660325Y7825D01*
Y7865D01*
X660330Y7910D01*
X660340Y7950D01*
X660345Y7990D01*
X660360Y8035D01*
X660370Y8075D01*
X660385Y8115D01*
X660405Y8155D01*
X660420Y8190D01*
X660440Y8230D01*
X660540Y8370D01*
X660570Y8400D01*
Y9530D01*
X660580Y9655D01*
X660620Y9780D01*
X660680Y9890D01*
X660760Y9990D01*
X660860Y10070D01*
X660970Y10130D01*
X661095Y10170D01*
X661220Y10180D01*
X661345Y10170D01*
X661470Y10130D01*
X661580Y10070D01*
X661680Y9990D01*
X661760Y9890D01*
X661820Y9780D01*
X661860Y9655D01*
X661870Y9530D01*
Y8400D01*
X661900Y8370D01*
X662000Y8230D01*
X662020Y8190D01*
X662035Y8155D01*
X662055Y8115D01*
X662070Y8075D01*
X662080Y8035D01*
X662095Y7990D01*
X662100Y7950D01*
X662110Y7910D01*
X662115Y7865D01*
Y7825D01*
X662120Y7780D01*
X662115Y7735D01*
Y7695D01*
X662110Y7650D01*
X662100Y7610D01*
X662095Y7570D01*
X662080Y7525D01*
X662070Y7485D01*
X662055Y7445D01*
X662035Y7405D01*
X662020Y7370D01*
X662000Y7330D01*
X661900Y7190D01*
X661870Y7160D01*
Y3730D01*
X661860Y3605D01*
X661820Y3480D01*
X661760Y3370D01*
X661680Y3270D01*
X661580Y3190D01*
X661470Y3130D01*
X661345Y3090D01*
X661220Y3080D01*
G37*
G36*
G01X656496D02*
X656371Y3090D01*
X656246Y3130D01*
X656136Y3190D01*
X656036Y3270D01*
X655956Y3370D01*
X655896Y3480D01*
X655856Y3605D01*
X655846Y3730D01*
Y7160D01*
X655816Y7190D01*
X655716Y7330D01*
X655696Y7370D01*
X655681Y7405D01*
X655661Y7445D01*
X655646Y7485D01*
X655636Y7525D01*
X655621Y7570D01*
X655616Y7610D01*
X655606Y7650D01*
X655601Y7695D01*
Y7735D01*
X655596Y7780D01*
X655601Y7825D01*
Y7865D01*
X655606Y7910D01*
X655616Y7950D01*
X655621Y7990D01*
X655636Y8035D01*
X655646Y8075D01*
X655661Y8115D01*
X655681Y8155D01*
X655696Y8190D01*
X655716Y8230D01*
X655816Y8370D01*
X655846Y8400D01*
Y9530D01*
X655856Y9655D01*
X655896Y9780D01*
X655956Y9890D01*
X656036Y9990D01*
X656136Y10070D01*
X656246Y10130D01*
X656371Y10170D01*
X656496Y10180D01*
X656621Y10170D01*
X656746Y10130D01*
X656856Y10070D01*
X656956Y9990D01*
X657036Y9890D01*
X657096Y9780D01*
X657136Y9655D01*
X657146Y9530D01*
Y8400D01*
X657176Y8370D01*
X657276Y8230D01*
X657296Y8190D01*
X657311Y8155D01*
X657331Y8115D01*
X657346Y8075D01*
X657356Y8035D01*
X657371Y7990D01*
X657376Y7950D01*
X657386Y7910D01*
X657391Y7865D01*
Y7825D01*
X657396Y7780D01*
X657391Y7735D01*
Y7695D01*
X657386Y7650D01*
X657376Y7610D01*
X657371Y7570D01*
X657356Y7525D01*
X657346Y7485D01*
X657331Y7445D01*
X657311Y7405D01*
X657296Y7370D01*
X657276Y7330D01*
X657176Y7190D01*
X657146Y7160D01*
Y3730D01*
X657136Y3605D01*
X657096Y3480D01*
X657036Y3370D01*
X656956Y3270D01*
X656856Y3190D01*
X656746Y3130D01*
X656621Y3090D01*
X656496Y3080D01*
G37*
G36*
G01X651771D02*
X651646Y3090D01*
X651521Y3130D01*
X651411Y3190D01*
X651311Y3270D01*
X651231Y3370D01*
X651171Y3480D01*
X651131Y3605D01*
X651121Y3730D01*
Y7160D01*
X651091Y7190D01*
X650991Y7330D01*
X650971Y7370D01*
X650956Y7405D01*
X650936Y7445D01*
X650921Y7485D01*
X650911Y7525D01*
X650896Y7570D01*
X650891Y7610D01*
X650881Y7650D01*
X650876Y7695D01*
Y7735D01*
X650871Y7780D01*
X650876Y7825D01*
Y7865D01*
X650881Y7910D01*
X650891Y7950D01*
X650896Y7990D01*
X650911Y8035D01*
X650921Y8075D01*
X650936Y8115D01*
X650956Y8155D01*
X650971Y8190D01*
X650991Y8230D01*
X651091Y8370D01*
X651121Y8400D01*
Y9530D01*
X651131Y9655D01*
X651171Y9780D01*
X651231Y9890D01*
X651311Y9990D01*
X651411Y10070D01*
X651521Y10130D01*
X651646Y10170D01*
X651771Y10180D01*
X651896Y10170D01*
X652021Y10130D01*
X652131Y10070D01*
X652231Y9990D01*
X652311Y9890D01*
X652371Y9780D01*
X652411Y9655D01*
X652421Y9530D01*
Y8400D01*
X652451Y8370D01*
X652551Y8230D01*
X652571Y8190D01*
X652586Y8155D01*
X652606Y8115D01*
X652621Y8075D01*
X652631Y8035D01*
X652646Y7990D01*
X652651Y7950D01*
X652661Y7910D01*
X652666Y7865D01*
Y7825D01*
X652671Y7780D01*
X652666Y7735D01*
Y7695D01*
X652661Y7650D01*
X652651Y7610D01*
X652646Y7570D01*
X652631Y7525D01*
X652621Y7485D01*
X652606Y7445D01*
X652586Y7405D01*
X652571Y7370D01*
X652551Y7330D01*
X652451Y7190D01*
X652421Y7160D01*
Y3730D01*
X652411Y3605D01*
X652371Y3480D01*
X652311Y3370D01*
X652231Y3270D01*
X652131Y3190D01*
X652021Y3130D01*
X651896Y3090D01*
X651771Y3080D01*
G37*
G36*
G01X680118D02*
X679993Y3090D01*
X679868Y3130D01*
X679758Y3190D01*
X679658Y3270D01*
X679578Y3370D01*
X679518Y3480D01*
X679478Y3605D01*
X679468Y3730D01*
Y7160D01*
X679438Y7190D01*
X679338Y7330D01*
X679318Y7370D01*
X679303Y7405D01*
X679283Y7445D01*
X679268Y7485D01*
X679258Y7525D01*
X679243Y7570D01*
X679238Y7610D01*
X679228Y7650D01*
X679223Y7695D01*
Y7735D01*
X679218Y7780D01*
X679223Y7825D01*
Y7865D01*
X679228Y7910D01*
X679238Y7950D01*
X679243Y7990D01*
X679258Y8035D01*
X679268Y8075D01*
X679283Y8115D01*
X679303Y8155D01*
X679318Y8190D01*
X679338Y8230D01*
X679438Y8370D01*
X679468Y8400D01*
Y9530D01*
X679478Y9655D01*
X679518Y9780D01*
X679578Y9890D01*
X679658Y9990D01*
X679758Y10070D01*
X679868Y10130D01*
X679993Y10170D01*
X680118Y10180D01*
X680243Y10170D01*
X680368Y10130D01*
X680478Y10070D01*
X680578Y9990D01*
X680658Y9890D01*
X680718Y9780D01*
X680758Y9655D01*
X680768Y9530D01*
Y8400D01*
X680798Y8370D01*
X680898Y8230D01*
X680918Y8190D01*
X680933Y8155D01*
X680953Y8115D01*
X680968Y8075D01*
X680978Y8035D01*
X680993Y7990D01*
X680998Y7950D01*
X681008Y7910D01*
X681013Y7865D01*
Y7825D01*
X681018Y7780D01*
X681013Y7735D01*
Y7695D01*
X681008Y7650D01*
X680998Y7610D01*
X680993Y7570D01*
X680978Y7525D01*
X680968Y7485D01*
X680953Y7445D01*
X680933Y7405D01*
X680918Y7370D01*
X680898Y7330D01*
X680798Y7190D01*
X680768Y7160D01*
Y3730D01*
X680758Y3605D01*
X680718Y3480D01*
X680658Y3370D01*
X680578Y3270D01*
X680478Y3190D01*
X680368Y3130D01*
X680243Y3090D01*
X680118Y3080D01*
G37*
G36*
G01X675393D02*
X675268Y3090D01*
X675143Y3130D01*
X675033Y3190D01*
X674933Y3270D01*
X674853Y3370D01*
X674793Y3480D01*
X674753Y3605D01*
X674743Y3730D01*
Y7160D01*
X674713Y7190D01*
X674613Y7330D01*
X674593Y7370D01*
X674578Y7405D01*
X674558Y7445D01*
X674543Y7485D01*
X674533Y7525D01*
X674518Y7570D01*
X674513Y7610D01*
X674503Y7650D01*
X674498Y7695D01*
Y7735D01*
X674493Y7780D01*
X674498Y7825D01*
Y7865D01*
X674503Y7910D01*
X674513Y7950D01*
X674518Y7990D01*
X674533Y8035D01*
X674543Y8075D01*
X674558Y8115D01*
X674578Y8155D01*
X674593Y8190D01*
X674613Y8230D01*
X674713Y8370D01*
X674743Y8400D01*
Y9530D01*
X674753Y9655D01*
X674793Y9780D01*
X674853Y9890D01*
X674933Y9990D01*
X675033Y10070D01*
X675143Y10130D01*
X675268Y10170D01*
X675393Y10180D01*
X675518Y10170D01*
X675643Y10130D01*
X675753Y10070D01*
X675853Y9990D01*
X675933Y9890D01*
X675993Y9780D01*
X676033Y9655D01*
X676043Y9530D01*
Y8400D01*
X676073Y8370D01*
X676173Y8230D01*
X676193Y8190D01*
X676208Y8155D01*
X676228Y8115D01*
X676243Y8075D01*
X676253Y8035D01*
X676268Y7990D01*
X676273Y7950D01*
X676283Y7910D01*
X676288Y7865D01*
Y7825D01*
X676293Y7780D01*
X676288Y7735D01*
Y7695D01*
X676283Y7650D01*
X676273Y7610D01*
X676268Y7570D01*
X676253Y7525D01*
X676243Y7485D01*
X676228Y7445D01*
X676208Y7405D01*
X676193Y7370D01*
X676173Y7330D01*
X676073Y7190D01*
X676043Y7160D01*
Y3730D01*
X676033Y3605D01*
X675993Y3480D01*
X675933Y3370D01*
X675853Y3270D01*
X675753Y3190D01*
X675643Y3130D01*
X675518Y3090D01*
X675393Y3080D01*
G37*
G36*
G01X670669D02*
X670544Y3090D01*
X670419Y3130D01*
X670309Y3190D01*
X670209Y3270D01*
X670129Y3370D01*
X670069Y3480D01*
X670029Y3605D01*
X670019Y3730D01*
Y7160D01*
X669989Y7190D01*
X669889Y7330D01*
X669869Y7370D01*
X669854Y7405D01*
X669834Y7445D01*
X669819Y7485D01*
X669809Y7525D01*
X669794Y7570D01*
X669789Y7610D01*
X669779Y7650D01*
X669774Y7695D01*
Y7735D01*
X669769Y7780D01*
X669774Y7825D01*
Y7865D01*
X669779Y7910D01*
X669789Y7950D01*
X669794Y7990D01*
X669809Y8035D01*
X669819Y8075D01*
X669834Y8115D01*
X669854Y8155D01*
X669869Y8190D01*
X669889Y8230D01*
X669989Y8370D01*
X670019Y8400D01*
Y9530D01*
X670029Y9655D01*
X670069Y9780D01*
X670129Y9890D01*
X670209Y9990D01*
X670309Y10070D01*
X670419Y10130D01*
X670544Y10170D01*
X670669Y10180D01*
X670794Y10170D01*
X670919Y10130D01*
X671029Y10070D01*
X671129Y9990D01*
X671209Y9890D01*
X671269Y9780D01*
X671309Y9655D01*
X671319Y9530D01*
Y8400D01*
X671349Y8370D01*
X671449Y8230D01*
X671469Y8190D01*
X671484Y8155D01*
X671504Y8115D01*
X671519Y8075D01*
X671529Y8035D01*
X671544Y7990D01*
X671549Y7950D01*
X671559Y7910D01*
X671564Y7865D01*
Y7825D01*
X671569Y7780D01*
X671564Y7735D01*
Y7695D01*
X671559Y7650D01*
X671549Y7610D01*
X671544Y7570D01*
X671529Y7525D01*
X671519Y7485D01*
X671504Y7445D01*
X671484Y7405D01*
X671469Y7370D01*
X671449Y7330D01*
X671349Y7190D01*
X671319Y7160D01*
Y3730D01*
X671309Y3605D01*
X671269Y3480D01*
X671209Y3370D01*
X671129Y3270D01*
X671029Y3190D01*
X670919Y3130D01*
X670794Y3090D01*
X670669Y3080D01*
G37*
G36*
G01X665945D02*
X665820Y3090D01*
X665695Y3130D01*
X665585Y3190D01*
X665485Y3270D01*
X665405Y3370D01*
X665345Y3480D01*
X665305Y3605D01*
X665295Y3730D01*
Y7160D01*
X665265Y7190D01*
X665165Y7330D01*
X665145Y7370D01*
X665130Y7405D01*
X665110Y7445D01*
X665095Y7485D01*
X665085Y7525D01*
X665070Y7570D01*
X665065Y7610D01*
X665055Y7650D01*
X665050Y7695D01*
Y7735D01*
X665045Y7780D01*
X665050Y7825D01*
Y7865D01*
X665055Y7910D01*
X665065Y7950D01*
X665070Y7990D01*
X665085Y8035D01*
X665095Y8075D01*
X665110Y8115D01*
X665130Y8155D01*
X665145Y8190D01*
X665165Y8230D01*
X665265Y8370D01*
X665295Y8400D01*
Y9530D01*
X665305Y9655D01*
X665345Y9780D01*
X665405Y9890D01*
X665485Y9990D01*
X665585Y10070D01*
X665695Y10130D01*
X665820Y10170D01*
X665945Y10180D01*
X666070Y10170D01*
X666195Y10130D01*
X666305Y10070D01*
X666405Y9990D01*
X666485Y9890D01*
X666545Y9780D01*
X666585Y9655D01*
X666595Y9530D01*
Y8400D01*
X666625Y8370D01*
X666725Y8230D01*
X666745Y8190D01*
X666760Y8155D01*
X666780Y8115D01*
X666795Y8075D01*
X666805Y8035D01*
X666820Y7990D01*
X666825Y7950D01*
X666835Y7910D01*
X666840Y7865D01*
Y7825D01*
X666845Y7780D01*
X666840Y7735D01*
Y7695D01*
X666835Y7650D01*
X666825Y7610D01*
X666820Y7570D01*
X666805Y7525D01*
X666795Y7485D01*
X666780Y7445D01*
X666760Y7405D01*
X666745Y7370D01*
X666725Y7330D01*
X666625Y7190D01*
X666595Y7160D01*
Y3730D01*
X666585Y3605D01*
X666545Y3480D01*
X666485Y3370D01*
X666405Y3270D01*
X666305Y3190D01*
X666195Y3130D01*
X666070Y3090D01*
X665945Y3080D01*
G37*
G36*
G01X694291D02*
X694166Y3090D01*
X694041Y3130D01*
X693931Y3190D01*
X693831Y3270D01*
X693751Y3370D01*
X693691Y3480D01*
X693651Y3605D01*
X693641Y3730D01*
Y7160D01*
X693611Y7190D01*
X693511Y7330D01*
X693491Y7370D01*
X693476Y7405D01*
X693456Y7445D01*
X693441Y7485D01*
X693431Y7525D01*
X693416Y7570D01*
X693411Y7610D01*
X693401Y7650D01*
X693396Y7695D01*
Y7735D01*
X693391Y7780D01*
X693396Y7825D01*
Y7865D01*
X693401Y7910D01*
X693411Y7950D01*
X693416Y7990D01*
X693431Y8035D01*
X693441Y8075D01*
X693456Y8115D01*
X693476Y8155D01*
X693491Y8190D01*
X693511Y8230D01*
X693611Y8370D01*
X693641Y8400D01*
Y9530D01*
X693651Y9655D01*
X693691Y9780D01*
X693751Y9890D01*
X693831Y9990D01*
X693931Y10070D01*
X694041Y10130D01*
X694166Y10170D01*
X694291Y10180D01*
X694416Y10170D01*
X694541Y10130D01*
X694651Y10070D01*
X694751Y9990D01*
X694831Y9890D01*
X694891Y9780D01*
X694931Y9655D01*
X694941Y9530D01*
Y8400D01*
X694971Y8370D01*
X695071Y8230D01*
X695091Y8190D01*
X695106Y8155D01*
X695126Y8115D01*
X695141Y8075D01*
X695151Y8035D01*
X695166Y7990D01*
X695171Y7950D01*
X695181Y7910D01*
X695186Y7865D01*
Y7825D01*
X695191Y7780D01*
X695186Y7735D01*
Y7695D01*
X695181Y7650D01*
X695171Y7610D01*
X695166Y7570D01*
X695151Y7525D01*
X695141Y7485D01*
X695126Y7445D01*
X695106Y7405D01*
X695091Y7370D01*
X695071Y7330D01*
X694971Y7190D01*
X694941Y7160D01*
Y3730D01*
X694931Y3605D01*
X694891Y3480D01*
X694831Y3370D01*
X694751Y3270D01*
X694651Y3190D01*
X694541Y3130D01*
X694416Y3090D01*
X694291Y3080D01*
G37*
G36*
G01X689567D02*
X689442Y3090D01*
X689317Y3130D01*
X689207Y3190D01*
X689107Y3270D01*
X689027Y3370D01*
X688967Y3480D01*
X688927Y3605D01*
X688917Y3730D01*
Y7160D01*
X688887Y7190D01*
X688787Y7330D01*
X688767Y7370D01*
X688752Y7405D01*
X688732Y7445D01*
X688717Y7485D01*
X688707Y7525D01*
X688692Y7570D01*
X688687Y7610D01*
X688677Y7650D01*
X688672Y7695D01*
Y7735D01*
X688667Y7780D01*
X688672Y7825D01*
Y7865D01*
X688677Y7910D01*
X688687Y7950D01*
X688692Y7990D01*
X688707Y8035D01*
X688717Y8075D01*
X688732Y8115D01*
X688752Y8155D01*
X688767Y8190D01*
X688787Y8230D01*
X688887Y8370D01*
X688917Y8400D01*
Y9530D01*
X688927Y9655D01*
X688967Y9780D01*
X689027Y9890D01*
X689107Y9990D01*
X689207Y10070D01*
X689317Y10130D01*
X689442Y10170D01*
X689567Y10180D01*
X689692Y10170D01*
X689817Y10130D01*
X689927Y10070D01*
X690027Y9990D01*
X690107Y9890D01*
X690167Y9780D01*
X690207Y9655D01*
X690217Y9530D01*
Y8400D01*
X690247Y8370D01*
X690347Y8230D01*
X690367Y8190D01*
X690382Y8155D01*
X690402Y8115D01*
X690417Y8075D01*
X690427Y8035D01*
X690442Y7990D01*
X690447Y7950D01*
X690457Y7910D01*
X690462Y7865D01*
Y7825D01*
X690467Y7780D01*
X690462Y7735D01*
Y7695D01*
X690457Y7650D01*
X690447Y7610D01*
X690442Y7570D01*
X690427Y7525D01*
X690417Y7485D01*
X690402Y7445D01*
X690382Y7405D01*
X690367Y7370D01*
X690347Y7330D01*
X690247Y7190D01*
X690217Y7160D01*
Y3730D01*
X690207Y3605D01*
X690167Y3480D01*
X690107Y3370D01*
X690027Y3270D01*
X689927Y3190D01*
X689817Y3130D01*
X689692Y3090D01*
X689567Y3080D01*
G37*
G36*
G01X684842D02*
X684717Y3090D01*
X684592Y3130D01*
X684482Y3190D01*
X684382Y3270D01*
X684302Y3370D01*
X684242Y3480D01*
X684202Y3605D01*
X684192Y3730D01*
Y7160D01*
X684162Y7190D01*
X684062Y7330D01*
X684042Y7370D01*
X684027Y7405D01*
X684007Y7445D01*
X683992Y7485D01*
X683982Y7525D01*
X683967Y7570D01*
X683962Y7610D01*
X683952Y7650D01*
X683947Y7695D01*
Y7735D01*
X683942Y7780D01*
X683947Y7825D01*
Y7865D01*
X683952Y7910D01*
X683962Y7950D01*
X683967Y7990D01*
X683982Y8035D01*
X683992Y8075D01*
X684007Y8115D01*
X684027Y8155D01*
X684042Y8190D01*
X684062Y8230D01*
X684162Y8370D01*
X684192Y8400D01*
Y9530D01*
X684202Y9655D01*
X684242Y9780D01*
X684302Y9890D01*
X684382Y9990D01*
X684482Y10070D01*
X684592Y10130D01*
X684717Y10170D01*
X684842Y10180D01*
X684967Y10170D01*
X685092Y10130D01*
X685202Y10070D01*
X685302Y9990D01*
X685382Y9890D01*
X685442Y9780D01*
X685482Y9655D01*
X685492Y9530D01*
Y8400D01*
X685522Y8370D01*
X685622Y8230D01*
X685642Y8190D01*
X685657Y8155D01*
X685677Y8115D01*
X685692Y8075D01*
X685702Y8035D01*
X685717Y7990D01*
X685722Y7950D01*
X685732Y7910D01*
X685737Y7865D01*
Y7825D01*
X685742Y7780D01*
X685737Y7735D01*
Y7695D01*
X685732Y7650D01*
X685722Y7610D01*
X685717Y7570D01*
X685702Y7525D01*
X685692Y7485D01*
X685677Y7445D01*
X685657Y7405D01*
X685642Y7370D01*
X685622Y7330D01*
X685522Y7190D01*
X685492Y7160D01*
Y3730D01*
X685482Y3605D01*
X685442Y3480D01*
X685382Y3370D01*
X685302Y3270D01*
X685202Y3190D01*
X685092Y3130D01*
X684967Y3090D01*
X684842Y3080D01*
G37*
G36*
G01X708464D02*
X708339Y3090D01*
X708214Y3130D01*
X708104Y3190D01*
X708004Y3270D01*
X707924Y3370D01*
X707864Y3480D01*
X707824Y3605D01*
X707814Y3730D01*
Y7160D01*
X707784Y7190D01*
X707684Y7330D01*
X707664Y7370D01*
X707649Y7405D01*
X707629Y7445D01*
X707614Y7485D01*
X707604Y7525D01*
X707589Y7570D01*
X707584Y7610D01*
X707574Y7650D01*
X707569Y7695D01*
Y7735D01*
X707564Y7780D01*
X707569Y7825D01*
Y7865D01*
X707574Y7910D01*
X707584Y7950D01*
X707589Y7990D01*
X707604Y8035D01*
X707614Y8075D01*
X707629Y8115D01*
X707649Y8155D01*
X707664Y8190D01*
X707684Y8230D01*
X707784Y8370D01*
X707814Y8400D01*
Y9530D01*
X707824Y9655D01*
X707864Y9780D01*
X707924Y9890D01*
X708004Y9990D01*
X708104Y10070D01*
X708214Y10130D01*
X708339Y10170D01*
X708464Y10180D01*
X708589Y10170D01*
X708714Y10130D01*
X708824Y10070D01*
X708924Y9990D01*
X709004Y9890D01*
X709064Y9780D01*
X709104Y9655D01*
X709114Y9530D01*
Y8400D01*
X709144Y8370D01*
X709244Y8230D01*
X709264Y8190D01*
X709279Y8155D01*
X709299Y8115D01*
X709314Y8075D01*
X709324Y8035D01*
X709339Y7990D01*
X709344Y7950D01*
X709354Y7910D01*
X709359Y7865D01*
Y7825D01*
X709364Y7780D01*
X709359Y7735D01*
Y7695D01*
X709354Y7650D01*
X709344Y7610D01*
X709339Y7570D01*
X709324Y7525D01*
X709314Y7485D01*
X709299Y7445D01*
X709279Y7405D01*
X709264Y7370D01*
X709244Y7330D01*
X709144Y7190D01*
X709114Y7160D01*
Y3730D01*
X709104Y3605D01*
X709064Y3480D01*
X709004Y3370D01*
X708924Y3270D01*
X708824Y3190D01*
X708714Y3130D01*
X708589Y3090D01*
X708464Y3080D01*
G37*
G36*
G01X703740D02*
X703615Y3090D01*
X703490Y3130D01*
X703380Y3190D01*
X703280Y3270D01*
X703200Y3370D01*
X703140Y3480D01*
X703100Y3605D01*
X703090Y3730D01*
Y7160D01*
X703060Y7190D01*
X702960Y7330D01*
X702940Y7370D01*
X702925Y7405D01*
X702905Y7445D01*
X702890Y7485D01*
X702880Y7525D01*
X702865Y7570D01*
X702860Y7610D01*
X702850Y7650D01*
X702845Y7695D01*
Y7735D01*
X702840Y7780D01*
X702845Y7825D01*
Y7865D01*
X702850Y7910D01*
X702860Y7950D01*
X702865Y7990D01*
X702880Y8035D01*
X702890Y8075D01*
X702905Y8115D01*
X702925Y8155D01*
X702940Y8190D01*
X702960Y8230D01*
X703060Y8370D01*
X703090Y8400D01*
Y9530D01*
X703100Y9655D01*
X703140Y9780D01*
X703200Y9890D01*
X703280Y9990D01*
X703380Y10070D01*
X703490Y10130D01*
X703615Y10170D01*
X703740Y10180D01*
X703865Y10170D01*
X703990Y10130D01*
X704100Y10070D01*
X704200Y9990D01*
X704280Y9890D01*
X704340Y9780D01*
X704380Y9655D01*
X704390Y9530D01*
Y8400D01*
X704420Y8370D01*
X704520Y8230D01*
X704540Y8190D01*
X704555Y8155D01*
X704575Y8115D01*
X704590Y8075D01*
X704600Y8035D01*
X704615Y7990D01*
X704620Y7950D01*
X704630Y7910D01*
X704635Y7865D01*
Y7825D01*
X704640Y7780D01*
X704635Y7735D01*
Y7695D01*
X704630Y7650D01*
X704620Y7610D01*
X704615Y7570D01*
X704600Y7525D01*
X704590Y7485D01*
X704575Y7445D01*
X704555Y7405D01*
X704540Y7370D01*
X704520Y7330D01*
X704420Y7190D01*
X704390Y7160D01*
Y3730D01*
X704380Y3605D01*
X704340Y3480D01*
X704280Y3370D01*
X704200Y3270D01*
X704100Y3190D01*
X703990Y3130D01*
X703865Y3090D01*
X703740Y3080D01*
G37*
G36*
G01X699015D02*
X698890Y3090D01*
X698765Y3130D01*
X698655Y3190D01*
X698555Y3270D01*
X698475Y3370D01*
X698415Y3480D01*
X698375Y3605D01*
X698365Y3730D01*
Y7160D01*
X698335Y7190D01*
X698235Y7330D01*
X698215Y7370D01*
X698200Y7405D01*
X698180Y7445D01*
X698165Y7485D01*
X698155Y7525D01*
X698140Y7570D01*
X698135Y7610D01*
X698125Y7650D01*
X698120Y7695D01*
Y7735D01*
X698115Y7780D01*
X698120Y7825D01*
Y7865D01*
X698125Y7910D01*
X698135Y7950D01*
X698140Y7990D01*
X698155Y8035D01*
X698165Y8075D01*
X698180Y8115D01*
X698200Y8155D01*
X698215Y8190D01*
X698235Y8230D01*
X698335Y8370D01*
X698365Y8400D01*
Y9530D01*
X698375Y9655D01*
X698415Y9780D01*
X698475Y9890D01*
X698555Y9990D01*
X698655Y10070D01*
X698765Y10130D01*
X698890Y10170D01*
X699015Y10180D01*
X699140Y10170D01*
X699265Y10130D01*
X699375Y10070D01*
X699475Y9990D01*
X699555Y9890D01*
X699615Y9780D01*
X699655Y9655D01*
X699665Y9530D01*
Y8400D01*
X699695Y8370D01*
X699795Y8230D01*
X699815Y8190D01*
X699830Y8155D01*
X699850Y8115D01*
X699865Y8075D01*
X699875Y8035D01*
X699890Y7990D01*
X699895Y7950D01*
X699905Y7910D01*
X699910Y7865D01*
Y7825D01*
X699915Y7780D01*
X699910Y7735D01*
Y7695D01*
X699905Y7650D01*
X699895Y7610D01*
X699890Y7570D01*
X699875Y7525D01*
X699865Y7485D01*
X699850Y7445D01*
X699830Y7405D01*
X699815Y7370D01*
X699795Y7330D01*
X699695Y7190D01*
X699665Y7160D01*
Y3730D01*
X699655Y3605D01*
X699615Y3480D01*
X699555Y3370D01*
X699475Y3270D01*
X699375Y3190D01*
X699265Y3130D01*
X699140Y3090D01*
X699015Y3080D01*
G37*
G36*
G01X722638D02*
X722513Y3090D01*
X722388Y3130D01*
X722278Y3190D01*
X722178Y3270D01*
X722098Y3370D01*
X722038Y3480D01*
X721998Y3605D01*
X721988Y3730D01*
Y7160D01*
X721958Y7190D01*
X721858Y7330D01*
X721838Y7370D01*
X721823Y7405D01*
X721803Y7445D01*
X721788Y7485D01*
X721778Y7525D01*
X721763Y7570D01*
X721758Y7610D01*
X721748Y7650D01*
X721743Y7695D01*
Y7735D01*
X721738Y7780D01*
X721743Y7825D01*
Y7865D01*
X721748Y7910D01*
X721758Y7950D01*
X721763Y7990D01*
X721778Y8035D01*
X721788Y8075D01*
X721803Y8115D01*
X721823Y8155D01*
X721838Y8190D01*
X721858Y8230D01*
X721958Y8370D01*
X721988Y8400D01*
Y9530D01*
X721998Y9655D01*
X722038Y9780D01*
X722098Y9890D01*
X722178Y9990D01*
X722278Y10070D01*
X722388Y10130D01*
X722513Y10170D01*
X722638Y10180D01*
X722763Y10170D01*
X722888Y10130D01*
X722998Y10070D01*
X723098Y9990D01*
X723178Y9890D01*
X723238Y9780D01*
X723278Y9655D01*
X723288Y9530D01*
Y8400D01*
X723318Y8370D01*
X723418Y8230D01*
X723438Y8190D01*
X723453Y8155D01*
X723473Y8115D01*
X723488Y8075D01*
X723498Y8035D01*
X723513Y7990D01*
X723518Y7950D01*
X723528Y7910D01*
X723533Y7865D01*
Y7825D01*
X723538Y7780D01*
X723533Y7735D01*
Y7695D01*
X723528Y7650D01*
X723518Y7610D01*
X723513Y7570D01*
X723498Y7525D01*
X723488Y7485D01*
X723473Y7445D01*
X723453Y7405D01*
X723438Y7370D01*
X723418Y7330D01*
X723318Y7190D01*
X723288Y7160D01*
Y3730D01*
X723278Y3605D01*
X723238Y3480D01*
X723178Y3370D01*
X723098Y3270D01*
X722998Y3190D01*
X722888Y3130D01*
X722763Y3090D01*
X722638Y3080D01*
G37*
G36*
G01X717913D02*
X717788Y3090D01*
X717663Y3130D01*
X717553Y3190D01*
X717453Y3270D01*
X717373Y3370D01*
X717313Y3480D01*
X717273Y3605D01*
X717263Y3730D01*
Y7160D01*
X717233Y7190D01*
X717133Y7330D01*
X717113Y7370D01*
X717098Y7405D01*
X717078Y7445D01*
X717063Y7485D01*
X717053Y7525D01*
X717038Y7570D01*
X717033Y7610D01*
X717023Y7650D01*
X717018Y7695D01*
Y7735D01*
X717013Y7780D01*
X717018Y7825D01*
Y7865D01*
X717023Y7910D01*
X717033Y7950D01*
X717038Y7990D01*
X717053Y8035D01*
X717063Y8075D01*
X717078Y8115D01*
X717098Y8155D01*
X717113Y8190D01*
X717133Y8230D01*
X717233Y8370D01*
X717263Y8400D01*
Y9530D01*
X717273Y9655D01*
X717313Y9780D01*
X717373Y9890D01*
X717453Y9990D01*
X717553Y10070D01*
X717663Y10130D01*
X717788Y10170D01*
X717913Y10180D01*
X718038Y10170D01*
X718163Y10130D01*
X718273Y10070D01*
X718373Y9990D01*
X718453Y9890D01*
X718513Y9780D01*
X718553Y9655D01*
X718563Y9530D01*
Y8400D01*
X718593Y8370D01*
X718693Y8230D01*
X718713Y8190D01*
X718728Y8155D01*
X718748Y8115D01*
X718763Y8075D01*
X718773Y8035D01*
X718788Y7990D01*
X718793Y7950D01*
X718803Y7910D01*
X718808Y7865D01*
Y7825D01*
X718813Y7780D01*
X718808Y7735D01*
Y7695D01*
X718803Y7650D01*
X718793Y7610D01*
X718788Y7570D01*
X718773Y7525D01*
X718763Y7485D01*
X718748Y7445D01*
X718728Y7405D01*
X718713Y7370D01*
X718693Y7330D01*
X718593Y7190D01*
X718563Y7160D01*
Y3730D01*
X718553Y3605D01*
X718513Y3480D01*
X718453Y3370D01*
X718373Y3270D01*
X718273Y3190D01*
X718163Y3130D01*
X718038Y3090D01*
X717913Y3080D01*
G37*
G36*
G01X713189D02*
X713064Y3090D01*
X712939Y3130D01*
X712829Y3190D01*
X712729Y3270D01*
X712649Y3370D01*
X712589Y3480D01*
X712549Y3605D01*
X712539Y3730D01*
Y7160D01*
X712509Y7190D01*
X712409Y7330D01*
X712389Y7370D01*
X712374Y7405D01*
X712354Y7445D01*
X712339Y7485D01*
X712329Y7525D01*
X712314Y7570D01*
X712309Y7610D01*
X712299Y7650D01*
X712294Y7695D01*
Y7735D01*
X712289Y7780D01*
X712294Y7825D01*
Y7865D01*
X712299Y7910D01*
X712309Y7950D01*
X712314Y7990D01*
X712329Y8035D01*
X712339Y8075D01*
X712354Y8115D01*
X712374Y8155D01*
X712389Y8190D01*
X712409Y8230D01*
X712509Y8370D01*
X712539Y8400D01*
Y9530D01*
X712549Y9655D01*
X712589Y9780D01*
X712649Y9890D01*
X712729Y9990D01*
X712829Y10070D01*
X712939Y10130D01*
X713064Y10170D01*
X713189Y10180D01*
X713314Y10170D01*
X713439Y10130D01*
X713549Y10070D01*
X713649Y9990D01*
X713729Y9890D01*
X713789Y9780D01*
X713829Y9655D01*
X713839Y9530D01*
Y8400D01*
X713869Y8370D01*
X713969Y8230D01*
X713989Y8190D01*
X714004Y8155D01*
X714024Y8115D01*
X714039Y8075D01*
X714049Y8035D01*
X714064Y7990D01*
X714069Y7950D01*
X714079Y7910D01*
X714084Y7865D01*
Y7825D01*
X714089Y7780D01*
X714084Y7735D01*
Y7695D01*
X714079Y7650D01*
X714069Y7610D01*
X714064Y7570D01*
X714049Y7525D01*
X714039Y7485D01*
X714024Y7445D01*
X714004Y7405D01*
X713989Y7370D01*
X713969Y7330D01*
X713869Y7190D01*
X713839Y7160D01*
Y3730D01*
X713829Y3605D01*
X713789Y3480D01*
X713729Y3370D01*
X713649Y3270D01*
X713549Y3190D01*
X713439Y3130D01*
X713314Y3090D01*
X713189Y3080D01*
G37*
G36*
G01X741535D02*
X741410Y3090D01*
X741285Y3130D01*
X741175Y3190D01*
X741075Y3270D01*
X740995Y3370D01*
X740935Y3480D01*
X740895Y3605D01*
X740885Y3730D01*
Y7160D01*
X740855Y7190D01*
X740755Y7330D01*
X740735Y7370D01*
X740720Y7405D01*
X740700Y7445D01*
X740685Y7485D01*
X740675Y7525D01*
X740660Y7570D01*
X740655Y7610D01*
X740645Y7650D01*
X740640Y7695D01*
Y7735D01*
X740635Y7780D01*
X740640Y7825D01*
Y7865D01*
X740645Y7910D01*
X740655Y7950D01*
X740660Y7990D01*
X740675Y8035D01*
X740685Y8075D01*
X740700Y8115D01*
X740720Y8155D01*
X740735Y8190D01*
X740755Y8230D01*
X740855Y8370D01*
X740885Y8400D01*
Y9530D01*
X740895Y9655D01*
X740935Y9780D01*
X740995Y9890D01*
X741075Y9990D01*
X741175Y10070D01*
X741285Y10130D01*
X741410Y10170D01*
X741535Y10180D01*
X741660Y10170D01*
X741785Y10130D01*
X741895Y10070D01*
X741995Y9990D01*
X742075Y9890D01*
X742135Y9780D01*
X742175Y9655D01*
X742185Y9530D01*
Y8400D01*
X742215Y8370D01*
X742315Y8230D01*
X742335Y8190D01*
X742350Y8155D01*
X742370Y8115D01*
X742385Y8075D01*
X742395Y8035D01*
X742410Y7990D01*
X742415Y7950D01*
X742425Y7910D01*
X742430Y7865D01*
Y7825D01*
X742435Y7780D01*
X742430Y7735D01*
Y7695D01*
X742425Y7650D01*
X742415Y7610D01*
X742410Y7570D01*
X742395Y7525D01*
X742385Y7485D01*
X742370Y7445D01*
X742350Y7405D01*
X742335Y7370D01*
X742315Y7330D01*
X742215Y7190D01*
X742185Y7160D01*
Y3730D01*
X742175Y3605D01*
X742135Y3480D01*
X742075Y3370D01*
X741995Y3270D01*
X741895Y3190D01*
X741785Y3130D01*
X741660Y3090D01*
X741535Y3080D01*
G37*
G36*
G01X736811D02*
X736686Y3090D01*
X736561Y3130D01*
X736451Y3190D01*
X736351Y3270D01*
X736271Y3370D01*
X736211Y3480D01*
X736171Y3605D01*
X736161Y3730D01*
Y7160D01*
X736131Y7190D01*
X736031Y7330D01*
X736011Y7370D01*
X735996Y7405D01*
X735976Y7445D01*
X735961Y7485D01*
X735951Y7525D01*
X735936Y7570D01*
X735931Y7610D01*
X735921Y7650D01*
X735916Y7695D01*
Y7735D01*
X735911Y7780D01*
X735916Y7825D01*
Y7865D01*
X735921Y7910D01*
X735931Y7950D01*
X735936Y7990D01*
X735951Y8035D01*
X735961Y8075D01*
X735976Y8115D01*
X735996Y8155D01*
X736011Y8190D01*
X736031Y8230D01*
X736131Y8370D01*
X736161Y8400D01*
Y9530D01*
X736171Y9655D01*
X736211Y9780D01*
X736271Y9890D01*
X736351Y9990D01*
X736451Y10070D01*
X736561Y10130D01*
X736686Y10170D01*
X736811Y10180D01*
X736936Y10170D01*
X737061Y10130D01*
X737171Y10070D01*
X737271Y9990D01*
X737351Y9890D01*
X737411Y9780D01*
X737451Y9655D01*
X737461Y9530D01*
Y8400D01*
X737491Y8370D01*
X737591Y8230D01*
X737611Y8190D01*
X737626Y8155D01*
X737646Y8115D01*
X737661Y8075D01*
X737671Y8035D01*
X737686Y7990D01*
X737691Y7950D01*
X737701Y7910D01*
X737706Y7865D01*
Y7825D01*
X737711Y7780D01*
X737706Y7735D01*
Y7695D01*
X737701Y7650D01*
X737691Y7610D01*
X737686Y7570D01*
X737671Y7525D01*
X737661Y7485D01*
X737646Y7445D01*
X737626Y7405D01*
X737611Y7370D01*
X737591Y7330D01*
X737491Y7190D01*
X737461Y7160D01*
Y3730D01*
X737451Y3605D01*
X737411Y3480D01*
X737351Y3370D01*
X737271Y3270D01*
X737171Y3190D01*
X737061Y3130D01*
X736936Y3090D01*
X736811Y3080D01*
G37*
G36*
G01X732086D02*
X731961Y3090D01*
X731836Y3130D01*
X731726Y3190D01*
X731626Y3270D01*
X731546Y3370D01*
X731486Y3480D01*
X731446Y3605D01*
X731436Y3730D01*
Y7160D01*
X731406Y7190D01*
X731306Y7330D01*
X731286Y7370D01*
X731271Y7405D01*
X731251Y7445D01*
X731236Y7485D01*
X731226Y7525D01*
X731211Y7570D01*
X731206Y7610D01*
X731196Y7650D01*
X731191Y7695D01*
Y7735D01*
X731186Y7780D01*
X731191Y7825D01*
Y7865D01*
X731196Y7910D01*
X731206Y7950D01*
X731211Y7990D01*
X731226Y8035D01*
X731236Y8075D01*
X731251Y8115D01*
X731271Y8155D01*
X731286Y8190D01*
X731306Y8230D01*
X731406Y8370D01*
X731436Y8400D01*
Y9530D01*
X731446Y9655D01*
X731486Y9780D01*
X731546Y9890D01*
X731626Y9990D01*
X731726Y10070D01*
X731836Y10130D01*
X731961Y10170D01*
X732086Y10180D01*
X732211Y10170D01*
X732336Y10130D01*
X732446Y10070D01*
X732546Y9990D01*
X732626Y9890D01*
X732686Y9780D01*
X732726Y9655D01*
X732736Y9530D01*
Y8400D01*
X732766Y8370D01*
X732866Y8230D01*
X732886Y8190D01*
X732901Y8155D01*
X732921Y8115D01*
X732936Y8075D01*
X732946Y8035D01*
X732961Y7990D01*
X732966Y7950D01*
X732976Y7910D01*
X732981Y7865D01*
Y7825D01*
X732986Y7780D01*
X732981Y7735D01*
Y7695D01*
X732976Y7650D01*
X732966Y7610D01*
X732961Y7570D01*
X732946Y7525D01*
X732936Y7485D01*
X732921Y7445D01*
X732901Y7405D01*
X732886Y7370D01*
X732866Y7330D01*
X732766Y7190D01*
X732736Y7160D01*
Y3730D01*
X732726Y3605D01*
X732686Y3480D01*
X732626Y3370D01*
X732546Y3270D01*
X732446Y3190D01*
X732336Y3130D01*
X732211Y3090D01*
X732086Y3080D01*
G37*
G36*
G01X727362D02*
X727237Y3090D01*
X727112Y3130D01*
X727002Y3190D01*
X726902Y3270D01*
X726822Y3370D01*
X726762Y3480D01*
X726722Y3605D01*
X726712Y3730D01*
Y7160D01*
X726682Y7190D01*
X726582Y7330D01*
X726562Y7370D01*
X726547Y7405D01*
X726527Y7445D01*
X726512Y7485D01*
X726502Y7525D01*
X726487Y7570D01*
X726482Y7610D01*
X726472Y7650D01*
X726467Y7695D01*
Y7735D01*
X726462Y7780D01*
X726467Y7825D01*
Y7865D01*
X726472Y7910D01*
X726482Y7950D01*
X726487Y7990D01*
X726502Y8035D01*
X726512Y8075D01*
X726527Y8115D01*
X726547Y8155D01*
X726562Y8190D01*
X726582Y8230D01*
X726682Y8370D01*
X726712Y8400D01*
Y9530D01*
X726722Y9655D01*
X726762Y9780D01*
X726822Y9890D01*
X726902Y9990D01*
X727002Y10070D01*
X727112Y10130D01*
X727237Y10170D01*
X727362Y10180D01*
X727487Y10170D01*
X727612Y10130D01*
X727722Y10070D01*
X727822Y9990D01*
X727902Y9890D01*
X727962Y9780D01*
X728002Y9655D01*
X728012Y9530D01*
Y8400D01*
X728042Y8370D01*
X728142Y8230D01*
X728162Y8190D01*
X728177Y8155D01*
X728197Y8115D01*
X728212Y8075D01*
X728222Y8035D01*
X728237Y7990D01*
X728242Y7950D01*
X728252Y7910D01*
X728257Y7865D01*
Y7825D01*
X728262Y7780D01*
X728257Y7735D01*
Y7695D01*
X728252Y7650D01*
X728242Y7610D01*
X728237Y7570D01*
X728222Y7525D01*
X728212Y7485D01*
X728197Y7445D01*
X728177Y7405D01*
X728162Y7370D01*
X728142Y7330D01*
X728042Y7190D01*
X728012Y7160D01*
Y3730D01*
X728002Y3605D01*
X727962Y3480D01*
X727902Y3370D01*
X727822Y3270D01*
X727722Y3190D01*
X727612Y3130D01*
X727487Y3090D01*
X727362Y3080D01*
G37*
G36*
G01X750984D02*
X750859Y3090D01*
X750734Y3130D01*
X750624Y3190D01*
X750524Y3270D01*
X750444Y3370D01*
X750384Y3480D01*
X750344Y3605D01*
X750334Y3730D01*
Y7160D01*
X750304Y7190D01*
X750204Y7330D01*
X750184Y7370D01*
X750169Y7405D01*
X750149Y7445D01*
X750134Y7485D01*
X750124Y7525D01*
X750109Y7570D01*
X750104Y7610D01*
X750094Y7650D01*
X750089Y7695D01*
Y7735D01*
X750084Y7780D01*
X750089Y7825D01*
Y7865D01*
X750094Y7910D01*
X750104Y7950D01*
X750109Y7990D01*
X750124Y8035D01*
X750134Y8075D01*
X750149Y8115D01*
X750169Y8155D01*
X750184Y8190D01*
X750204Y8230D01*
X750304Y8370D01*
X750334Y8400D01*
Y9530D01*
X750344Y9655D01*
X750384Y9780D01*
X750444Y9890D01*
X750524Y9990D01*
X750624Y10070D01*
X750734Y10130D01*
X750859Y10170D01*
X750984Y10180D01*
X751109Y10170D01*
X751234Y10130D01*
X751344Y10070D01*
X751444Y9990D01*
X751524Y9890D01*
X751584Y9780D01*
X751624Y9655D01*
X751634Y9530D01*
Y8400D01*
X751664Y8370D01*
X751764Y8230D01*
X751784Y8190D01*
X751799Y8155D01*
X751819Y8115D01*
X751834Y8075D01*
X751844Y8035D01*
X751859Y7990D01*
X751864Y7950D01*
X751874Y7910D01*
X751879Y7865D01*
Y7825D01*
X751884Y7780D01*
X751879Y7735D01*
Y7695D01*
X751874Y7650D01*
X751864Y7610D01*
X751859Y7570D01*
X751844Y7525D01*
X751834Y7485D01*
X751819Y7445D01*
X751799Y7405D01*
X751784Y7370D01*
X751764Y7330D01*
X751664Y7190D01*
X751634Y7160D01*
Y3730D01*
X751624Y3605D01*
X751584Y3480D01*
X751524Y3370D01*
X751444Y3270D01*
X751344Y3190D01*
X751234Y3130D01*
X751109Y3090D01*
X750984Y3080D01*
G37*
G36*
G01X746260D02*
X746135Y3090D01*
X746010Y3130D01*
X745900Y3190D01*
X745800Y3270D01*
X745720Y3370D01*
X745660Y3480D01*
X745620Y3605D01*
X745610Y3730D01*
Y7160D01*
X745580Y7190D01*
X745480Y7330D01*
X745460Y7370D01*
X745445Y7405D01*
X745425Y7445D01*
X745410Y7485D01*
X745400Y7525D01*
X745385Y7570D01*
X745380Y7610D01*
X745370Y7650D01*
X745365Y7695D01*
Y7735D01*
X745360Y7780D01*
X745365Y7825D01*
Y7865D01*
X745370Y7910D01*
X745380Y7950D01*
X745385Y7990D01*
X745400Y8035D01*
X745410Y8075D01*
X745425Y8115D01*
X745445Y8155D01*
X745460Y8190D01*
X745480Y8230D01*
X745580Y8370D01*
X745610Y8400D01*
Y9530D01*
X745620Y9655D01*
X745660Y9780D01*
X745720Y9890D01*
X745800Y9990D01*
X745900Y10070D01*
X746010Y10130D01*
X746135Y10170D01*
X746260Y10180D01*
X746385Y10170D01*
X746510Y10130D01*
X746620Y10070D01*
X746720Y9990D01*
X746800Y9890D01*
X746860Y9780D01*
X746900Y9655D01*
X746910Y9530D01*
Y8400D01*
X746940Y8370D01*
X747040Y8230D01*
X747060Y8190D01*
X747075Y8155D01*
X747095Y8115D01*
X747110Y8075D01*
X747120Y8035D01*
X747135Y7990D01*
X747140Y7950D01*
X747150Y7910D01*
X747155Y7865D01*
Y7825D01*
X747160Y7780D01*
X747155Y7735D01*
Y7695D01*
X747150Y7650D01*
X747140Y7610D01*
X747135Y7570D01*
X747120Y7525D01*
X747110Y7485D01*
X747095Y7445D01*
X747075Y7405D01*
X747060Y7370D01*
X747040Y7330D01*
X746940Y7190D01*
X746910Y7160D01*
Y3730D01*
X746900Y3605D01*
X746860Y3480D01*
X746800Y3370D01*
X746720Y3270D01*
X746620Y3190D01*
X746510Y3130D01*
X746385Y3090D01*
X746260Y3080D01*
G37*
G54D110*
X535210Y218348D03*
Y220316D03*
Y222285D03*
Y224254D03*
Y226222D03*
X546710D03*
Y224254D03*
Y222285D03*
Y220316D03*
Y218348D03*
G36*
G01X508858Y35416D02*
X508733Y35426D01*
X508608Y35466D01*
X508498Y35526D01*
X508398Y35606D01*
X508318Y35706D01*
X508258Y35816D01*
X508218Y35941D01*
X508208Y36066D01*
Y38191D01*
X508178Y38221D01*
X508153Y38256D01*
X508123Y38291D01*
X508103Y38326D01*
X508078Y38361D01*
X508038Y38441D01*
X507993Y38561D01*
X507983Y38601D01*
X507973Y38646D01*
X507968Y38686D01*
X507958Y38731D01*
Y38901D01*
X507968Y38946D01*
X507973Y38986D01*
X507983Y39031D01*
X507993Y39071D01*
X508038Y39191D01*
X508078Y39271D01*
X508103Y39306D01*
X508123Y39341D01*
X508153Y39376D01*
X508178Y39411D01*
X508208Y39441D01*
Y41866D01*
X508218Y41991D01*
X508258Y42116D01*
X508318Y42226D01*
X508398Y42326D01*
X508498Y42406D01*
X508608Y42466D01*
X508733Y42506D01*
X508858Y42516D01*
X508983Y42506D01*
X509108Y42466D01*
X509218Y42406D01*
X509318Y42326D01*
X509398Y42226D01*
X509458Y42116D01*
X509498Y41991D01*
X509508Y41866D01*
Y39436D01*
X509538Y39406D01*
X509638Y39266D01*
X509658Y39226D01*
X509673Y39191D01*
X509693Y39151D01*
X509708Y39111D01*
X509718Y39071D01*
X509733Y39026D01*
X509738Y38986D01*
X509748Y38946D01*
X509753Y38901D01*
Y38861D01*
X509758Y38816D01*
X509753Y38771D01*
Y38731D01*
X509748Y38686D01*
X509738Y38646D01*
X509733Y38606D01*
X509718Y38561D01*
X509708Y38521D01*
X509693Y38481D01*
X509673Y38441D01*
X509658Y38406D01*
X509638Y38366D01*
X509538Y38226D01*
X509508Y38196D01*
Y36066D01*
X509498Y35941D01*
X509458Y35816D01*
X509398Y35706D01*
X509318Y35606D01*
X509218Y35526D01*
X509108Y35466D01*
X508983Y35426D01*
X508858Y35416D01*
G37*
G36*
G01X523031D02*
X522906Y35426D01*
X522781Y35466D01*
X522671Y35526D01*
X522571Y35606D01*
X522491Y35706D01*
X522431Y35816D01*
X522391Y35941D01*
X522381Y36066D01*
Y38191D01*
X522351Y38221D01*
X522326Y38256D01*
X522296Y38291D01*
X522276Y38326D01*
X522251Y38361D01*
X522211Y38441D01*
X522166Y38561D01*
X522156Y38601D01*
X522146Y38646D01*
X522141Y38686D01*
X522131Y38731D01*
Y38901D01*
X522141Y38946D01*
X522146Y38986D01*
X522156Y39031D01*
X522166Y39071D01*
X522211Y39191D01*
X522251Y39271D01*
X522276Y39306D01*
X522296Y39341D01*
X522326Y39376D01*
X522351Y39411D01*
X522381Y39441D01*
Y41866D01*
X522391Y41991D01*
X522431Y42116D01*
X522491Y42226D01*
X522571Y42326D01*
X522671Y42406D01*
X522781Y42466D01*
X522906Y42506D01*
X523031Y42516D01*
X523156Y42506D01*
X523281Y42466D01*
X523391Y42406D01*
X523491Y42326D01*
X523571Y42226D01*
X523631Y42116D01*
X523671Y41991D01*
X523681Y41866D01*
Y39436D01*
X523711Y39406D01*
X523811Y39266D01*
X523831Y39226D01*
X523846Y39191D01*
X523866Y39151D01*
X523881Y39111D01*
X523891Y39071D01*
X523906Y39026D01*
X523911Y38986D01*
X523921Y38946D01*
X523926Y38901D01*
Y38861D01*
X523931Y38816D01*
X523926Y38771D01*
Y38731D01*
X523921Y38686D01*
X523911Y38646D01*
X523906Y38606D01*
X523891Y38561D01*
X523881Y38521D01*
X523866Y38481D01*
X523846Y38441D01*
X523831Y38406D01*
X523811Y38366D01*
X523711Y38226D01*
X523681Y38196D01*
Y36066D01*
X523671Y35941D01*
X523631Y35816D01*
X523571Y35706D01*
X523491Y35606D01*
X523391Y35526D01*
X523281Y35466D01*
X523156Y35426D01*
X523031Y35416D01*
G37*
G36*
G01X518307D02*
X518182Y35426D01*
X518057Y35466D01*
X517947Y35526D01*
X517847Y35606D01*
X517767Y35706D01*
X517707Y35816D01*
X517667Y35941D01*
X517657Y36066D01*
Y38191D01*
X517627Y38221D01*
X517602Y38256D01*
X517572Y38291D01*
X517552Y38326D01*
X517527Y38361D01*
X517487Y38441D01*
X517442Y38561D01*
X517432Y38601D01*
X517422Y38646D01*
X517417Y38686D01*
X517407Y38731D01*
Y38901D01*
X517417Y38946D01*
X517422Y38986D01*
X517432Y39031D01*
X517442Y39071D01*
X517487Y39191D01*
X517527Y39271D01*
X517552Y39306D01*
X517572Y39341D01*
X517602Y39376D01*
X517627Y39411D01*
X517657Y39441D01*
Y41866D01*
X517667Y41991D01*
X517707Y42116D01*
X517767Y42226D01*
X517847Y42326D01*
X517947Y42406D01*
X518057Y42466D01*
X518182Y42506D01*
X518307Y42516D01*
X518432Y42506D01*
X518557Y42466D01*
X518667Y42406D01*
X518767Y42326D01*
X518847Y42226D01*
X518907Y42116D01*
X518947Y41991D01*
X518957Y41866D01*
Y39436D01*
X518987Y39406D01*
X519087Y39266D01*
X519107Y39226D01*
X519122Y39191D01*
X519142Y39151D01*
X519157Y39111D01*
X519167Y39071D01*
X519182Y39026D01*
X519187Y38986D01*
X519197Y38946D01*
X519202Y38901D01*
Y38861D01*
X519207Y38816D01*
X519202Y38771D01*
Y38731D01*
X519197Y38686D01*
X519187Y38646D01*
X519182Y38606D01*
X519167Y38561D01*
X519157Y38521D01*
X519142Y38481D01*
X519122Y38441D01*
X519107Y38406D01*
X519087Y38366D01*
X518987Y38226D01*
X518957Y38196D01*
Y36066D01*
X518947Y35941D01*
X518907Y35816D01*
X518847Y35706D01*
X518767Y35606D01*
X518667Y35526D01*
X518557Y35466D01*
X518432Y35426D01*
X518307Y35416D01*
G37*
G36*
G01X513582D02*
X513457Y35426D01*
X513332Y35466D01*
X513222Y35526D01*
X513122Y35606D01*
X513042Y35706D01*
X512982Y35816D01*
X512942Y35941D01*
X512932Y36066D01*
Y38191D01*
X512902Y38221D01*
X512877Y38256D01*
X512847Y38291D01*
X512827Y38326D01*
X512802Y38361D01*
X512762Y38441D01*
X512717Y38561D01*
X512707Y38601D01*
X512697Y38646D01*
X512692Y38686D01*
X512682Y38731D01*
Y38901D01*
X512692Y38946D01*
X512697Y38986D01*
X512707Y39031D01*
X512717Y39071D01*
X512762Y39191D01*
X512802Y39271D01*
X512827Y39306D01*
X512847Y39341D01*
X512877Y39376D01*
X512902Y39411D01*
X512932Y39441D01*
Y41866D01*
X512942Y41991D01*
X512982Y42116D01*
X513042Y42226D01*
X513122Y42326D01*
X513222Y42406D01*
X513332Y42466D01*
X513457Y42506D01*
X513582Y42516D01*
X513707Y42506D01*
X513832Y42466D01*
X513942Y42406D01*
X514042Y42326D01*
X514122Y42226D01*
X514182Y42116D01*
X514222Y41991D01*
X514232Y41866D01*
Y39436D01*
X514262Y39406D01*
X514362Y39266D01*
X514382Y39226D01*
X514397Y39191D01*
X514417Y39151D01*
X514432Y39111D01*
X514442Y39071D01*
X514457Y39026D01*
X514462Y38986D01*
X514472Y38946D01*
X514477Y38901D01*
Y38861D01*
X514482Y38816D01*
X514477Y38771D01*
Y38731D01*
X514472Y38686D01*
X514462Y38646D01*
X514457Y38606D01*
X514442Y38561D01*
X514432Y38521D01*
X514417Y38481D01*
X514397Y38441D01*
X514382Y38406D01*
X514362Y38366D01*
X514262Y38226D01*
X514232Y38196D01*
Y36066D01*
X514222Y35941D01*
X514182Y35816D01*
X514122Y35706D01*
X514042Y35606D01*
X513942Y35526D01*
X513832Y35466D01*
X513707Y35426D01*
X513582Y35416D01*
G37*
G36*
G01X541929D02*
X541804Y35426D01*
X541679Y35466D01*
X541569Y35526D01*
X541469Y35606D01*
X541389Y35706D01*
X541329Y35816D01*
X541289Y35941D01*
X541279Y36066D01*
Y38191D01*
X541249Y38221D01*
X541224Y38256D01*
X541194Y38291D01*
X541174Y38326D01*
X541149Y38361D01*
X541109Y38441D01*
X541064Y38561D01*
X541054Y38601D01*
X541044Y38646D01*
X541039Y38686D01*
X541029Y38731D01*
Y38901D01*
X541039Y38946D01*
X541044Y38986D01*
X541054Y39031D01*
X541064Y39071D01*
X541109Y39191D01*
X541149Y39271D01*
X541174Y39306D01*
X541194Y39341D01*
X541224Y39376D01*
X541249Y39411D01*
X541279Y39441D01*
Y41866D01*
X541289Y41991D01*
X541329Y42116D01*
X541389Y42226D01*
X541469Y42326D01*
X541569Y42406D01*
X541679Y42466D01*
X541804Y42506D01*
X541929Y42516D01*
X542054Y42506D01*
X542179Y42466D01*
X542289Y42406D01*
X542389Y42326D01*
X542469Y42226D01*
X542529Y42116D01*
X542569Y41991D01*
X542579Y41866D01*
Y39436D01*
X542609Y39406D01*
X542709Y39266D01*
X542729Y39226D01*
X542744Y39191D01*
X542764Y39151D01*
X542779Y39111D01*
X542789Y39071D01*
X542804Y39026D01*
X542809Y38986D01*
X542819Y38946D01*
X542824Y38901D01*
Y38861D01*
X542829Y38816D01*
X542824Y38771D01*
Y38731D01*
X542819Y38686D01*
X542809Y38646D01*
X542804Y38606D01*
X542789Y38561D01*
X542779Y38521D01*
X542764Y38481D01*
X542744Y38441D01*
X542729Y38406D01*
X542709Y38366D01*
X542609Y38226D01*
X542579Y38196D01*
Y36066D01*
X542569Y35941D01*
X542529Y35816D01*
X542469Y35706D01*
X542389Y35606D01*
X542289Y35526D01*
X542179Y35466D01*
X542054Y35426D01*
X541929Y35416D01*
G37*
G36*
G01X537204D02*
X537079Y35426D01*
X536954Y35466D01*
X536844Y35526D01*
X536744Y35606D01*
X536664Y35706D01*
X536604Y35816D01*
X536564Y35941D01*
X536554Y36066D01*
Y38191D01*
X536524Y38221D01*
X536499Y38256D01*
X536469Y38291D01*
X536449Y38326D01*
X536424Y38361D01*
X536384Y38441D01*
X536339Y38561D01*
X536329Y38601D01*
X536319Y38646D01*
X536314Y38686D01*
X536304Y38731D01*
Y38901D01*
X536314Y38946D01*
X536319Y38986D01*
X536329Y39031D01*
X536339Y39071D01*
X536384Y39191D01*
X536424Y39271D01*
X536449Y39306D01*
X536469Y39341D01*
X536499Y39376D01*
X536524Y39411D01*
X536554Y39441D01*
Y41866D01*
X536564Y41991D01*
X536604Y42116D01*
X536664Y42226D01*
X536744Y42326D01*
X536844Y42406D01*
X536954Y42466D01*
X537079Y42506D01*
X537204Y42516D01*
X537329Y42506D01*
X537454Y42466D01*
X537564Y42406D01*
X537664Y42326D01*
X537744Y42226D01*
X537804Y42116D01*
X537844Y41991D01*
X537854Y41866D01*
Y39436D01*
X537884Y39406D01*
X537984Y39266D01*
X538004Y39226D01*
X538019Y39191D01*
X538039Y39151D01*
X538054Y39111D01*
X538064Y39071D01*
X538079Y39026D01*
X538084Y38986D01*
X538094Y38946D01*
X538099Y38901D01*
Y38861D01*
X538104Y38816D01*
X538099Y38771D01*
Y38731D01*
X538094Y38686D01*
X538084Y38646D01*
X538079Y38606D01*
X538064Y38561D01*
X538054Y38521D01*
X538039Y38481D01*
X538019Y38441D01*
X538004Y38406D01*
X537984Y38366D01*
X537884Y38226D01*
X537854Y38196D01*
Y36066D01*
X537844Y35941D01*
X537804Y35816D01*
X537744Y35706D01*
X537664Y35606D01*
X537564Y35526D01*
X537454Y35466D01*
X537329Y35426D01*
X537204Y35416D01*
G37*
G36*
G01X532480D02*
X532355Y35426D01*
X532230Y35466D01*
X532120Y35526D01*
X532020Y35606D01*
X531940Y35706D01*
X531880Y35816D01*
X531840Y35941D01*
X531830Y36066D01*
Y38191D01*
X531800Y38221D01*
X531775Y38256D01*
X531745Y38291D01*
X531725Y38326D01*
X531700Y38361D01*
X531660Y38441D01*
X531615Y38561D01*
X531605Y38601D01*
X531595Y38646D01*
X531590Y38686D01*
X531580Y38731D01*
Y38901D01*
X531590Y38946D01*
X531595Y38986D01*
X531605Y39031D01*
X531615Y39071D01*
X531660Y39191D01*
X531700Y39271D01*
X531725Y39306D01*
X531745Y39341D01*
X531775Y39376D01*
X531800Y39411D01*
X531830Y39441D01*
Y41866D01*
X531840Y41991D01*
X531880Y42116D01*
X531940Y42226D01*
X532020Y42326D01*
X532120Y42406D01*
X532230Y42466D01*
X532355Y42506D01*
X532480Y42516D01*
X532605Y42506D01*
X532730Y42466D01*
X532840Y42406D01*
X532940Y42326D01*
X533020Y42226D01*
X533080Y42116D01*
X533120Y41991D01*
X533130Y41866D01*
Y39436D01*
X533160Y39406D01*
X533260Y39266D01*
X533280Y39226D01*
X533295Y39191D01*
X533315Y39151D01*
X533330Y39111D01*
X533340Y39071D01*
X533355Y39026D01*
X533360Y38986D01*
X533370Y38946D01*
X533375Y38901D01*
Y38861D01*
X533380Y38816D01*
X533375Y38771D01*
Y38731D01*
X533370Y38686D01*
X533360Y38646D01*
X533355Y38606D01*
X533340Y38561D01*
X533330Y38521D01*
X533315Y38481D01*
X533295Y38441D01*
X533280Y38406D01*
X533260Y38366D01*
X533160Y38226D01*
X533130Y38196D01*
Y36066D01*
X533120Y35941D01*
X533080Y35816D01*
X533020Y35706D01*
X532940Y35606D01*
X532840Y35526D01*
X532730Y35466D01*
X532605Y35426D01*
X532480Y35416D01*
G37*
G36*
G01X527756D02*
X527631Y35426D01*
X527506Y35466D01*
X527396Y35526D01*
X527296Y35606D01*
X527216Y35706D01*
X527156Y35816D01*
X527116Y35941D01*
X527106Y36066D01*
Y38191D01*
X527076Y38221D01*
X527051Y38256D01*
X527021Y38291D01*
X527001Y38326D01*
X526976Y38361D01*
X526936Y38441D01*
X526891Y38561D01*
X526881Y38601D01*
X526871Y38646D01*
X526866Y38686D01*
X526856Y38731D01*
Y38901D01*
X526866Y38946D01*
X526871Y38986D01*
X526881Y39031D01*
X526891Y39071D01*
X526936Y39191D01*
X526976Y39271D01*
X527001Y39306D01*
X527021Y39341D01*
X527051Y39376D01*
X527076Y39411D01*
X527106Y39441D01*
Y41866D01*
X527116Y41991D01*
X527156Y42116D01*
X527216Y42226D01*
X527296Y42326D01*
X527396Y42406D01*
X527506Y42466D01*
X527631Y42506D01*
X527756Y42516D01*
X527881Y42506D01*
X528006Y42466D01*
X528116Y42406D01*
X528216Y42326D01*
X528296Y42226D01*
X528356Y42116D01*
X528396Y41991D01*
X528406Y41866D01*
Y39436D01*
X528436Y39406D01*
X528536Y39266D01*
X528556Y39226D01*
X528571Y39191D01*
X528591Y39151D01*
X528606Y39111D01*
X528616Y39071D01*
X528631Y39026D01*
X528636Y38986D01*
X528646Y38946D01*
X528651Y38901D01*
Y38861D01*
X528656Y38816D01*
X528651Y38771D01*
Y38731D01*
X528646Y38686D01*
X528636Y38646D01*
X528631Y38606D01*
X528616Y38561D01*
X528606Y38521D01*
X528591Y38481D01*
X528571Y38441D01*
X528556Y38406D01*
X528536Y38366D01*
X528436Y38226D01*
X528406Y38196D01*
Y36066D01*
X528396Y35941D01*
X528356Y35816D01*
X528296Y35706D01*
X528216Y35606D01*
X528116Y35526D01*
X528006Y35466D01*
X527881Y35426D01*
X527756Y35416D01*
G37*
G36*
G01X556102D02*
X555977Y35426D01*
X555852Y35466D01*
X555742Y35526D01*
X555642Y35606D01*
X555562Y35706D01*
X555502Y35816D01*
X555462Y35941D01*
X555452Y36066D01*
Y38191D01*
X555422Y38221D01*
X555397Y38256D01*
X555367Y38291D01*
X555347Y38326D01*
X555322Y38361D01*
X555282Y38441D01*
X555237Y38561D01*
X555227Y38601D01*
X555217Y38646D01*
X555212Y38686D01*
X555202Y38731D01*
Y38901D01*
X555212Y38946D01*
X555217Y38986D01*
X555227Y39031D01*
X555237Y39071D01*
X555282Y39191D01*
X555322Y39271D01*
X555347Y39306D01*
X555367Y39341D01*
X555397Y39376D01*
X555422Y39411D01*
X555452Y39441D01*
Y41866D01*
X555462Y41991D01*
X555502Y42116D01*
X555562Y42226D01*
X555642Y42326D01*
X555742Y42406D01*
X555852Y42466D01*
X555977Y42506D01*
X556102Y42516D01*
X556227Y42506D01*
X556352Y42466D01*
X556462Y42406D01*
X556562Y42326D01*
X556642Y42226D01*
X556702Y42116D01*
X556742Y41991D01*
X556752Y41866D01*
Y39436D01*
X556782Y39406D01*
X556882Y39266D01*
X556902Y39226D01*
X556917Y39191D01*
X556937Y39151D01*
X556952Y39111D01*
X556962Y39071D01*
X556977Y39026D01*
X556982Y38986D01*
X556992Y38946D01*
X556997Y38901D01*
Y38861D01*
X557002Y38816D01*
X556997Y38771D01*
Y38731D01*
X556992Y38686D01*
X556982Y38646D01*
X556977Y38606D01*
X556962Y38561D01*
X556952Y38521D01*
X556937Y38481D01*
X556917Y38441D01*
X556902Y38406D01*
X556882Y38366D01*
X556782Y38226D01*
X556752Y38196D01*
Y36066D01*
X556742Y35941D01*
X556702Y35816D01*
X556642Y35706D01*
X556562Y35606D01*
X556462Y35526D01*
X556352Y35466D01*
X556227Y35426D01*
X556102Y35416D01*
G37*
G36*
G01X551378D02*
X551253Y35426D01*
X551128Y35466D01*
X551018Y35526D01*
X550918Y35606D01*
X550838Y35706D01*
X550778Y35816D01*
X550738Y35941D01*
X550728Y36066D01*
Y38191D01*
X550698Y38221D01*
X550673Y38256D01*
X550643Y38291D01*
X550623Y38326D01*
X550598Y38361D01*
X550558Y38441D01*
X550513Y38561D01*
X550503Y38601D01*
X550493Y38646D01*
X550488Y38686D01*
X550478Y38731D01*
Y38901D01*
X550488Y38946D01*
X550493Y38986D01*
X550503Y39031D01*
X550513Y39071D01*
X550558Y39191D01*
X550598Y39271D01*
X550623Y39306D01*
X550643Y39341D01*
X550673Y39376D01*
X550698Y39411D01*
X550728Y39441D01*
Y41866D01*
X550738Y41991D01*
X550778Y42116D01*
X550838Y42226D01*
X550918Y42326D01*
X551018Y42406D01*
X551128Y42466D01*
X551253Y42506D01*
X551378Y42516D01*
X551503Y42506D01*
X551628Y42466D01*
X551738Y42406D01*
X551838Y42326D01*
X551918Y42226D01*
X551978Y42116D01*
X552018Y41991D01*
X552028Y41866D01*
Y39436D01*
X552058Y39406D01*
X552158Y39266D01*
X552178Y39226D01*
X552193Y39191D01*
X552213Y39151D01*
X552228Y39111D01*
X552238Y39071D01*
X552253Y39026D01*
X552258Y38986D01*
X552268Y38946D01*
X552273Y38901D01*
Y38861D01*
X552278Y38816D01*
X552273Y38771D01*
Y38731D01*
X552268Y38686D01*
X552258Y38646D01*
X552253Y38606D01*
X552238Y38561D01*
X552228Y38521D01*
X552213Y38481D01*
X552193Y38441D01*
X552178Y38406D01*
X552158Y38366D01*
X552058Y38226D01*
X552028Y38196D01*
Y36066D01*
X552018Y35941D01*
X551978Y35816D01*
X551918Y35706D01*
X551838Y35606D01*
X551738Y35526D01*
X551628Y35466D01*
X551503Y35426D01*
X551378Y35416D01*
G37*
G36*
G01X546653D02*
X546528Y35426D01*
X546403Y35466D01*
X546293Y35526D01*
X546193Y35606D01*
X546113Y35706D01*
X546053Y35816D01*
X546013Y35941D01*
X546003Y36066D01*
Y38191D01*
X545973Y38221D01*
X545948Y38256D01*
X545918Y38291D01*
X545898Y38326D01*
X545873Y38361D01*
X545833Y38441D01*
X545788Y38561D01*
X545778Y38601D01*
X545768Y38646D01*
X545763Y38686D01*
X545753Y38731D01*
Y38901D01*
X545763Y38946D01*
X545768Y38986D01*
X545778Y39031D01*
X545788Y39071D01*
X545833Y39191D01*
X545873Y39271D01*
X545898Y39306D01*
X545918Y39341D01*
X545948Y39376D01*
X545973Y39411D01*
X546003Y39441D01*
Y41866D01*
X546013Y41991D01*
X546053Y42116D01*
X546113Y42226D01*
X546193Y42326D01*
X546293Y42406D01*
X546403Y42466D01*
X546528Y42506D01*
X546653Y42516D01*
X546778Y42506D01*
X546903Y42466D01*
X547013Y42406D01*
X547113Y42326D01*
X547193Y42226D01*
X547253Y42116D01*
X547293Y41991D01*
X547303Y41866D01*
Y39436D01*
X547333Y39406D01*
X547433Y39266D01*
X547453Y39226D01*
X547468Y39191D01*
X547488Y39151D01*
X547503Y39111D01*
X547513Y39071D01*
X547528Y39026D01*
X547533Y38986D01*
X547543Y38946D01*
X547548Y38901D01*
Y38861D01*
X547553Y38816D01*
X547548Y38771D01*
Y38731D01*
X547543Y38686D01*
X547533Y38646D01*
X547528Y38606D01*
X547513Y38561D01*
X547503Y38521D01*
X547488Y38481D01*
X547468Y38441D01*
X547453Y38406D01*
X547433Y38366D01*
X547333Y38226D01*
X547303Y38196D01*
Y36066D01*
X547293Y35941D01*
X547253Y35816D01*
X547193Y35706D01*
X547113Y35606D01*
X547013Y35526D01*
X546903Y35466D01*
X546778Y35426D01*
X546653Y35416D01*
G37*
G36*
G01X570275D02*
X570150Y35426D01*
X570025Y35466D01*
X569915Y35526D01*
X569815Y35606D01*
X569735Y35706D01*
X569675Y35816D01*
X569635Y35941D01*
X569625Y36066D01*
Y38191D01*
X569595Y38221D01*
X569570Y38256D01*
X569540Y38291D01*
X569520Y38326D01*
X569495Y38361D01*
X569455Y38441D01*
X569410Y38561D01*
X569400Y38601D01*
X569390Y38646D01*
X569385Y38686D01*
X569375Y38731D01*
Y38901D01*
X569385Y38946D01*
X569390Y38986D01*
X569400Y39031D01*
X569410Y39071D01*
X569455Y39191D01*
X569495Y39271D01*
X569520Y39306D01*
X569540Y39341D01*
X569570Y39376D01*
X569595Y39411D01*
X569625Y39441D01*
Y41866D01*
X569635Y41991D01*
X569675Y42116D01*
X569735Y42226D01*
X569815Y42326D01*
X569915Y42406D01*
X570025Y42466D01*
X570150Y42506D01*
X570275Y42516D01*
X570400Y42506D01*
X570525Y42466D01*
X570635Y42406D01*
X570735Y42326D01*
X570815Y42226D01*
X570875Y42116D01*
X570915Y41991D01*
X570925Y41866D01*
Y39436D01*
X570955Y39406D01*
X571055Y39266D01*
X571075Y39226D01*
X571090Y39191D01*
X571110Y39151D01*
X571125Y39111D01*
X571135Y39071D01*
X571150Y39026D01*
X571155Y38986D01*
X571165Y38946D01*
X571170Y38901D01*
Y38861D01*
X571175Y38816D01*
X571170Y38771D01*
Y38731D01*
X571165Y38686D01*
X571155Y38646D01*
X571150Y38606D01*
X571135Y38561D01*
X571125Y38521D01*
X571110Y38481D01*
X571090Y38441D01*
X571075Y38406D01*
X571055Y38366D01*
X570955Y38226D01*
X570925Y38196D01*
Y36066D01*
X570915Y35941D01*
X570875Y35816D01*
X570815Y35706D01*
X570735Y35606D01*
X570635Y35526D01*
X570525Y35466D01*
X570400Y35426D01*
X570275Y35416D01*
G37*
G36*
G01X565551D02*
X565426Y35426D01*
X565301Y35466D01*
X565191Y35526D01*
X565091Y35606D01*
X565011Y35706D01*
X564951Y35816D01*
X564911Y35941D01*
X564901Y36066D01*
Y38191D01*
X564871Y38221D01*
X564846Y38256D01*
X564816Y38291D01*
X564796Y38326D01*
X564771Y38361D01*
X564731Y38441D01*
X564686Y38561D01*
X564676Y38601D01*
X564666Y38646D01*
X564661Y38686D01*
X564651Y38731D01*
Y38901D01*
X564661Y38946D01*
X564666Y38986D01*
X564676Y39031D01*
X564686Y39071D01*
X564731Y39191D01*
X564771Y39271D01*
X564796Y39306D01*
X564816Y39341D01*
X564846Y39376D01*
X564871Y39411D01*
X564901Y39441D01*
Y41866D01*
X564911Y41991D01*
X564951Y42116D01*
X565011Y42226D01*
X565091Y42326D01*
X565191Y42406D01*
X565301Y42466D01*
X565426Y42506D01*
X565551Y42516D01*
X565676Y42506D01*
X565801Y42466D01*
X565911Y42406D01*
X566011Y42326D01*
X566091Y42226D01*
X566151Y42116D01*
X566191Y41991D01*
X566201Y41866D01*
Y39436D01*
X566231Y39406D01*
X566331Y39266D01*
X566351Y39226D01*
X566366Y39191D01*
X566386Y39151D01*
X566401Y39111D01*
X566411Y39071D01*
X566426Y39026D01*
X566431Y38986D01*
X566441Y38946D01*
X566446Y38901D01*
Y38861D01*
X566451Y38816D01*
X566446Y38771D01*
Y38731D01*
X566441Y38686D01*
X566431Y38646D01*
X566426Y38606D01*
X566411Y38561D01*
X566401Y38521D01*
X566386Y38481D01*
X566366Y38441D01*
X566351Y38406D01*
X566331Y38366D01*
X566231Y38226D01*
X566201Y38196D01*
Y36066D01*
X566191Y35941D01*
X566151Y35816D01*
X566091Y35706D01*
X566011Y35606D01*
X565911Y35526D01*
X565801Y35466D01*
X565676Y35426D01*
X565551Y35416D01*
G37*
G36*
G01X560827D02*
X560702Y35426D01*
X560577Y35466D01*
X560467Y35526D01*
X560367Y35606D01*
X560287Y35706D01*
X560227Y35816D01*
X560187Y35941D01*
X560177Y36066D01*
Y38191D01*
X560147Y38221D01*
X560122Y38256D01*
X560092Y38291D01*
X560072Y38326D01*
X560047Y38361D01*
X560007Y38441D01*
X559962Y38561D01*
X559952Y38601D01*
X559942Y38646D01*
X559937Y38686D01*
X559927Y38731D01*
Y38901D01*
X559937Y38946D01*
X559942Y38986D01*
X559952Y39031D01*
X559962Y39071D01*
X560007Y39191D01*
X560047Y39271D01*
X560072Y39306D01*
X560092Y39341D01*
X560122Y39376D01*
X560147Y39411D01*
X560177Y39441D01*
Y41866D01*
X560187Y41991D01*
X560227Y42116D01*
X560287Y42226D01*
X560367Y42326D01*
X560467Y42406D01*
X560577Y42466D01*
X560702Y42506D01*
X560827Y42516D01*
X560952Y42506D01*
X561077Y42466D01*
X561187Y42406D01*
X561287Y42326D01*
X561367Y42226D01*
X561427Y42116D01*
X561467Y41991D01*
X561477Y41866D01*
Y39436D01*
X561507Y39406D01*
X561607Y39266D01*
X561627Y39226D01*
X561642Y39191D01*
X561662Y39151D01*
X561677Y39111D01*
X561687Y39071D01*
X561702Y39026D01*
X561707Y38986D01*
X561717Y38946D01*
X561722Y38901D01*
Y38861D01*
X561727Y38816D01*
X561722Y38771D01*
Y38731D01*
X561717Y38686D01*
X561707Y38646D01*
X561702Y38606D01*
X561687Y38561D01*
X561677Y38521D01*
X561662Y38481D01*
X561642Y38441D01*
X561627Y38406D01*
X561607Y38366D01*
X561507Y38226D01*
X561477Y38196D01*
Y36066D01*
X561467Y35941D01*
X561427Y35816D01*
X561367Y35706D01*
X561287Y35606D01*
X561187Y35526D01*
X561077Y35466D01*
X560952Y35426D01*
X560827Y35416D01*
G37*
G36*
G01X584449D02*
X584324Y35426D01*
X584199Y35466D01*
X584089Y35526D01*
X583989Y35606D01*
X583909Y35706D01*
X583849Y35816D01*
X583809Y35941D01*
X583799Y36066D01*
Y38191D01*
X583769Y38221D01*
X583744Y38256D01*
X583714Y38291D01*
X583694Y38326D01*
X583669Y38361D01*
X583629Y38441D01*
X583584Y38561D01*
X583574Y38601D01*
X583564Y38646D01*
X583559Y38686D01*
X583549Y38731D01*
Y38901D01*
X583559Y38946D01*
X583564Y38986D01*
X583574Y39031D01*
X583584Y39071D01*
X583629Y39191D01*
X583669Y39271D01*
X583694Y39306D01*
X583714Y39341D01*
X583744Y39376D01*
X583769Y39411D01*
X583799Y39441D01*
Y41866D01*
X583809Y41991D01*
X583849Y42116D01*
X583909Y42226D01*
X583989Y42326D01*
X584089Y42406D01*
X584199Y42466D01*
X584324Y42506D01*
X584449Y42516D01*
X584574Y42506D01*
X584699Y42466D01*
X584809Y42406D01*
X584909Y42326D01*
X584989Y42226D01*
X585049Y42116D01*
X585089Y41991D01*
X585099Y41866D01*
Y39436D01*
X585129Y39406D01*
X585229Y39266D01*
X585249Y39226D01*
X585264Y39191D01*
X585284Y39151D01*
X585299Y39111D01*
X585309Y39071D01*
X585324Y39026D01*
X585329Y38986D01*
X585339Y38946D01*
X585344Y38901D01*
Y38861D01*
X585349Y38816D01*
X585344Y38771D01*
Y38731D01*
X585339Y38686D01*
X585329Y38646D01*
X585324Y38606D01*
X585309Y38561D01*
X585299Y38521D01*
X585284Y38481D01*
X585264Y38441D01*
X585249Y38406D01*
X585229Y38366D01*
X585129Y38226D01*
X585099Y38196D01*
Y36066D01*
X585089Y35941D01*
X585049Y35816D01*
X584989Y35706D01*
X584909Y35606D01*
X584809Y35526D01*
X584699Y35466D01*
X584574Y35426D01*
X584449Y35416D01*
G37*
G36*
G01X579724D02*
X579599Y35426D01*
X579474Y35466D01*
X579364Y35526D01*
X579264Y35606D01*
X579184Y35706D01*
X579124Y35816D01*
X579084Y35941D01*
X579074Y36066D01*
Y38191D01*
X579044Y38221D01*
X579019Y38256D01*
X578989Y38291D01*
X578969Y38326D01*
X578944Y38361D01*
X578904Y38441D01*
X578859Y38561D01*
X578849Y38601D01*
X578839Y38646D01*
X578834Y38686D01*
X578824Y38731D01*
Y38901D01*
X578834Y38946D01*
X578839Y38986D01*
X578849Y39031D01*
X578859Y39071D01*
X578904Y39191D01*
X578944Y39271D01*
X578969Y39306D01*
X578989Y39341D01*
X579019Y39376D01*
X579044Y39411D01*
X579074Y39441D01*
Y41866D01*
X579084Y41991D01*
X579124Y42116D01*
X579184Y42226D01*
X579264Y42326D01*
X579364Y42406D01*
X579474Y42466D01*
X579599Y42506D01*
X579724Y42516D01*
X579849Y42506D01*
X579974Y42466D01*
X580084Y42406D01*
X580184Y42326D01*
X580264Y42226D01*
X580324Y42116D01*
X580364Y41991D01*
X580374Y41866D01*
Y39436D01*
X580404Y39406D01*
X580504Y39266D01*
X580524Y39226D01*
X580539Y39191D01*
X580559Y39151D01*
X580574Y39111D01*
X580584Y39071D01*
X580599Y39026D01*
X580604Y38986D01*
X580614Y38946D01*
X580619Y38901D01*
Y38861D01*
X580624Y38816D01*
X580619Y38771D01*
Y38731D01*
X580614Y38686D01*
X580604Y38646D01*
X580599Y38606D01*
X580584Y38561D01*
X580574Y38521D01*
X580559Y38481D01*
X580539Y38441D01*
X580524Y38406D01*
X580504Y38366D01*
X580404Y38226D01*
X580374Y38196D01*
Y36066D01*
X580364Y35941D01*
X580324Y35816D01*
X580264Y35706D01*
X580184Y35606D01*
X580084Y35526D01*
X579974Y35466D01*
X579849Y35426D01*
X579724Y35416D01*
G37*
G36*
G01X575000D02*
X574875Y35426D01*
X574750Y35466D01*
X574640Y35526D01*
X574540Y35606D01*
X574460Y35706D01*
X574400Y35816D01*
X574360Y35941D01*
X574350Y36066D01*
Y38191D01*
X574320Y38221D01*
X574295Y38256D01*
X574265Y38291D01*
X574245Y38326D01*
X574220Y38361D01*
X574180Y38441D01*
X574135Y38561D01*
X574125Y38601D01*
X574115Y38646D01*
X574110Y38686D01*
X574100Y38731D01*
Y38901D01*
X574110Y38946D01*
X574115Y38986D01*
X574125Y39031D01*
X574135Y39071D01*
X574180Y39191D01*
X574220Y39271D01*
X574245Y39306D01*
X574265Y39341D01*
X574295Y39376D01*
X574320Y39411D01*
X574350Y39441D01*
Y41866D01*
X574360Y41991D01*
X574400Y42116D01*
X574460Y42226D01*
X574540Y42326D01*
X574640Y42406D01*
X574750Y42466D01*
X574875Y42506D01*
X575000Y42516D01*
X575125Y42506D01*
X575250Y42466D01*
X575360Y42406D01*
X575460Y42326D01*
X575540Y42226D01*
X575600Y42116D01*
X575640Y41991D01*
X575650Y41866D01*
Y39436D01*
X575680Y39406D01*
X575780Y39266D01*
X575800Y39226D01*
X575815Y39191D01*
X575835Y39151D01*
X575850Y39111D01*
X575860Y39071D01*
X575875Y39026D01*
X575880Y38986D01*
X575890Y38946D01*
X575895Y38901D01*
Y38861D01*
X575900Y38816D01*
X575895Y38771D01*
Y38731D01*
X575890Y38686D01*
X575880Y38646D01*
X575875Y38606D01*
X575860Y38561D01*
X575850Y38521D01*
X575835Y38481D01*
X575815Y38441D01*
X575800Y38406D01*
X575780Y38366D01*
X575680Y38226D01*
X575650Y38196D01*
Y36066D01*
X575640Y35941D01*
X575600Y35816D01*
X575540Y35706D01*
X575460Y35606D01*
X575360Y35526D01*
X575250Y35466D01*
X575125Y35426D01*
X575000Y35416D01*
G37*
G36*
G01X603346D02*
X603221Y35426D01*
X603096Y35466D01*
X602986Y35526D01*
X602886Y35606D01*
X602806Y35706D01*
X602746Y35816D01*
X602706Y35941D01*
X602696Y36066D01*
Y38191D01*
X602666Y38221D01*
X602641Y38256D01*
X602611Y38291D01*
X602591Y38326D01*
X602566Y38361D01*
X602526Y38441D01*
X602481Y38561D01*
X602471Y38601D01*
X602461Y38646D01*
X602456Y38686D01*
X602446Y38731D01*
Y38901D01*
X602456Y38946D01*
X602461Y38986D01*
X602471Y39031D01*
X602481Y39071D01*
X602526Y39191D01*
X602566Y39271D01*
X602591Y39306D01*
X602611Y39341D01*
X602641Y39376D01*
X602666Y39411D01*
X602696Y39441D01*
Y41866D01*
X602706Y41991D01*
X602746Y42116D01*
X602806Y42226D01*
X602886Y42326D01*
X602986Y42406D01*
X603096Y42466D01*
X603221Y42506D01*
X603346Y42516D01*
X603471Y42506D01*
X603596Y42466D01*
X603706Y42406D01*
X603806Y42326D01*
X603886Y42226D01*
X603946Y42116D01*
X603986Y41991D01*
X603996Y41866D01*
Y39436D01*
X604026Y39406D01*
X604126Y39266D01*
X604146Y39226D01*
X604161Y39191D01*
X604181Y39151D01*
X604196Y39111D01*
X604206Y39071D01*
X604221Y39026D01*
X604226Y38986D01*
X604236Y38946D01*
X604241Y38901D01*
Y38861D01*
X604246Y38816D01*
X604241Y38771D01*
Y38731D01*
X604236Y38686D01*
X604226Y38646D01*
X604221Y38606D01*
X604206Y38561D01*
X604196Y38521D01*
X604181Y38481D01*
X604161Y38441D01*
X604146Y38406D01*
X604126Y38366D01*
X604026Y38226D01*
X603996Y38196D01*
Y36066D01*
X603986Y35941D01*
X603946Y35816D01*
X603886Y35706D01*
X603806Y35606D01*
X603706Y35526D01*
X603596Y35466D01*
X603471Y35426D01*
X603346Y35416D01*
G37*
G36*
G01X589173D02*
X589048Y35426D01*
X588923Y35466D01*
X588813Y35526D01*
X588713Y35606D01*
X588633Y35706D01*
X588573Y35816D01*
X588533Y35941D01*
X588523Y36066D01*
Y38191D01*
X588493Y38221D01*
X588468Y38256D01*
X588438Y38291D01*
X588418Y38326D01*
X588393Y38361D01*
X588353Y38441D01*
X588308Y38561D01*
X588298Y38601D01*
X588288Y38646D01*
X588283Y38686D01*
X588273Y38731D01*
Y38901D01*
X588283Y38946D01*
X588288Y38986D01*
X588298Y39031D01*
X588308Y39071D01*
X588353Y39191D01*
X588393Y39271D01*
X588418Y39306D01*
X588438Y39341D01*
X588468Y39376D01*
X588493Y39411D01*
X588523Y39441D01*
Y41866D01*
X588533Y41991D01*
X588573Y42116D01*
X588633Y42226D01*
X588713Y42326D01*
X588813Y42406D01*
X588923Y42466D01*
X589048Y42506D01*
X589173Y42516D01*
X589298Y42506D01*
X589423Y42466D01*
X589533Y42406D01*
X589633Y42326D01*
X589713Y42226D01*
X589773Y42116D01*
X589813Y41991D01*
X589823Y41866D01*
Y39436D01*
X589853Y39406D01*
X589953Y39266D01*
X589973Y39226D01*
X589988Y39191D01*
X590008Y39151D01*
X590023Y39111D01*
X590033Y39071D01*
X590048Y39026D01*
X590053Y38986D01*
X590063Y38946D01*
X590068Y38901D01*
Y38861D01*
X590073Y38816D01*
X590068Y38771D01*
Y38731D01*
X590063Y38686D01*
X590053Y38646D01*
X590048Y38606D01*
X590033Y38561D01*
X590023Y38521D01*
X590008Y38481D01*
X589988Y38441D01*
X589973Y38406D01*
X589953Y38366D01*
X589853Y38226D01*
X589823Y38196D01*
Y36066D01*
X589813Y35941D01*
X589773Y35816D01*
X589713Y35706D01*
X589633Y35606D01*
X589533Y35526D01*
X589423Y35466D01*
X589298Y35426D01*
X589173Y35416D01*
G37*
G36*
G01X617519D02*
X617394Y35426D01*
X617269Y35466D01*
X617159Y35526D01*
X617059Y35606D01*
X616979Y35706D01*
X616919Y35816D01*
X616879Y35941D01*
X616869Y36066D01*
Y38191D01*
X616839Y38221D01*
X616814Y38256D01*
X616784Y38291D01*
X616764Y38326D01*
X616739Y38361D01*
X616699Y38441D01*
X616654Y38561D01*
X616644Y38601D01*
X616634Y38646D01*
X616629Y38686D01*
X616619Y38731D01*
Y38901D01*
X616629Y38946D01*
X616634Y38986D01*
X616644Y39031D01*
X616654Y39071D01*
X616699Y39191D01*
X616739Y39271D01*
X616764Y39306D01*
X616784Y39341D01*
X616814Y39376D01*
X616839Y39411D01*
X616869Y39441D01*
Y41866D01*
X616879Y41991D01*
X616919Y42116D01*
X616979Y42226D01*
X617059Y42326D01*
X617159Y42406D01*
X617269Y42466D01*
X617394Y42506D01*
X617519Y42516D01*
X617644Y42506D01*
X617769Y42466D01*
X617879Y42406D01*
X617979Y42326D01*
X618059Y42226D01*
X618119Y42116D01*
X618159Y41991D01*
X618169Y41866D01*
Y39436D01*
X618199Y39406D01*
X618299Y39266D01*
X618319Y39226D01*
X618334Y39191D01*
X618354Y39151D01*
X618369Y39111D01*
X618379Y39071D01*
X618394Y39026D01*
X618399Y38986D01*
X618409Y38946D01*
X618414Y38901D01*
Y38861D01*
X618419Y38816D01*
X618414Y38771D01*
Y38731D01*
X618409Y38686D01*
X618399Y38646D01*
X618394Y38606D01*
X618379Y38561D01*
X618369Y38521D01*
X618354Y38481D01*
X618334Y38441D01*
X618319Y38406D01*
X618299Y38366D01*
X618199Y38226D01*
X618169Y38196D01*
Y36066D01*
X618159Y35941D01*
X618119Y35816D01*
X618059Y35706D01*
X617979Y35606D01*
X617879Y35526D01*
X617769Y35466D01*
X617644Y35426D01*
X617519Y35416D01*
G37*
G36*
G01X612795D02*
X612670Y35426D01*
X612545Y35466D01*
X612435Y35526D01*
X612335Y35606D01*
X612255Y35706D01*
X612195Y35816D01*
X612155Y35941D01*
X612145Y36066D01*
Y38191D01*
X612115Y38221D01*
X612090Y38256D01*
X612060Y38291D01*
X612040Y38326D01*
X612015Y38361D01*
X611975Y38441D01*
X611930Y38561D01*
X611920Y38601D01*
X611910Y38646D01*
X611905Y38686D01*
X611895Y38731D01*
Y38901D01*
X611905Y38946D01*
X611910Y38986D01*
X611920Y39031D01*
X611930Y39071D01*
X611975Y39191D01*
X612015Y39271D01*
X612040Y39306D01*
X612060Y39341D01*
X612090Y39376D01*
X612115Y39411D01*
X612145Y39441D01*
Y41866D01*
X612155Y41991D01*
X612195Y42116D01*
X612255Y42226D01*
X612335Y42326D01*
X612435Y42406D01*
X612545Y42466D01*
X612670Y42506D01*
X612795Y42516D01*
X612920Y42506D01*
X613045Y42466D01*
X613155Y42406D01*
X613255Y42326D01*
X613335Y42226D01*
X613395Y42116D01*
X613435Y41991D01*
X613445Y41866D01*
Y39436D01*
X613475Y39406D01*
X613575Y39266D01*
X613595Y39226D01*
X613610Y39191D01*
X613630Y39151D01*
X613645Y39111D01*
X613655Y39071D01*
X613670Y39026D01*
X613675Y38986D01*
X613685Y38946D01*
X613690Y38901D01*
Y38861D01*
X613695Y38816D01*
X613690Y38771D01*
Y38731D01*
X613685Y38686D01*
X613675Y38646D01*
X613670Y38606D01*
X613655Y38561D01*
X613645Y38521D01*
X613630Y38481D01*
X613610Y38441D01*
X613595Y38406D01*
X613575Y38366D01*
X613475Y38226D01*
X613445Y38196D01*
Y36066D01*
X613435Y35941D01*
X613395Y35816D01*
X613335Y35706D01*
X613255Y35606D01*
X613155Y35526D01*
X613045Y35466D01*
X612920Y35426D01*
X612795Y35416D01*
G37*
G36*
G01X608071D02*
X607946Y35426D01*
X607821Y35466D01*
X607711Y35526D01*
X607611Y35606D01*
X607531Y35706D01*
X607471Y35816D01*
X607431Y35941D01*
X607421Y36066D01*
Y38191D01*
X607391Y38221D01*
X607366Y38256D01*
X607336Y38291D01*
X607316Y38326D01*
X607291Y38361D01*
X607251Y38441D01*
X607206Y38561D01*
X607196Y38601D01*
X607186Y38646D01*
X607181Y38686D01*
X607171Y38731D01*
Y38901D01*
X607181Y38946D01*
X607186Y38986D01*
X607196Y39031D01*
X607206Y39071D01*
X607251Y39191D01*
X607291Y39271D01*
X607316Y39306D01*
X607336Y39341D01*
X607366Y39376D01*
X607391Y39411D01*
X607421Y39441D01*
Y41866D01*
X607431Y41991D01*
X607471Y42116D01*
X607531Y42226D01*
X607611Y42326D01*
X607711Y42406D01*
X607821Y42466D01*
X607946Y42506D01*
X608071Y42516D01*
X608196Y42506D01*
X608321Y42466D01*
X608431Y42406D01*
X608531Y42326D01*
X608611Y42226D01*
X608671Y42116D01*
X608711Y41991D01*
X608721Y41866D01*
Y39436D01*
X608751Y39406D01*
X608851Y39266D01*
X608871Y39226D01*
X608886Y39191D01*
X608906Y39151D01*
X608921Y39111D01*
X608931Y39071D01*
X608946Y39026D01*
X608951Y38986D01*
X608961Y38946D01*
X608966Y38901D01*
Y38861D01*
X608971Y38816D01*
X608966Y38771D01*
Y38731D01*
X608961Y38686D01*
X608951Y38646D01*
X608946Y38606D01*
X608931Y38561D01*
X608921Y38521D01*
X608906Y38481D01*
X608886Y38441D01*
X608871Y38406D01*
X608851Y38366D01*
X608751Y38226D01*
X608721Y38196D01*
Y36066D01*
X608711Y35941D01*
X608671Y35816D01*
X608611Y35706D01*
X608531Y35606D01*
X608431Y35526D01*
X608321Y35466D01*
X608196Y35426D01*
X608071Y35416D01*
G37*
G36*
G01X631693D02*
X631568Y35426D01*
X631443Y35466D01*
X631333Y35526D01*
X631233Y35606D01*
X631153Y35706D01*
X631093Y35816D01*
X631053Y35941D01*
X631043Y36066D01*
Y38191D01*
X631013Y38221D01*
X630988Y38256D01*
X630958Y38291D01*
X630938Y38326D01*
X630913Y38361D01*
X630873Y38441D01*
X630828Y38561D01*
X630818Y38601D01*
X630808Y38646D01*
X630803Y38686D01*
X630793Y38731D01*
Y38901D01*
X630803Y38946D01*
X630808Y38986D01*
X630818Y39031D01*
X630828Y39071D01*
X630873Y39191D01*
X630913Y39271D01*
X630938Y39306D01*
X630958Y39341D01*
X630988Y39376D01*
X631013Y39411D01*
X631043Y39441D01*
Y41866D01*
X631053Y41991D01*
X631093Y42116D01*
X631153Y42226D01*
X631233Y42326D01*
X631333Y42406D01*
X631443Y42466D01*
X631568Y42506D01*
X631693Y42516D01*
X631818Y42506D01*
X631943Y42466D01*
X632053Y42406D01*
X632153Y42326D01*
X632233Y42226D01*
X632293Y42116D01*
X632333Y41991D01*
X632343Y41866D01*
Y39436D01*
X632373Y39406D01*
X632473Y39266D01*
X632493Y39226D01*
X632508Y39191D01*
X632528Y39151D01*
X632543Y39111D01*
X632553Y39071D01*
X632568Y39026D01*
X632573Y38986D01*
X632583Y38946D01*
X632588Y38901D01*
Y38861D01*
X632593Y38816D01*
X632588Y38771D01*
Y38731D01*
X632583Y38686D01*
X632573Y38646D01*
X632568Y38606D01*
X632553Y38561D01*
X632543Y38521D01*
X632528Y38481D01*
X632508Y38441D01*
X632493Y38406D01*
X632473Y38366D01*
X632373Y38226D01*
X632343Y38196D01*
Y36066D01*
X632333Y35941D01*
X632293Y35816D01*
X632233Y35706D01*
X632153Y35606D01*
X632053Y35526D01*
X631943Y35466D01*
X631818Y35426D01*
X631693Y35416D01*
G37*
G36*
G01X626968D02*
X626843Y35426D01*
X626718Y35466D01*
X626608Y35526D01*
X626508Y35606D01*
X626428Y35706D01*
X626368Y35816D01*
X626328Y35941D01*
X626318Y36066D01*
Y38191D01*
X626288Y38221D01*
X626263Y38256D01*
X626233Y38291D01*
X626213Y38326D01*
X626188Y38361D01*
X626148Y38441D01*
X626103Y38561D01*
X626093Y38601D01*
X626083Y38646D01*
X626078Y38686D01*
X626068Y38731D01*
Y38901D01*
X626078Y38946D01*
X626083Y38986D01*
X626093Y39031D01*
X626103Y39071D01*
X626148Y39191D01*
X626188Y39271D01*
X626213Y39306D01*
X626233Y39341D01*
X626263Y39376D01*
X626288Y39411D01*
X626318Y39441D01*
Y41866D01*
X626328Y41991D01*
X626368Y42116D01*
X626428Y42226D01*
X626508Y42326D01*
X626608Y42406D01*
X626718Y42466D01*
X626843Y42506D01*
X626968Y42516D01*
X627093Y42506D01*
X627218Y42466D01*
X627328Y42406D01*
X627428Y42326D01*
X627508Y42226D01*
X627568Y42116D01*
X627608Y41991D01*
X627618Y41866D01*
Y39436D01*
X627648Y39406D01*
X627748Y39266D01*
X627768Y39226D01*
X627783Y39191D01*
X627803Y39151D01*
X627818Y39111D01*
X627828Y39071D01*
X627843Y39026D01*
X627848Y38986D01*
X627858Y38946D01*
X627863Y38901D01*
Y38861D01*
X627868Y38816D01*
X627863Y38771D01*
Y38731D01*
X627858Y38686D01*
X627848Y38646D01*
X627843Y38606D01*
X627828Y38561D01*
X627818Y38521D01*
X627803Y38481D01*
X627783Y38441D01*
X627768Y38406D01*
X627748Y38366D01*
X627648Y38226D01*
X627618Y38196D01*
Y36066D01*
X627608Y35941D01*
X627568Y35816D01*
X627508Y35706D01*
X627428Y35606D01*
X627328Y35526D01*
X627218Y35466D01*
X627093Y35426D01*
X626968Y35416D01*
G37*
G36*
G01X622244D02*
X622119Y35426D01*
X621994Y35466D01*
X621884Y35526D01*
X621784Y35606D01*
X621704Y35706D01*
X621644Y35816D01*
X621604Y35941D01*
X621594Y36066D01*
Y38191D01*
X621564Y38221D01*
X621539Y38256D01*
X621509Y38291D01*
X621489Y38326D01*
X621464Y38361D01*
X621424Y38441D01*
X621379Y38561D01*
X621369Y38601D01*
X621359Y38646D01*
X621354Y38686D01*
X621344Y38731D01*
Y38901D01*
X621354Y38946D01*
X621359Y38986D01*
X621369Y39031D01*
X621379Y39071D01*
X621424Y39191D01*
X621464Y39271D01*
X621489Y39306D01*
X621509Y39341D01*
X621539Y39376D01*
X621564Y39411D01*
X621594Y39441D01*
Y41866D01*
X621604Y41991D01*
X621644Y42116D01*
X621704Y42226D01*
X621784Y42326D01*
X621884Y42406D01*
X621994Y42466D01*
X622119Y42506D01*
X622244Y42516D01*
X622369Y42506D01*
X622494Y42466D01*
X622604Y42406D01*
X622704Y42326D01*
X622784Y42226D01*
X622844Y42116D01*
X622884Y41991D01*
X622894Y41866D01*
Y39436D01*
X622924Y39406D01*
X623024Y39266D01*
X623044Y39226D01*
X623059Y39191D01*
X623079Y39151D01*
X623094Y39111D01*
X623104Y39071D01*
X623119Y39026D01*
X623124Y38986D01*
X623134Y38946D01*
X623139Y38901D01*
Y38861D01*
X623144Y38816D01*
X623139Y38771D01*
Y38731D01*
X623134Y38686D01*
X623124Y38646D01*
X623119Y38606D01*
X623104Y38561D01*
X623094Y38521D01*
X623079Y38481D01*
X623059Y38441D01*
X623044Y38406D01*
X623024Y38366D01*
X622924Y38226D01*
X622894Y38196D01*
Y36066D01*
X622884Y35941D01*
X622844Y35816D01*
X622784Y35706D01*
X622704Y35606D01*
X622604Y35526D01*
X622494Y35466D01*
X622369Y35426D01*
X622244Y35416D01*
G37*
G36*
G01X645866D02*
X645741Y35426D01*
X645616Y35466D01*
X645506Y35526D01*
X645406Y35606D01*
X645326Y35706D01*
X645266Y35816D01*
X645226Y35941D01*
X645216Y36066D01*
Y38191D01*
X645186Y38221D01*
X645161Y38256D01*
X645131Y38291D01*
X645111Y38326D01*
X645086Y38361D01*
X645046Y38441D01*
X645001Y38561D01*
X644991Y38601D01*
X644981Y38646D01*
X644976Y38686D01*
X644966Y38731D01*
Y38901D01*
X644976Y38946D01*
X644981Y38986D01*
X644991Y39031D01*
X645001Y39071D01*
X645046Y39191D01*
X645086Y39271D01*
X645111Y39306D01*
X645131Y39341D01*
X645161Y39376D01*
X645186Y39411D01*
X645216Y39441D01*
Y41866D01*
X645226Y41991D01*
X645266Y42116D01*
X645326Y42226D01*
X645406Y42326D01*
X645506Y42406D01*
X645616Y42466D01*
X645741Y42506D01*
X645866Y42516D01*
X645991Y42506D01*
X646116Y42466D01*
X646226Y42406D01*
X646326Y42326D01*
X646406Y42226D01*
X646466Y42116D01*
X646506Y41991D01*
X646516Y41866D01*
Y39436D01*
X646546Y39406D01*
X646646Y39266D01*
X646666Y39226D01*
X646681Y39191D01*
X646701Y39151D01*
X646716Y39111D01*
X646726Y39071D01*
X646741Y39026D01*
X646746Y38986D01*
X646756Y38946D01*
X646761Y38901D01*
Y38861D01*
X646766Y38816D01*
X646761Y38771D01*
Y38731D01*
X646756Y38686D01*
X646746Y38646D01*
X646741Y38606D01*
X646726Y38561D01*
X646716Y38521D01*
X646701Y38481D01*
X646681Y38441D01*
X646666Y38406D01*
X646646Y38366D01*
X646546Y38226D01*
X646516Y38196D01*
Y36066D01*
X646506Y35941D01*
X646466Y35816D01*
X646406Y35706D01*
X646326Y35606D01*
X646226Y35526D01*
X646116Y35466D01*
X645991Y35426D01*
X645866Y35416D01*
G37*
G36*
G01X641141D02*
X641016Y35426D01*
X640891Y35466D01*
X640781Y35526D01*
X640681Y35606D01*
X640601Y35706D01*
X640541Y35816D01*
X640501Y35941D01*
X640491Y36066D01*
Y38191D01*
X640461Y38221D01*
X640436Y38256D01*
X640406Y38291D01*
X640386Y38326D01*
X640361Y38361D01*
X640321Y38441D01*
X640276Y38561D01*
X640266Y38601D01*
X640256Y38646D01*
X640251Y38686D01*
X640241Y38731D01*
Y38901D01*
X640251Y38946D01*
X640256Y38986D01*
X640266Y39031D01*
X640276Y39071D01*
X640321Y39191D01*
X640361Y39271D01*
X640386Y39306D01*
X640406Y39341D01*
X640436Y39376D01*
X640461Y39411D01*
X640491Y39441D01*
Y41866D01*
X640501Y41991D01*
X640541Y42116D01*
X640601Y42226D01*
X640681Y42326D01*
X640781Y42406D01*
X640891Y42466D01*
X641016Y42506D01*
X641141Y42516D01*
X641266Y42506D01*
X641391Y42466D01*
X641501Y42406D01*
X641601Y42326D01*
X641681Y42226D01*
X641741Y42116D01*
X641781Y41991D01*
X641791Y41866D01*
Y39436D01*
X641821Y39406D01*
X641921Y39266D01*
X641941Y39226D01*
X641956Y39191D01*
X641976Y39151D01*
X641991Y39111D01*
X642001Y39071D01*
X642016Y39026D01*
X642021Y38986D01*
X642031Y38946D01*
X642036Y38901D01*
Y38861D01*
X642041Y38816D01*
X642036Y38771D01*
Y38731D01*
X642031Y38686D01*
X642021Y38646D01*
X642016Y38606D01*
X642001Y38561D01*
X641991Y38521D01*
X641976Y38481D01*
X641956Y38441D01*
X641941Y38406D01*
X641921Y38366D01*
X641821Y38226D01*
X641791Y38196D01*
Y36066D01*
X641781Y35941D01*
X641741Y35816D01*
X641681Y35706D01*
X641601Y35606D01*
X641501Y35526D01*
X641391Y35466D01*
X641266Y35426D01*
X641141Y35416D01*
G37*
G36*
G01X636417D02*
X636292Y35426D01*
X636167Y35466D01*
X636057Y35526D01*
X635957Y35606D01*
X635877Y35706D01*
X635817Y35816D01*
X635777Y35941D01*
X635767Y36066D01*
Y38191D01*
X635737Y38221D01*
X635712Y38256D01*
X635682Y38291D01*
X635662Y38326D01*
X635637Y38361D01*
X635597Y38441D01*
X635552Y38561D01*
X635542Y38601D01*
X635532Y38646D01*
X635527Y38686D01*
X635517Y38731D01*
Y38901D01*
X635527Y38946D01*
X635532Y38986D01*
X635542Y39031D01*
X635552Y39071D01*
X635597Y39191D01*
X635637Y39271D01*
X635662Y39306D01*
X635682Y39341D01*
X635712Y39376D01*
X635737Y39411D01*
X635767Y39441D01*
Y41866D01*
X635777Y41991D01*
X635817Y42116D01*
X635877Y42226D01*
X635957Y42326D01*
X636057Y42406D01*
X636167Y42466D01*
X636292Y42506D01*
X636417Y42516D01*
X636542Y42506D01*
X636667Y42466D01*
X636777Y42406D01*
X636877Y42326D01*
X636957Y42226D01*
X637017Y42116D01*
X637057Y41991D01*
X637067Y41866D01*
Y39436D01*
X637097Y39406D01*
X637197Y39266D01*
X637217Y39226D01*
X637232Y39191D01*
X637252Y39151D01*
X637267Y39111D01*
X637277Y39071D01*
X637292Y39026D01*
X637297Y38986D01*
X637307Y38946D01*
X637312Y38901D01*
Y38861D01*
X637317Y38816D01*
X637312Y38771D01*
Y38731D01*
X637307Y38686D01*
X637297Y38646D01*
X637292Y38606D01*
X637277Y38561D01*
X637267Y38521D01*
X637252Y38481D01*
X637232Y38441D01*
X637217Y38406D01*
X637197Y38366D01*
X637097Y38226D01*
X637067Y38196D01*
Y36066D01*
X637057Y35941D01*
X637017Y35816D01*
X636957Y35706D01*
X636877Y35606D01*
X636777Y35526D01*
X636667Y35466D01*
X636542Y35426D01*
X636417Y35416D01*
G37*
G36*
G01X664764D02*
X664639Y35426D01*
X664514Y35466D01*
X664404Y35526D01*
X664304Y35606D01*
X664224Y35706D01*
X664164Y35816D01*
X664124Y35941D01*
X664114Y36066D01*
Y38191D01*
X664084Y38221D01*
X664059Y38256D01*
X664029Y38291D01*
X664009Y38326D01*
X663984Y38361D01*
X663944Y38441D01*
X663899Y38561D01*
X663889Y38601D01*
X663879Y38646D01*
X663874Y38686D01*
X663864Y38731D01*
Y38901D01*
X663874Y38946D01*
X663879Y38986D01*
X663889Y39031D01*
X663899Y39071D01*
X663944Y39191D01*
X663984Y39271D01*
X664009Y39306D01*
X664029Y39341D01*
X664059Y39376D01*
X664084Y39411D01*
X664114Y39441D01*
Y41866D01*
X664124Y41991D01*
X664164Y42116D01*
X664224Y42226D01*
X664304Y42326D01*
X664404Y42406D01*
X664514Y42466D01*
X664639Y42506D01*
X664764Y42516D01*
X664889Y42506D01*
X665014Y42466D01*
X665124Y42406D01*
X665224Y42326D01*
X665304Y42226D01*
X665364Y42116D01*
X665404Y41991D01*
X665414Y41866D01*
Y39436D01*
X665444Y39406D01*
X665544Y39266D01*
X665564Y39226D01*
X665579Y39191D01*
X665599Y39151D01*
X665614Y39111D01*
X665624Y39071D01*
X665639Y39026D01*
X665644Y38986D01*
X665654Y38946D01*
X665659Y38901D01*
Y38861D01*
X665664Y38816D01*
X665659Y38771D01*
Y38731D01*
X665654Y38686D01*
X665644Y38646D01*
X665639Y38606D01*
X665624Y38561D01*
X665614Y38521D01*
X665599Y38481D01*
X665579Y38441D01*
X665564Y38406D01*
X665544Y38366D01*
X665444Y38226D01*
X665414Y38196D01*
Y36066D01*
X665404Y35941D01*
X665364Y35816D01*
X665304Y35706D01*
X665224Y35606D01*
X665124Y35526D01*
X665014Y35466D01*
X664889Y35426D01*
X664764Y35416D01*
G37*
G36*
G01X660039D02*
X659914Y35426D01*
X659789Y35466D01*
X659679Y35526D01*
X659579Y35606D01*
X659499Y35706D01*
X659439Y35816D01*
X659399Y35941D01*
X659389Y36066D01*
Y38191D01*
X659359Y38221D01*
X659334Y38256D01*
X659304Y38291D01*
X659284Y38326D01*
X659259Y38361D01*
X659219Y38441D01*
X659174Y38561D01*
X659164Y38601D01*
X659154Y38646D01*
X659149Y38686D01*
X659139Y38731D01*
Y38901D01*
X659149Y38946D01*
X659154Y38986D01*
X659164Y39031D01*
X659174Y39071D01*
X659219Y39191D01*
X659259Y39271D01*
X659284Y39306D01*
X659304Y39341D01*
X659334Y39376D01*
X659359Y39411D01*
X659389Y39441D01*
Y41866D01*
X659399Y41991D01*
X659439Y42116D01*
X659499Y42226D01*
X659579Y42326D01*
X659679Y42406D01*
X659789Y42466D01*
X659914Y42506D01*
X660039Y42516D01*
X660164Y42506D01*
X660289Y42466D01*
X660399Y42406D01*
X660499Y42326D01*
X660579Y42226D01*
X660639Y42116D01*
X660679Y41991D01*
X660689Y41866D01*
Y39436D01*
X660719Y39406D01*
X660819Y39266D01*
X660839Y39226D01*
X660854Y39191D01*
X660874Y39151D01*
X660889Y39111D01*
X660899Y39071D01*
X660914Y39026D01*
X660919Y38986D01*
X660929Y38946D01*
X660934Y38901D01*
Y38861D01*
X660939Y38816D01*
X660934Y38771D01*
Y38731D01*
X660929Y38686D01*
X660919Y38646D01*
X660914Y38606D01*
X660899Y38561D01*
X660889Y38521D01*
X660874Y38481D01*
X660854Y38441D01*
X660839Y38406D01*
X660819Y38366D01*
X660719Y38226D01*
X660689Y38196D01*
Y36066D01*
X660679Y35941D01*
X660639Y35816D01*
X660579Y35706D01*
X660499Y35606D01*
X660399Y35526D01*
X660289Y35466D01*
X660164Y35426D01*
X660039Y35416D01*
G37*
G36*
G01X655315D02*
X655190Y35426D01*
X655065Y35466D01*
X654955Y35526D01*
X654855Y35606D01*
X654775Y35706D01*
X654715Y35816D01*
X654675Y35941D01*
X654665Y36066D01*
Y38191D01*
X654635Y38221D01*
X654610Y38256D01*
X654580Y38291D01*
X654560Y38326D01*
X654535Y38361D01*
X654495Y38441D01*
X654450Y38561D01*
X654440Y38601D01*
X654430Y38646D01*
X654425Y38686D01*
X654415Y38731D01*
Y38901D01*
X654425Y38946D01*
X654430Y38986D01*
X654440Y39031D01*
X654450Y39071D01*
X654495Y39191D01*
X654535Y39271D01*
X654560Y39306D01*
X654580Y39341D01*
X654610Y39376D01*
X654635Y39411D01*
X654665Y39441D01*
Y41866D01*
X654675Y41991D01*
X654715Y42116D01*
X654775Y42226D01*
X654855Y42326D01*
X654955Y42406D01*
X655065Y42466D01*
X655190Y42506D01*
X655315Y42516D01*
X655440Y42506D01*
X655565Y42466D01*
X655675Y42406D01*
X655775Y42326D01*
X655855Y42226D01*
X655915Y42116D01*
X655955Y41991D01*
X655965Y41866D01*
Y39436D01*
X655995Y39406D01*
X656095Y39266D01*
X656115Y39226D01*
X656130Y39191D01*
X656150Y39151D01*
X656165Y39111D01*
X656175Y39071D01*
X656190Y39026D01*
X656195Y38986D01*
X656205Y38946D01*
X656210Y38901D01*
Y38861D01*
X656215Y38816D01*
X656210Y38771D01*
Y38731D01*
X656205Y38686D01*
X656195Y38646D01*
X656190Y38606D01*
X656175Y38561D01*
X656165Y38521D01*
X656150Y38481D01*
X656130Y38441D01*
X656115Y38406D01*
X656095Y38366D01*
X655995Y38226D01*
X655965Y38196D01*
Y36066D01*
X655955Y35941D01*
X655915Y35816D01*
X655855Y35706D01*
X655775Y35606D01*
X655675Y35526D01*
X655565Y35466D01*
X655440Y35426D01*
X655315Y35416D01*
G37*
G36*
G01X650590D02*
X650465Y35426D01*
X650340Y35466D01*
X650230Y35526D01*
X650130Y35606D01*
X650050Y35706D01*
X649990Y35816D01*
X649950Y35941D01*
X649940Y36066D01*
Y38191D01*
X649910Y38221D01*
X649885Y38256D01*
X649855Y38291D01*
X649835Y38326D01*
X649810Y38361D01*
X649770Y38441D01*
X649725Y38561D01*
X649715Y38601D01*
X649705Y38646D01*
X649700Y38686D01*
X649690Y38731D01*
Y38901D01*
X649700Y38946D01*
X649705Y38986D01*
X649715Y39031D01*
X649725Y39071D01*
X649770Y39191D01*
X649810Y39271D01*
X649835Y39306D01*
X649855Y39341D01*
X649885Y39376D01*
X649910Y39411D01*
X649940Y39441D01*
Y41866D01*
X649950Y41991D01*
X649990Y42116D01*
X650050Y42226D01*
X650130Y42326D01*
X650230Y42406D01*
X650340Y42466D01*
X650465Y42506D01*
X650590Y42516D01*
X650715Y42506D01*
X650840Y42466D01*
X650950Y42406D01*
X651050Y42326D01*
X651130Y42226D01*
X651190Y42116D01*
X651230Y41991D01*
X651240Y41866D01*
Y39436D01*
X651270Y39406D01*
X651370Y39266D01*
X651390Y39226D01*
X651405Y39191D01*
X651425Y39151D01*
X651440Y39111D01*
X651450Y39071D01*
X651465Y39026D01*
X651470Y38986D01*
X651480Y38946D01*
X651485Y38901D01*
Y38861D01*
X651490Y38816D01*
X651485Y38771D01*
Y38731D01*
X651480Y38686D01*
X651470Y38646D01*
X651465Y38606D01*
X651450Y38561D01*
X651440Y38521D01*
X651425Y38481D01*
X651405Y38441D01*
X651390Y38406D01*
X651370Y38366D01*
X651270Y38226D01*
X651240Y38196D01*
Y36066D01*
X651230Y35941D01*
X651190Y35816D01*
X651130Y35706D01*
X651050Y35606D01*
X650950Y35526D01*
X650840Y35466D01*
X650715Y35426D01*
X650590Y35416D01*
G37*
G36*
G01X678937D02*
X678812Y35426D01*
X678687Y35466D01*
X678577Y35526D01*
X678477Y35606D01*
X678397Y35706D01*
X678337Y35816D01*
X678297Y35941D01*
X678287Y36066D01*
Y38191D01*
X678257Y38221D01*
X678232Y38256D01*
X678202Y38291D01*
X678182Y38326D01*
X678157Y38361D01*
X678117Y38441D01*
X678072Y38561D01*
X678062Y38601D01*
X678052Y38646D01*
X678047Y38686D01*
X678037Y38731D01*
Y38901D01*
X678047Y38946D01*
X678052Y38986D01*
X678062Y39031D01*
X678072Y39071D01*
X678117Y39191D01*
X678157Y39271D01*
X678182Y39306D01*
X678202Y39341D01*
X678232Y39376D01*
X678257Y39411D01*
X678287Y39441D01*
Y41866D01*
X678297Y41991D01*
X678337Y42116D01*
X678397Y42226D01*
X678477Y42326D01*
X678577Y42406D01*
X678687Y42466D01*
X678812Y42506D01*
X678937Y42516D01*
X679062Y42506D01*
X679187Y42466D01*
X679297Y42406D01*
X679397Y42326D01*
X679477Y42226D01*
X679537Y42116D01*
X679577Y41991D01*
X679587Y41866D01*
Y39436D01*
X679617Y39406D01*
X679717Y39266D01*
X679737Y39226D01*
X679752Y39191D01*
X679772Y39151D01*
X679787Y39111D01*
X679797Y39071D01*
X679812Y39026D01*
X679817Y38986D01*
X679827Y38946D01*
X679832Y38901D01*
Y38861D01*
X679837Y38816D01*
X679832Y38771D01*
Y38731D01*
X679827Y38686D01*
X679817Y38646D01*
X679812Y38606D01*
X679797Y38561D01*
X679787Y38521D01*
X679772Y38481D01*
X679752Y38441D01*
X679737Y38406D01*
X679717Y38366D01*
X679617Y38226D01*
X679587Y38196D01*
Y36066D01*
X679577Y35941D01*
X679537Y35816D01*
X679477Y35706D01*
X679397Y35606D01*
X679297Y35526D01*
X679187Y35466D01*
X679062Y35426D01*
X678937Y35416D01*
G37*
G36*
G01X674212D02*
X674087Y35426D01*
X673962Y35466D01*
X673852Y35526D01*
X673752Y35606D01*
X673672Y35706D01*
X673612Y35816D01*
X673572Y35941D01*
X673562Y36066D01*
Y38191D01*
X673532Y38221D01*
X673507Y38256D01*
X673477Y38291D01*
X673457Y38326D01*
X673432Y38361D01*
X673392Y38441D01*
X673347Y38561D01*
X673337Y38601D01*
X673327Y38646D01*
X673322Y38686D01*
X673312Y38731D01*
Y38901D01*
X673322Y38946D01*
X673327Y38986D01*
X673337Y39031D01*
X673347Y39071D01*
X673392Y39191D01*
X673432Y39271D01*
X673457Y39306D01*
X673477Y39341D01*
X673507Y39376D01*
X673532Y39411D01*
X673562Y39441D01*
Y41866D01*
X673572Y41991D01*
X673612Y42116D01*
X673672Y42226D01*
X673752Y42326D01*
X673852Y42406D01*
X673962Y42466D01*
X674087Y42506D01*
X674212Y42516D01*
X674337Y42506D01*
X674462Y42466D01*
X674572Y42406D01*
X674672Y42326D01*
X674752Y42226D01*
X674812Y42116D01*
X674852Y41991D01*
X674862Y41866D01*
Y39436D01*
X674892Y39406D01*
X674992Y39266D01*
X675012Y39226D01*
X675027Y39191D01*
X675047Y39151D01*
X675062Y39111D01*
X675072Y39071D01*
X675087Y39026D01*
X675092Y38986D01*
X675102Y38946D01*
X675107Y38901D01*
Y38861D01*
X675112Y38816D01*
X675107Y38771D01*
Y38731D01*
X675102Y38686D01*
X675092Y38646D01*
X675087Y38606D01*
X675072Y38561D01*
X675062Y38521D01*
X675047Y38481D01*
X675027Y38441D01*
X675012Y38406D01*
X674992Y38366D01*
X674892Y38226D01*
X674862Y38196D01*
Y36066D01*
X674852Y35941D01*
X674812Y35816D01*
X674752Y35706D01*
X674672Y35606D01*
X674572Y35526D01*
X674462Y35466D01*
X674337Y35426D01*
X674212Y35416D01*
G37*
G36*
G01X669488D02*
X669363Y35426D01*
X669238Y35466D01*
X669128Y35526D01*
X669028Y35606D01*
X668948Y35706D01*
X668888Y35816D01*
X668848Y35941D01*
X668838Y36066D01*
Y38191D01*
X668808Y38221D01*
X668783Y38256D01*
X668753Y38291D01*
X668733Y38326D01*
X668708Y38361D01*
X668668Y38441D01*
X668623Y38561D01*
X668613Y38601D01*
X668603Y38646D01*
X668598Y38686D01*
X668588Y38731D01*
Y38901D01*
X668598Y38946D01*
X668603Y38986D01*
X668613Y39031D01*
X668623Y39071D01*
X668668Y39191D01*
X668708Y39271D01*
X668733Y39306D01*
X668753Y39341D01*
X668783Y39376D01*
X668808Y39411D01*
X668838Y39441D01*
Y41866D01*
X668848Y41991D01*
X668888Y42116D01*
X668948Y42226D01*
X669028Y42326D01*
X669128Y42406D01*
X669238Y42466D01*
X669363Y42506D01*
X669488Y42516D01*
X669613Y42506D01*
X669738Y42466D01*
X669848Y42406D01*
X669948Y42326D01*
X670028Y42226D01*
X670088Y42116D01*
X670128Y41991D01*
X670138Y41866D01*
Y39436D01*
X670168Y39406D01*
X670268Y39266D01*
X670288Y39226D01*
X670303Y39191D01*
X670323Y39151D01*
X670338Y39111D01*
X670348Y39071D01*
X670363Y39026D01*
X670368Y38986D01*
X670378Y38946D01*
X670383Y38901D01*
Y38861D01*
X670388Y38816D01*
X670383Y38771D01*
Y38731D01*
X670378Y38686D01*
X670368Y38646D01*
X670363Y38606D01*
X670348Y38561D01*
X670338Y38521D01*
X670323Y38481D01*
X670303Y38441D01*
X670288Y38406D01*
X670268Y38366D01*
X670168Y38226D01*
X670138Y38196D01*
Y36066D01*
X670128Y35941D01*
X670088Y35816D01*
X670028Y35706D01*
X669948Y35606D01*
X669848Y35526D01*
X669738Y35466D01*
X669613Y35426D01*
X669488Y35416D01*
G37*
G36*
G01X693110D02*
X692985Y35426D01*
X692860Y35466D01*
X692750Y35526D01*
X692650Y35606D01*
X692570Y35706D01*
X692510Y35816D01*
X692470Y35941D01*
X692460Y36066D01*
Y38191D01*
X692430Y38221D01*
X692405Y38256D01*
X692375Y38291D01*
X692355Y38326D01*
X692330Y38361D01*
X692290Y38441D01*
X692245Y38561D01*
X692235Y38601D01*
X692225Y38646D01*
X692220Y38686D01*
X692210Y38731D01*
Y38901D01*
X692220Y38946D01*
X692225Y38986D01*
X692235Y39031D01*
X692245Y39071D01*
X692290Y39191D01*
X692330Y39271D01*
X692355Y39306D01*
X692375Y39341D01*
X692405Y39376D01*
X692430Y39411D01*
X692460Y39441D01*
Y41866D01*
X692470Y41991D01*
X692510Y42116D01*
X692570Y42226D01*
X692650Y42326D01*
X692750Y42406D01*
X692860Y42466D01*
X692985Y42506D01*
X693110Y42516D01*
X693235Y42506D01*
X693360Y42466D01*
X693470Y42406D01*
X693570Y42326D01*
X693650Y42226D01*
X693710Y42116D01*
X693750Y41991D01*
X693760Y41866D01*
Y39436D01*
X693790Y39406D01*
X693890Y39266D01*
X693910Y39226D01*
X693925Y39191D01*
X693945Y39151D01*
X693960Y39111D01*
X693970Y39071D01*
X693985Y39026D01*
X693990Y38986D01*
X694000Y38946D01*
X694005Y38901D01*
Y38861D01*
X694010Y38816D01*
X694005Y38771D01*
Y38731D01*
X694000Y38686D01*
X693990Y38646D01*
X693985Y38606D01*
X693970Y38561D01*
X693960Y38521D01*
X693945Y38481D01*
X693925Y38441D01*
X693910Y38406D01*
X693890Y38366D01*
X693790Y38226D01*
X693760Y38196D01*
Y36066D01*
X693750Y35941D01*
X693710Y35816D01*
X693650Y35706D01*
X693570Y35606D01*
X693470Y35526D01*
X693360Y35466D01*
X693235Y35426D01*
X693110Y35416D01*
G37*
G36*
G01X688386D02*
X688261Y35426D01*
X688136Y35466D01*
X688026Y35526D01*
X687926Y35606D01*
X687846Y35706D01*
X687786Y35816D01*
X687746Y35941D01*
X687736Y36066D01*
Y38191D01*
X687706Y38221D01*
X687681Y38256D01*
X687651Y38291D01*
X687631Y38326D01*
X687606Y38361D01*
X687566Y38441D01*
X687521Y38561D01*
X687511Y38601D01*
X687501Y38646D01*
X687496Y38686D01*
X687486Y38731D01*
Y38901D01*
X687496Y38946D01*
X687501Y38986D01*
X687511Y39031D01*
X687521Y39071D01*
X687566Y39191D01*
X687606Y39271D01*
X687631Y39306D01*
X687651Y39341D01*
X687681Y39376D01*
X687706Y39411D01*
X687736Y39441D01*
Y41866D01*
X687746Y41991D01*
X687786Y42116D01*
X687846Y42226D01*
X687926Y42326D01*
X688026Y42406D01*
X688136Y42466D01*
X688261Y42506D01*
X688386Y42516D01*
X688511Y42506D01*
X688636Y42466D01*
X688746Y42406D01*
X688846Y42326D01*
X688926Y42226D01*
X688986Y42116D01*
X689026Y41991D01*
X689036Y41866D01*
Y39436D01*
X689066Y39406D01*
X689166Y39266D01*
X689186Y39226D01*
X689201Y39191D01*
X689221Y39151D01*
X689236Y39111D01*
X689246Y39071D01*
X689261Y39026D01*
X689266Y38986D01*
X689276Y38946D01*
X689281Y38901D01*
Y38861D01*
X689286Y38816D01*
X689281Y38771D01*
Y38731D01*
X689276Y38686D01*
X689266Y38646D01*
X689261Y38606D01*
X689246Y38561D01*
X689236Y38521D01*
X689221Y38481D01*
X689201Y38441D01*
X689186Y38406D01*
X689166Y38366D01*
X689066Y38226D01*
X689036Y38196D01*
Y36066D01*
X689026Y35941D01*
X688986Y35816D01*
X688926Y35706D01*
X688846Y35606D01*
X688746Y35526D01*
X688636Y35466D01*
X688511Y35426D01*
X688386Y35416D01*
G37*
G36*
G01X683661D02*
X683536Y35426D01*
X683411Y35466D01*
X683301Y35526D01*
X683201Y35606D01*
X683121Y35706D01*
X683061Y35816D01*
X683021Y35941D01*
X683011Y36066D01*
Y38191D01*
X682981Y38221D01*
X682956Y38256D01*
X682926Y38291D01*
X682906Y38326D01*
X682881Y38361D01*
X682841Y38441D01*
X682796Y38561D01*
X682786Y38601D01*
X682776Y38646D01*
X682771Y38686D01*
X682761Y38731D01*
Y38901D01*
X682771Y38946D01*
X682776Y38986D01*
X682786Y39031D01*
X682796Y39071D01*
X682841Y39191D01*
X682881Y39271D01*
X682906Y39306D01*
X682926Y39341D01*
X682956Y39376D01*
X682981Y39411D01*
X683011Y39441D01*
Y41866D01*
X683021Y41991D01*
X683061Y42116D01*
X683121Y42226D01*
X683201Y42326D01*
X683301Y42406D01*
X683411Y42466D01*
X683536Y42506D01*
X683661Y42516D01*
X683786Y42506D01*
X683911Y42466D01*
X684021Y42406D01*
X684121Y42326D01*
X684201Y42226D01*
X684261Y42116D01*
X684301Y41991D01*
X684311Y41866D01*
Y39436D01*
X684341Y39406D01*
X684441Y39266D01*
X684461Y39226D01*
X684476Y39191D01*
X684496Y39151D01*
X684511Y39111D01*
X684521Y39071D01*
X684536Y39026D01*
X684541Y38986D01*
X684551Y38946D01*
X684556Y38901D01*
Y38861D01*
X684561Y38816D01*
X684556Y38771D01*
Y38731D01*
X684551Y38686D01*
X684541Y38646D01*
X684536Y38606D01*
X684521Y38561D01*
X684511Y38521D01*
X684496Y38481D01*
X684476Y38441D01*
X684461Y38406D01*
X684441Y38366D01*
X684341Y38226D01*
X684311Y38196D01*
Y36066D01*
X684301Y35941D01*
X684261Y35816D01*
X684201Y35706D01*
X684121Y35606D01*
X684021Y35526D01*
X683911Y35466D01*
X683786Y35426D01*
X683661Y35416D01*
G37*
G36*
G01X707283D02*
X707158Y35426D01*
X707033Y35466D01*
X706923Y35526D01*
X706823Y35606D01*
X706743Y35706D01*
X706683Y35816D01*
X706643Y35941D01*
X706633Y36066D01*
Y38191D01*
X706603Y38221D01*
X706578Y38256D01*
X706548Y38291D01*
X706528Y38326D01*
X706503Y38361D01*
X706463Y38441D01*
X706418Y38561D01*
X706408Y38601D01*
X706398Y38646D01*
X706393Y38686D01*
X706383Y38731D01*
Y38901D01*
X706393Y38946D01*
X706398Y38986D01*
X706408Y39031D01*
X706418Y39071D01*
X706463Y39191D01*
X706503Y39271D01*
X706528Y39306D01*
X706548Y39341D01*
X706578Y39376D01*
X706603Y39411D01*
X706633Y39441D01*
Y41866D01*
X706643Y41991D01*
X706683Y42116D01*
X706743Y42226D01*
X706823Y42326D01*
X706923Y42406D01*
X707033Y42466D01*
X707158Y42506D01*
X707283Y42516D01*
X707408Y42506D01*
X707533Y42466D01*
X707643Y42406D01*
X707743Y42326D01*
X707823Y42226D01*
X707883Y42116D01*
X707923Y41991D01*
X707933Y41866D01*
Y39436D01*
X707963Y39406D01*
X708063Y39266D01*
X708083Y39226D01*
X708098Y39191D01*
X708118Y39151D01*
X708133Y39111D01*
X708143Y39071D01*
X708158Y39026D01*
X708163Y38986D01*
X708173Y38946D01*
X708178Y38901D01*
Y38861D01*
X708183Y38816D01*
X708178Y38771D01*
Y38731D01*
X708173Y38686D01*
X708163Y38646D01*
X708158Y38606D01*
X708143Y38561D01*
X708133Y38521D01*
X708118Y38481D01*
X708098Y38441D01*
X708083Y38406D01*
X708063Y38366D01*
X707963Y38226D01*
X707933Y38196D01*
Y36066D01*
X707923Y35941D01*
X707883Y35816D01*
X707823Y35706D01*
X707743Y35606D01*
X707643Y35526D01*
X707533Y35466D01*
X707408Y35426D01*
X707283Y35416D01*
G37*
G36*
G01X702559D02*
X702434Y35426D01*
X702309Y35466D01*
X702199Y35526D01*
X702099Y35606D01*
X702019Y35706D01*
X701959Y35816D01*
X701919Y35941D01*
X701909Y36066D01*
Y38191D01*
X701879Y38221D01*
X701854Y38256D01*
X701824Y38291D01*
X701804Y38326D01*
X701779Y38361D01*
X701739Y38441D01*
X701694Y38561D01*
X701684Y38601D01*
X701674Y38646D01*
X701669Y38686D01*
X701659Y38731D01*
Y38901D01*
X701669Y38946D01*
X701674Y38986D01*
X701684Y39031D01*
X701694Y39071D01*
X701739Y39191D01*
X701779Y39271D01*
X701804Y39306D01*
X701824Y39341D01*
X701854Y39376D01*
X701879Y39411D01*
X701909Y39441D01*
Y41866D01*
X701919Y41991D01*
X701959Y42116D01*
X702019Y42226D01*
X702099Y42326D01*
X702199Y42406D01*
X702309Y42466D01*
X702434Y42506D01*
X702559Y42516D01*
X702684Y42506D01*
X702809Y42466D01*
X702919Y42406D01*
X703019Y42326D01*
X703099Y42226D01*
X703159Y42116D01*
X703199Y41991D01*
X703209Y41866D01*
Y39436D01*
X703239Y39406D01*
X703339Y39266D01*
X703359Y39226D01*
X703374Y39191D01*
X703394Y39151D01*
X703409Y39111D01*
X703419Y39071D01*
X703434Y39026D01*
X703439Y38986D01*
X703449Y38946D01*
X703454Y38901D01*
Y38861D01*
X703459Y38816D01*
X703454Y38771D01*
Y38731D01*
X703449Y38686D01*
X703439Y38646D01*
X703434Y38606D01*
X703419Y38561D01*
X703409Y38521D01*
X703394Y38481D01*
X703374Y38441D01*
X703359Y38406D01*
X703339Y38366D01*
X703239Y38226D01*
X703209Y38196D01*
Y36066D01*
X703199Y35941D01*
X703159Y35816D01*
X703099Y35706D01*
X703019Y35606D01*
X702919Y35526D01*
X702809Y35466D01*
X702684Y35426D01*
X702559Y35416D01*
G37*
G36*
G01X697834D02*
X697709Y35426D01*
X697584Y35466D01*
X697474Y35526D01*
X697374Y35606D01*
X697294Y35706D01*
X697234Y35816D01*
X697194Y35941D01*
X697184Y36066D01*
Y38191D01*
X697154Y38221D01*
X697129Y38256D01*
X697099Y38291D01*
X697079Y38326D01*
X697054Y38361D01*
X697014Y38441D01*
X696969Y38561D01*
X696959Y38601D01*
X696949Y38646D01*
X696944Y38686D01*
X696934Y38731D01*
Y38901D01*
X696944Y38946D01*
X696949Y38986D01*
X696959Y39031D01*
X696969Y39071D01*
X697014Y39191D01*
X697054Y39271D01*
X697079Y39306D01*
X697099Y39341D01*
X697129Y39376D01*
X697154Y39411D01*
X697184Y39441D01*
Y41866D01*
X697194Y41991D01*
X697234Y42116D01*
X697294Y42226D01*
X697374Y42326D01*
X697474Y42406D01*
X697584Y42466D01*
X697709Y42506D01*
X697834Y42516D01*
X697959Y42506D01*
X698084Y42466D01*
X698194Y42406D01*
X698294Y42326D01*
X698374Y42226D01*
X698434Y42116D01*
X698474Y41991D01*
X698484Y41866D01*
Y39436D01*
X698514Y39406D01*
X698614Y39266D01*
X698634Y39226D01*
X698649Y39191D01*
X698669Y39151D01*
X698684Y39111D01*
X698694Y39071D01*
X698709Y39026D01*
X698714Y38986D01*
X698724Y38946D01*
X698729Y38901D01*
Y38861D01*
X698734Y38816D01*
X698729Y38771D01*
Y38731D01*
X698724Y38686D01*
X698714Y38646D01*
X698709Y38606D01*
X698694Y38561D01*
X698684Y38521D01*
X698669Y38481D01*
X698649Y38441D01*
X698634Y38406D01*
X698614Y38366D01*
X698514Y38226D01*
X698484Y38196D01*
Y36066D01*
X698474Y35941D01*
X698434Y35816D01*
X698374Y35706D01*
X698294Y35606D01*
X698194Y35526D01*
X698084Y35466D01*
X697959Y35426D01*
X697834Y35416D01*
G37*
G36*
G01X726181D02*
X726056Y35426D01*
X725931Y35466D01*
X725821Y35526D01*
X725721Y35606D01*
X725641Y35706D01*
X725581Y35816D01*
X725541Y35941D01*
X725531Y36066D01*
Y38191D01*
X725501Y38221D01*
X725476Y38256D01*
X725446Y38291D01*
X725426Y38326D01*
X725401Y38361D01*
X725361Y38441D01*
X725316Y38561D01*
X725306Y38601D01*
X725296Y38646D01*
X725291Y38686D01*
X725281Y38731D01*
Y38901D01*
X725291Y38946D01*
X725296Y38986D01*
X725306Y39031D01*
X725316Y39071D01*
X725361Y39191D01*
X725401Y39271D01*
X725426Y39306D01*
X725446Y39341D01*
X725476Y39376D01*
X725501Y39411D01*
X725531Y39441D01*
Y41866D01*
X725541Y41991D01*
X725581Y42116D01*
X725641Y42226D01*
X725721Y42326D01*
X725821Y42406D01*
X725931Y42466D01*
X726056Y42506D01*
X726181Y42516D01*
X726306Y42506D01*
X726431Y42466D01*
X726541Y42406D01*
X726641Y42326D01*
X726721Y42226D01*
X726781Y42116D01*
X726821Y41991D01*
X726831Y41866D01*
Y39436D01*
X726861Y39406D01*
X726961Y39266D01*
X726981Y39226D01*
X726996Y39191D01*
X727016Y39151D01*
X727031Y39111D01*
X727041Y39071D01*
X727056Y39026D01*
X727061Y38986D01*
X727071Y38946D01*
X727076Y38901D01*
Y38861D01*
X727081Y38816D01*
X727076Y38771D01*
Y38731D01*
X727071Y38686D01*
X727061Y38646D01*
X727056Y38606D01*
X727041Y38561D01*
X727031Y38521D01*
X727016Y38481D01*
X726996Y38441D01*
X726981Y38406D01*
X726961Y38366D01*
X726861Y38226D01*
X726831Y38196D01*
Y36066D01*
X726821Y35941D01*
X726781Y35816D01*
X726721Y35706D01*
X726641Y35606D01*
X726541Y35526D01*
X726431Y35466D01*
X726306Y35426D01*
X726181Y35416D01*
G37*
G36*
G01X721456D02*
X721331Y35426D01*
X721206Y35466D01*
X721096Y35526D01*
X720996Y35606D01*
X720916Y35706D01*
X720856Y35816D01*
X720816Y35941D01*
X720806Y36066D01*
Y38191D01*
X720776Y38221D01*
X720751Y38256D01*
X720721Y38291D01*
X720701Y38326D01*
X720676Y38361D01*
X720636Y38441D01*
X720591Y38561D01*
X720581Y38601D01*
X720571Y38646D01*
X720566Y38686D01*
X720556Y38731D01*
Y38901D01*
X720566Y38946D01*
X720571Y38986D01*
X720581Y39031D01*
X720591Y39071D01*
X720636Y39191D01*
X720676Y39271D01*
X720701Y39306D01*
X720721Y39341D01*
X720751Y39376D01*
X720776Y39411D01*
X720806Y39441D01*
Y41866D01*
X720816Y41991D01*
X720856Y42116D01*
X720916Y42226D01*
X720996Y42326D01*
X721096Y42406D01*
X721206Y42466D01*
X721331Y42506D01*
X721456Y42516D01*
X721581Y42506D01*
X721706Y42466D01*
X721816Y42406D01*
X721916Y42326D01*
X721996Y42226D01*
X722056Y42116D01*
X722096Y41991D01*
X722106Y41866D01*
Y39436D01*
X722136Y39406D01*
X722236Y39266D01*
X722256Y39226D01*
X722271Y39191D01*
X722291Y39151D01*
X722306Y39111D01*
X722316Y39071D01*
X722331Y39026D01*
X722336Y38986D01*
X722346Y38946D01*
X722351Y38901D01*
Y38861D01*
X722356Y38816D01*
X722351Y38771D01*
Y38731D01*
X722346Y38686D01*
X722336Y38646D01*
X722331Y38606D01*
X722316Y38561D01*
X722306Y38521D01*
X722291Y38481D01*
X722271Y38441D01*
X722256Y38406D01*
X722236Y38366D01*
X722136Y38226D01*
X722106Y38196D01*
Y36066D01*
X722096Y35941D01*
X722056Y35816D01*
X721996Y35706D01*
X721916Y35606D01*
X721816Y35526D01*
X721706Y35466D01*
X721581Y35426D01*
X721456Y35416D01*
G37*
G36*
G01X716732D02*
X716607Y35426D01*
X716482Y35466D01*
X716372Y35526D01*
X716272Y35606D01*
X716192Y35706D01*
X716132Y35816D01*
X716092Y35941D01*
X716082Y36066D01*
Y38191D01*
X716052Y38221D01*
X716027Y38256D01*
X715997Y38291D01*
X715977Y38326D01*
X715952Y38361D01*
X715912Y38441D01*
X715867Y38561D01*
X715857Y38601D01*
X715847Y38646D01*
X715842Y38686D01*
X715832Y38731D01*
Y38901D01*
X715842Y38946D01*
X715847Y38986D01*
X715857Y39031D01*
X715867Y39071D01*
X715912Y39191D01*
X715952Y39271D01*
X715977Y39306D01*
X715997Y39341D01*
X716027Y39376D01*
X716052Y39411D01*
X716082Y39441D01*
Y41866D01*
X716092Y41991D01*
X716132Y42116D01*
X716192Y42226D01*
X716272Y42326D01*
X716372Y42406D01*
X716482Y42466D01*
X716607Y42506D01*
X716732Y42516D01*
X716857Y42506D01*
X716982Y42466D01*
X717092Y42406D01*
X717192Y42326D01*
X717272Y42226D01*
X717332Y42116D01*
X717372Y41991D01*
X717382Y41866D01*
Y39436D01*
X717412Y39406D01*
X717512Y39266D01*
X717532Y39226D01*
X717547Y39191D01*
X717567Y39151D01*
X717582Y39111D01*
X717592Y39071D01*
X717607Y39026D01*
X717612Y38986D01*
X717622Y38946D01*
X717627Y38901D01*
Y38861D01*
X717632Y38816D01*
X717627Y38771D01*
Y38731D01*
X717622Y38686D01*
X717612Y38646D01*
X717607Y38606D01*
X717592Y38561D01*
X717582Y38521D01*
X717567Y38481D01*
X717547Y38441D01*
X717532Y38406D01*
X717512Y38366D01*
X717412Y38226D01*
X717382Y38196D01*
Y36066D01*
X717372Y35941D01*
X717332Y35816D01*
X717272Y35706D01*
X717192Y35606D01*
X717092Y35526D01*
X716982Y35466D01*
X716857Y35426D01*
X716732Y35416D01*
G37*
G36*
G01X712008D02*
X711883Y35426D01*
X711758Y35466D01*
X711648Y35526D01*
X711548Y35606D01*
X711468Y35706D01*
X711408Y35816D01*
X711368Y35941D01*
X711358Y36066D01*
Y38191D01*
X711328Y38221D01*
X711303Y38256D01*
X711273Y38291D01*
X711253Y38326D01*
X711228Y38361D01*
X711188Y38441D01*
X711143Y38561D01*
X711133Y38601D01*
X711123Y38646D01*
X711118Y38686D01*
X711108Y38731D01*
Y38901D01*
X711118Y38946D01*
X711123Y38986D01*
X711133Y39031D01*
X711143Y39071D01*
X711188Y39191D01*
X711228Y39271D01*
X711253Y39306D01*
X711273Y39341D01*
X711303Y39376D01*
X711328Y39411D01*
X711358Y39441D01*
Y41866D01*
X711368Y41991D01*
X711408Y42116D01*
X711468Y42226D01*
X711548Y42326D01*
X711648Y42406D01*
X711758Y42466D01*
X711883Y42506D01*
X712008Y42516D01*
X712133Y42506D01*
X712258Y42466D01*
X712368Y42406D01*
X712468Y42326D01*
X712548Y42226D01*
X712608Y42116D01*
X712648Y41991D01*
X712658Y41866D01*
Y39436D01*
X712688Y39406D01*
X712788Y39266D01*
X712808Y39226D01*
X712823Y39191D01*
X712843Y39151D01*
X712858Y39111D01*
X712868Y39071D01*
X712883Y39026D01*
X712888Y38986D01*
X712898Y38946D01*
X712903Y38901D01*
Y38861D01*
X712908Y38816D01*
X712903Y38771D01*
Y38731D01*
X712898Y38686D01*
X712888Y38646D01*
X712883Y38606D01*
X712868Y38561D01*
X712858Y38521D01*
X712843Y38481D01*
X712823Y38441D01*
X712808Y38406D01*
X712788Y38366D01*
X712688Y38226D01*
X712658Y38196D01*
Y36066D01*
X712648Y35941D01*
X712608Y35816D01*
X712548Y35706D01*
X712468Y35606D01*
X712368Y35526D01*
X712258Y35466D01*
X712133Y35426D01*
X712008Y35416D01*
G37*
G36*
G01X740354D02*
X740229Y35426D01*
X740104Y35466D01*
X739994Y35526D01*
X739894Y35606D01*
X739814Y35706D01*
X739754Y35816D01*
X739714Y35941D01*
X739704Y36066D01*
Y38191D01*
X739674Y38221D01*
X739649Y38256D01*
X739619Y38291D01*
X739599Y38326D01*
X739574Y38361D01*
X739534Y38441D01*
X739489Y38561D01*
X739479Y38601D01*
X739469Y38646D01*
X739464Y38686D01*
X739454Y38731D01*
Y38901D01*
X739464Y38946D01*
X739469Y38986D01*
X739479Y39031D01*
X739489Y39071D01*
X739534Y39191D01*
X739574Y39271D01*
X739599Y39306D01*
X739619Y39341D01*
X739649Y39376D01*
X739674Y39411D01*
X739704Y39441D01*
Y41866D01*
X739714Y41991D01*
X739754Y42116D01*
X739814Y42226D01*
X739894Y42326D01*
X739994Y42406D01*
X740104Y42466D01*
X740229Y42506D01*
X740354Y42516D01*
X740479Y42506D01*
X740604Y42466D01*
X740714Y42406D01*
X740814Y42326D01*
X740894Y42226D01*
X740954Y42116D01*
X740994Y41991D01*
X741004Y41866D01*
Y39436D01*
X741034Y39406D01*
X741134Y39266D01*
X741154Y39226D01*
X741169Y39191D01*
X741189Y39151D01*
X741204Y39111D01*
X741214Y39071D01*
X741229Y39026D01*
X741234Y38986D01*
X741244Y38946D01*
X741249Y38901D01*
Y38861D01*
X741254Y38816D01*
X741249Y38771D01*
Y38731D01*
X741244Y38686D01*
X741234Y38646D01*
X741229Y38606D01*
X741214Y38561D01*
X741204Y38521D01*
X741189Y38481D01*
X741169Y38441D01*
X741154Y38406D01*
X741134Y38366D01*
X741034Y38226D01*
X741004Y38196D01*
Y36066D01*
X740994Y35941D01*
X740954Y35816D01*
X740894Y35706D01*
X740814Y35606D01*
X740714Y35526D01*
X740604Y35466D01*
X740479Y35426D01*
X740354Y35416D01*
G37*
G36*
G01X735630D02*
X735505Y35426D01*
X735380Y35466D01*
X735270Y35526D01*
X735170Y35606D01*
X735090Y35706D01*
X735030Y35816D01*
X734990Y35941D01*
X734980Y36066D01*
Y38191D01*
X734950Y38221D01*
X734925Y38256D01*
X734895Y38291D01*
X734875Y38326D01*
X734850Y38361D01*
X734810Y38441D01*
X734765Y38561D01*
X734755Y38601D01*
X734745Y38646D01*
X734740Y38686D01*
X734730Y38731D01*
Y38901D01*
X734740Y38946D01*
X734745Y38986D01*
X734755Y39031D01*
X734765Y39071D01*
X734810Y39191D01*
X734850Y39271D01*
X734875Y39306D01*
X734895Y39341D01*
X734925Y39376D01*
X734950Y39411D01*
X734980Y39441D01*
Y41866D01*
X734990Y41991D01*
X735030Y42116D01*
X735090Y42226D01*
X735170Y42326D01*
X735270Y42406D01*
X735380Y42466D01*
X735505Y42506D01*
X735630Y42516D01*
X735755Y42506D01*
X735880Y42466D01*
X735990Y42406D01*
X736090Y42326D01*
X736170Y42226D01*
X736230Y42116D01*
X736270Y41991D01*
X736280Y41866D01*
Y39436D01*
X736310Y39406D01*
X736410Y39266D01*
X736430Y39226D01*
X736445Y39191D01*
X736465Y39151D01*
X736480Y39111D01*
X736490Y39071D01*
X736505Y39026D01*
X736510Y38986D01*
X736520Y38946D01*
X736525Y38901D01*
Y38861D01*
X736530Y38816D01*
X736525Y38771D01*
Y38731D01*
X736520Y38686D01*
X736510Y38646D01*
X736505Y38606D01*
X736490Y38561D01*
X736480Y38521D01*
X736465Y38481D01*
X736445Y38441D01*
X736430Y38406D01*
X736410Y38366D01*
X736310Y38226D01*
X736280Y38196D01*
Y36066D01*
X736270Y35941D01*
X736230Y35816D01*
X736170Y35706D01*
X736090Y35606D01*
X735990Y35526D01*
X735880Y35466D01*
X735755Y35426D01*
X735630Y35416D01*
G37*
G36*
G01X730905D02*
X730780Y35426D01*
X730655Y35466D01*
X730545Y35526D01*
X730445Y35606D01*
X730365Y35706D01*
X730305Y35816D01*
X730265Y35941D01*
X730255Y36066D01*
Y38191D01*
X730225Y38221D01*
X730200Y38256D01*
X730170Y38291D01*
X730150Y38326D01*
X730125Y38361D01*
X730085Y38441D01*
X730040Y38561D01*
X730030Y38601D01*
X730020Y38646D01*
X730015Y38686D01*
X730005Y38731D01*
Y38901D01*
X730015Y38946D01*
X730020Y38986D01*
X730030Y39031D01*
X730040Y39071D01*
X730085Y39191D01*
X730125Y39271D01*
X730150Y39306D01*
X730170Y39341D01*
X730200Y39376D01*
X730225Y39411D01*
X730255Y39441D01*
Y41866D01*
X730265Y41991D01*
X730305Y42116D01*
X730365Y42226D01*
X730445Y42326D01*
X730545Y42406D01*
X730655Y42466D01*
X730780Y42506D01*
X730905Y42516D01*
X731030Y42506D01*
X731155Y42466D01*
X731265Y42406D01*
X731365Y42326D01*
X731445Y42226D01*
X731505Y42116D01*
X731545Y41991D01*
X731555Y41866D01*
Y39436D01*
X731585Y39406D01*
X731685Y39266D01*
X731705Y39226D01*
X731720Y39191D01*
X731740Y39151D01*
X731755Y39111D01*
X731765Y39071D01*
X731780Y39026D01*
X731785Y38986D01*
X731795Y38946D01*
X731800Y38901D01*
Y38861D01*
X731805Y38816D01*
X731800Y38771D01*
Y38731D01*
X731795Y38686D01*
X731785Y38646D01*
X731780Y38606D01*
X731765Y38561D01*
X731755Y38521D01*
X731740Y38481D01*
X731720Y38441D01*
X731705Y38406D01*
X731685Y38366D01*
X731585Y38226D01*
X731555Y38196D01*
Y36066D01*
X731545Y35941D01*
X731505Y35816D01*
X731445Y35706D01*
X731365Y35606D01*
X731265Y35526D01*
X731155Y35466D01*
X731030Y35426D01*
X730905Y35416D01*
G37*
G36*
G01X754527D02*
X754402Y35426D01*
X754277Y35466D01*
X754167Y35526D01*
X754067Y35606D01*
X753987Y35706D01*
X753927Y35816D01*
X753887Y35941D01*
X753877Y36066D01*
Y38191D01*
X753847Y38221D01*
X753822Y38256D01*
X753792Y38291D01*
X753772Y38326D01*
X753747Y38361D01*
X753707Y38441D01*
X753662Y38561D01*
X753652Y38601D01*
X753642Y38646D01*
X753637Y38686D01*
X753627Y38731D01*
Y38901D01*
X753637Y38946D01*
X753642Y38986D01*
X753652Y39031D01*
X753662Y39071D01*
X753707Y39191D01*
X753747Y39271D01*
X753772Y39306D01*
X753792Y39341D01*
X753822Y39376D01*
X753847Y39411D01*
X753877Y39441D01*
Y41866D01*
X753887Y41991D01*
X753927Y42116D01*
X753987Y42226D01*
X754067Y42326D01*
X754167Y42406D01*
X754277Y42466D01*
X754402Y42506D01*
X754527Y42516D01*
X754652Y42506D01*
X754777Y42466D01*
X754887Y42406D01*
X754987Y42326D01*
X755067Y42226D01*
X755127Y42116D01*
X755167Y41991D01*
X755177Y41866D01*
Y39436D01*
X755207Y39406D01*
X755307Y39266D01*
X755327Y39226D01*
X755342Y39191D01*
X755362Y39151D01*
X755377Y39111D01*
X755387Y39071D01*
X755402Y39026D01*
X755407Y38986D01*
X755417Y38946D01*
X755422Y38901D01*
Y38861D01*
X755427Y38816D01*
X755422Y38771D01*
Y38731D01*
X755417Y38686D01*
X755407Y38646D01*
X755402Y38606D01*
X755387Y38561D01*
X755377Y38521D01*
X755362Y38481D01*
X755342Y38441D01*
X755327Y38406D01*
X755307Y38366D01*
X755207Y38226D01*
X755177Y38196D01*
Y36066D01*
X755167Y35941D01*
X755127Y35816D01*
X755067Y35706D01*
X754987Y35606D01*
X754887Y35526D01*
X754777Y35466D01*
X754652Y35426D01*
X754527Y35416D01*
G37*
G36*
G01X749803D02*
X749678Y35426D01*
X749553Y35466D01*
X749443Y35526D01*
X749343Y35606D01*
X749263Y35706D01*
X749203Y35816D01*
X749163Y35941D01*
X749153Y36066D01*
Y38191D01*
X749123Y38221D01*
X749098Y38256D01*
X749068Y38291D01*
X749048Y38326D01*
X749023Y38361D01*
X748983Y38441D01*
X748938Y38561D01*
X748928Y38601D01*
X748918Y38646D01*
X748913Y38686D01*
X748903Y38731D01*
Y38901D01*
X748913Y38946D01*
X748918Y38986D01*
X748928Y39031D01*
X748938Y39071D01*
X748983Y39191D01*
X749023Y39271D01*
X749048Y39306D01*
X749068Y39341D01*
X749098Y39376D01*
X749123Y39411D01*
X749153Y39441D01*
Y41866D01*
X749163Y41991D01*
X749203Y42116D01*
X749263Y42226D01*
X749343Y42326D01*
X749443Y42406D01*
X749553Y42466D01*
X749678Y42506D01*
X749803Y42516D01*
X749928Y42506D01*
X750053Y42466D01*
X750163Y42406D01*
X750263Y42326D01*
X750343Y42226D01*
X750403Y42116D01*
X750443Y41991D01*
X750453Y41866D01*
Y39436D01*
X750483Y39406D01*
X750583Y39266D01*
X750603Y39226D01*
X750618Y39191D01*
X750638Y39151D01*
X750653Y39111D01*
X750663Y39071D01*
X750678Y39026D01*
X750683Y38986D01*
X750693Y38946D01*
X750698Y38901D01*
Y38861D01*
X750703Y38816D01*
X750698Y38771D01*
Y38731D01*
X750693Y38686D01*
X750683Y38646D01*
X750678Y38606D01*
X750663Y38561D01*
X750653Y38521D01*
X750638Y38481D01*
X750618Y38441D01*
X750603Y38406D01*
X750583Y38366D01*
X750483Y38226D01*
X750453Y38196D01*
Y36066D01*
X750443Y35941D01*
X750403Y35816D01*
X750343Y35706D01*
X750263Y35606D01*
X750163Y35526D01*
X750053Y35466D01*
X749928Y35426D01*
X749803Y35416D01*
G37*
G36*
G01X745078D02*
X744953Y35426D01*
X744828Y35466D01*
X744718Y35526D01*
X744618Y35606D01*
X744538Y35706D01*
X744478Y35816D01*
X744438Y35941D01*
X744428Y36066D01*
Y38191D01*
X744398Y38221D01*
X744373Y38256D01*
X744343Y38291D01*
X744323Y38326D01*
X744298Y38361D01*
X744258Y38441D01*
X744213Y38561D01*
X744203Y38601D01*
X744193Y38646D01*
X744188Y38686D01*
X744178Y38731D01*
Y38901D01*
X744188Y38946D01*
X744193Y38986D01*
X744203Y39031D01*
X744213Y39071D01*
X744258Y39191D01*
X744298Y39271D01*
X744323Y39306D01*
X744343Y39341D01*
X744373Y39376D01*
X744398Y39411D01*
X744428Y39441D01*
Y41866D01*
X744438Y41991D01*
X744478Y42116D01*
X744538Y42226D01*
X744618Y42326D01*
X744718Y42406D01*
X744828Y42466D01*
X744953Y42506D01*
X745078Y42516D01*
X745203Y42506D01*
X745328Y42466D01*
X745438Y42406D01*
X745538Y42326D01*
X745618Y42226D01*
X745678Y42116D01*
X745718Y41991D01*
X745728Y41866D01*
Y39436D01*
X745758Y39406D01*
X745858Y39266D01*
X745878Y39226D01*
X745893Y39191D01*
X745913Y39151D01*
X745928Y39111D01*
X745938Y39071D01*
X745953Y39026D01*
X745958Y38986D01*
X745968Y38946D01*
X745973Y38901D01*
Y38861D01*
X745978Y38816D01*
X745973Y38771D01*
Y38731D01*
X745968Y38686D01*
X745958Y38646D01*
X745953Y38606D01*
X745938Y38561D01*
X745928Y38521D01*
X745913Y38481D01*
X745893Y38441D01*
X745878Y38406D01*
X745858Y38366D01*
X745758Y38226D01*
X745728Y38196D01*
Y36066D01*
X745718Y35941D01*
X745678Y35816D01*
X745618Y35706D01*
X745538Y35606D01*
X745438Y35526D01*
X745328Y35466D01*
X745203Y35426D01*
X745078Y35416D01*
G37*
G54D120*
X662362Y167248D03*
X653638D03*
X662362Y160752D03*
X653638D03*
G36*
G01X506496Y35416D02*
X506371Y35426D01*
X506246Y35466D01*
X506136Y35526D01*
X506036Y35606D01*
X505956Y35706D01*
X505896Y35816D01*
X505856Y35941D01*
X505846Y36066D01*
Y37196D01*
X505816Y37226D01*
X505716Y37366D01*
X505696Y37406D01*
X505681Y37441D01*
X505661Y37481D01*
X505646Y37521D01*
X505636Y37561D01*
X505621Y37606D01*
X505616Y37646D01*
X505606Y37686D01*
X505601Y37731D01*
Y37771D01*
X505596Y37816D01*
X505601Y37861D01*
Y37901D01*
X505606Y37946D01*
X505616Y37986D01*
X505621Y38026D01*
X505636Y38071D01*
X505646Y38111D01*
X505661Y38151D01*
X505681Y38191D01*
X505696Y38226D01*
X505716Y38266D01*
X505816Y38406D01*
X505846Y38436D01*
Y41866D01*
X505856Y41991D01*
X505896Y42116D01*
X505956Y42226D01*
X506036Y42326D01*
X506136Y42406D01*
X506246Y42466D01*
X506371Y42506D01*
X506496Y42516D01*
X506621Y42506D01*
X506746Y42466D01*
X506856Y42406D01*
X506956Y42326D01*
X507036Y42226D01*
X507096Y42116D01*
X507136Y41991D01*
X507146Y41866D01*
Y38436D01*
X507176Y38406D01*
X507276Y38266D01*
X507296Y38226D01*
X507311Y38191D01*
X507331Y38151D01*
X507346Y38111D01*
X507356Y38071D01*
X507371Y38026D01*
X507376Y37986D01*
X507386Y37946D01*
X507391Y37901D01*
Y37861D01*
X507396Y37816D01*
X507391Y37771D01*
Y37731D01*
X507386Y37686D01*
X507376Y37646D01*
X507371Y37606D01*
X507356Y37561D01*
X507346Y37521D01*
X507331Y37481D01*
X507311Y37441D01*
X507296Y37406D01*
X507276Y37366D01*
X507176Y37226D01*
X507146Y37196D01*
Y36066D01*
X507136Y35941D01*
X507096Y35816D01*
X507036Y35706D01*
X506956Y35606D01*
X506856Y35526D01*
X506746Y35466D01*
X506621Y35426D01*
X506496Y35416D01*
G37*
G36*
G01X525393D02*
X525268Y35426D01*
X525143Y35466D01*
X525033Y35526D01*
X524933Y35606D01*
X524853Y35706D01*
X524793Y35816D01*
X524753Y35941D01*
X524743Y36066D01*
Y37196D01*
X524713Y37226D01*
X524613Y37366D01*
X524593Y37406D01*
X524578Y37441D01*
X524558Y37481D01*
X524543Y37521D01*
X524533Y37561D01*
X524518Y37606D01*
X524513Y37646D01*
X524503Y37686D01*
X524498Y37731D01*
Y37771D01*
X524493Y37816D01*
X524498Y37861D01*
Y37901D01*
X524503Y37946D01*
X524513Y37986D01*
X524518Y38026D01*
X524533Y38071D01*
X524543Y38111D01*
X524558Y38151D01*
X524578Y38191D01*
X524593Y38226D01*
X524613Y38266D01*
X524713Y38406D01*
X524743Y38436D01*
Y41866D01*
X524753Y41991D01*
X524793Y42116D01*
X524853Y42226D01*
X524933Y42326D01*
X525033Y42406D01*
X525143Y42466D01*
X525268Y42506D01*
X525393Y42516D01*
X525518Y42506D01*
X525643Y42466D01*
X525753Y42406D01*
X525853Y42326D01*
X525933Y42226D01*
X525993Y42116D01*
X526033Y41991D01*
X526043Y41866D01*
Y38436D01*
X526073Y38406D01*
X526173Y38266D01*
X526193Y38226D01*
X526208Y38191D01*
X526228Y38151D01*
X526243Y38111D01*
X526253Y38071D01*
X526268Y38026D01*
X526273Y37986D01*
X526283Y37946D01*
X526288Y37901D01*
Y37861D01*
X526293Y37816D01*
X526288Y37771D01*
Y37731D01*
X526283Y37686D01*
X526273Y37646D01*
X526268Y37606D01*
X526253Y37561D01*
X526243Y37521D01*
X526228Y37481D01*
X526208Y37441D01*
X526193Y37406D01*
X526173Y37366D01*
X526073Y37226D01*
X526043Y37196D01*
Y36066D01*
X526033Y35941D01*
X525993Y35816D01*
X525933Y35706D01*
X525853Y35606D01*
X525753Y35526D01*
X525643Y35466D01*
X525518Y35426D01*
X525393Y35416D01*
G37*
G36*
G01X520669D02*
X520544Y35426D01*
X520419Y35466D01*
X520309Y35526D01*
X520209Y35606D01*
X520129Y35706D01*
X520069Y35816D01*
X520029Y35941D01*
X520019Y36066D01*
Y37196D01*
X519989Y37226D01*
X519889Y37366D01*
X519869Y37406D01*
X519854Y37441D01*
X519834Y37481D01*
X519819Y37521D01*
X519809Y37561D01*
X519794Y37606D01*
X519789Y37646D01*
X519779Y37686D01*
X519774Y37731D01*
Y37771D01*
X519769Y37816D01*
X519774Y37861D01*
Y37901D01*
X519779Y37946D01*
X519789Y37986D01*
X519794Y38026D01*
X519809Y38071D01*
X519819Y38111D01*
X519834Y38151D01*
X519854Y38191D01*
X519869Y38226D01*
X519889Y38266D01*
X519989Y38406D01*
X520019Y38436D01*
Y41866D01*
X520029Y41991D01*
X520069Y42116D01*
X520129Y42226D01*
X520209Y42326D01*
X520309Y42406D01*
X520419Y42466D01*
X520544Y42506D01*
X520669Y42516D01*
X520794Y42506D01*
X520919Y42466D01*
X521029Y42406D01*
X521129Y42326D01*
X521209Y42226D01*
X521269Y42116D01*
X521309Y41991D01*
X521319Y41866D01*
Y38436D01*
X521349Y38406D01*
X521449Y38266D01*
X521469Y38226D01*
X521484Y38191D01*
X521504Y38151D01*
X521519Y38111D01*
X521529Y38071D01*
X521544Y38026D01*
X521549Y37986D01*
X521559Y37946D01*
X521564Y37901D01*
Y37861D01*
X521569Y37816D01*
X521564Y37771D01*
Y37731D01*
X521559Y37686D01*
X521549Y37646D01*
X521544Y37606D01*
X521529Y37561D01*
X521519Y37521D01*
X521504Y37481D01*
X521484Y37441D01*
X521469Y37406D01*
X521449Y37366D01*
X521349Y37226D01*
X521319Y37196D01*
Y36066D01*
X521309Y35941D01*
X521269Y35816D01*
X521209Y35706D01*
X521129Y35606D01*
X521029Y35526D01*
X520919Y35466D01*
X520794Y35426D01*
X520669Y35416D01*
G37*
G36*
G01X515945D02*
X515820Y35426D01*
X515695Y35466D01*
X515585Y35526D01*
X515485Y35606D01*
X515405Y35706D01*
X515345Y35816D01*
X515305Y35941D01*
X515295Y36066D01*
Y37196D01*
X515265Y37226D01*
X515165Y37366D01*
X515145Y37406D01*
X515130Y37441D01*
X515110Y37481D01*
X515095Y37521D01*
X515085Y37561D01*
X515070Y37606D01*
X515065Y37646D01*
X515055Y37686D01*
X515050Y37731D01*
Y37771D01*
X515045Y37816D01*
X515050Y37861D01*
Y37901D01*
X515055Y37946D01*
X515065Y37986D01*
X515070Y38026D01*
X515085Y38071D01*
X515095Y38111D01*
X515110Y38151D01*
X515130Y38191D01*
X515145Y38226D01*
X515165Y38266D01*
X515265Y38406D01*
X515295Y38436D01*
Y41866D01*
X515305Y41991D01*
X515345Y42116D01*
X515405Y42226D01*
X515485Y42326D01*
X515585Y42406D01*
X515695Y42466D01*
X515820Y42506D01*
X515945Y42516D01*
X516070Y42506D01*
X516195Y42466D01*
X516305Y42406D01*
X516405Y42326D01*
X516485Y42226D01*
X516545Y42116D01*
X516585Y41991D01*
X516595Y41866D01*
Y38436D01*
X516625Y38406D01*
X516725Y38266D01*
X516745Y38226D01*
X516760Y38191D01*
X516780Y38151D01*
X516795Y38111D01*
X516805Y38071D01*
X516820Y38026D01*
X516825Y37986D01*
X516835Y37946D01*
X516840Y37901D01*
Y37861D01*
X516845Y37816D01*
X516840Y37771D01*
Y37731D01*
X516835Y37686D01*
X516825Y37646D01*
X516820Y37606D01*
X516805Y37561D01*
X516795Y37521D01*
X516780Y37481D01*
X516760Y37441D01*
X516745Y37406D01*
X516725Y37366D01*
X516625Y37226D01*
X516595Y37196D01*
Y36066D01*
X516585Y35941D01*
X516545Y35816D01*
X516485Y35706D01*
X516405Y35606D01*
X516305Y35526D01*
X516195Y35466D01*
X516070Y35426D01*
X515945Y35416D01*
G37*
G36*
G01X511220D02*
X511095Y35426D01*
X510970Y35466D01*
X510860Y35526D01*
X510760Y35606D01*
X510680Y35706D01*
X510620Y35816D01*
X510580Y35941D01*
X510570Y36066D01*
Y37196D01*
X510540Y37226D01*
X510440Y37366D01*
X510420Y37406D01*
X510405Y37441D01*
X510385Y37481D01*
X510370Y37521D01*
X510360Y37561D01*
X510345Y37606D01*
X510340Y37646D01*
X510330Y37686D01*
X510325Y37731D01*
Y37771D01*
X510320Y37816D01*
X510325Y37861D01*
Y37901D01*
X510330Y37946D01*
X510340Y37986D01*
X510345Y38026D01*
X510360Y38071D01*
X510370Y38111D01*
X510385Y38151D01*
X510405Y38191D01*
X510420Y38226D01*
X510440Y38266D01*
X510540Y38406D01*
X510570Y38436D01*
Y41866D01*
X510580Y41991D01*
X510620Y42116D01*
X510680Y42226D01*
X510760Y42326D01*
X510860Y42406D01*
X510970Y42466D01*
X511095Y42506D01*
X511220Y42516D01*
X511345Y42506D01*
X511470Y42466D01*
X511580Y42406D01*
X511680Y42326D01*
X511760Y42226D01*
X511820Y42116D01*
X511860Y41991D01*
X511870Y41866D01*
Y38436D01*
X511900Y38406D01*
X512000Y38266D01*
X512020Y38226D01*
X512035Y38191D01*
X512055Y38151D01*
X512070Y38111D01*
X512080Y38071D01*
X512095Y38026D01*
X512100Y37986D01*
X512110Y37946D01*
X512115Y37901D01*
Y37861D01*
X512120Y37816D01*
X512115Y37771D01*
Y37731D01*
X512110Y37686D01*
X512100Y37646D01*
X512095Y37606D01*
X512080Y37561D01*
X512070Y37521D01*
X512055Y37481D01*
X512035Y37441D01*
X512020Y37406D01*
X512000Y37366D01*
X511900Y37226D01*
X511870Y37196D01*
Y36066D01*
X511860Y35941D01*
X511820Y35816D01*
X511760Y35706D01*
X511680Y35606D01*
X511580Y35526D01*
X511470Y35466D01*
X511345Y35426D01*
X511220Y35416D01*
G37*
G36*
G01X539567D02*
X539442Y35426D01*
X539317Y35466D01*
X539207Y35526D01*
X539107Y35606D01*
X539027Y35706D01*
X538967Y35816D01*
X538927Y35941D01*
X538917Y36066D01*
Y37196D01*
X538887Y37226D01*
X538787Y37366D01*
X538767Y37406D01*
X538752Y37441D01*
X538732Y37481D01*
X538717Y37521D01*
X538707Y37561D01*
X538692Y37606D01*
X538687Y37646D01*
X538677Y37686D01*
X538672Y37731D01*
Y37771D01*
X538667Y37816D01*
X538672Y37861D01*
Y37901D01*
X538677Y37946D01*
X538687Y37986D01*
X538692Y38026D01*
X538707Y38071D01*
X538717Y38111D01*
X538732Y38151D01*
X538752Y38191D01*
X538767Y38226D01*
X538787Y38266D01*
X538887Y38406D01*
X538917Y38436D01*
Y41866D01*
X538927Y41991D01*
X538967Y42116D01*
X539027Y42226D01*
X539107Y42326D01*
X539207Y42406D01*
X539317Y42466D01*
X539442Y42506D01*
X539567Y42516D01*
X539692Y42506D01*
X539817Y42466D01*
X539927Y42406D01*
X540027Y42326D01*
X540107Y42226D01*
X540167Y42116D01*
X540207Y41991D01*
X540217Y41866D01*
Y38436D01*
X540247Y38406D01*
X540347Y38266D01*
X540367Y38226D01*
X540382Y38191D01*
X540402Y38151D01*
X540417Y38111D01*
X540427Y38071D01*
X540442Y38026D01*
X540447Y37986D01*
X540457Y37946D01*
X540462Y37901D01*
Y37861D01*
X540467Y37816D01*
X540462Y37771D01*
Y37731D01*
X540457Y37686D01*
X540447Y37646D01*
X540442Y37606D01*
X540427Y37561D01*
X540417Y37521D01*
X540402Y37481D01*
X540382Y37441D01*
X540367Y37406D01*
X540347Y37366D01*
X540247Y37226D01*
X540217Y37196D01*
Y36066D01*
X540207Y35941D01*
X540167Y35816D01*
X540107Y35706D01*
X540027Y35606D01*
X539927Y35526D01*
X539817Y35466D01*
X539692Y35426D01*
X539567Y35416D01*
G37*
G36*
G01X534842D02*
X534717Y35426D01*
X534592Y35466D01*
X534482Y35526D01*
X534382Y35606D01*
X534302Y35706D01*
X534242Y35816D01*
X534202Y35941D01*
X534192Y36066D01*
Y37196D01*
X534162Y37226D01*
X534062Y37366D01*
X534042Y37406D01*
X534027Y37441D01*
X534007Y37481D01*
X533992Y37521D01*
X533982Y37561D01*
X533967Y37606D01*
X533962Y37646D01*
X533952Y37686D01*
X533947Y37731D01*
Y37771D01*
X533942Y37816D01*
X533947Y37861D01*
Y37901D01*
X533952Y37946D01*
X533962Y37986D01*
X533967Y38026D01*
X533982Y38071D01*
X533992Y38111D01*
X534007Y38151D01*
X534027Y38191D01*
X534042Y38226D01*
X534062Y38266D01*
X534162Y38406D01*
X534192Y38436D01*
Y41866D01*
X534202Y41991D01*
X534242Y42116D01*
X534302Y42226D01*
X534382Y42326D01*
X534482Y42406D01*
X534592Y42466D01*
X534717Y42506D01*
X534842Y42516D01*
X534967Y42506D01*
X535092Y42466D01*
X535202Y42406D01*
X535302Y42326D01*
X535382Y42226D01*
X535442Y42116D01*
X535482Y41991D01*
X535492Y41866D01*
Y38436D01*
X535522Y38406D01*
X535622Y38266D01*
X535642Y38226D01*
X535657Y38191D01*
X535677Y38151D01*
X535692Y38111D01*
X535702Y38071D01*
X535717Y38026D01*
X535722Y37986D01*
X535732Y37946D01*
X535737Y37901D01*
Y37861D01*
X535742Y37816D01*
X535737Y37771D01*
Y37731D01*
X535732Y37686D01*
X535722Y37646D01*
X535717Y37606D01*
X535702Y37561D01*
X535692Y37521D01*
X535677Y37481D01*
X535657Y37441D01*
X535642Y37406D01*
X535622Y37366D01*
X535522Y37226D01*
X535492Y37196D01*
Y36066D01*
X535482Y35941D01*
X535442Y35816D01*
X535382Y35706D01*
X535302Y35606D01*
X535202Y35526D01*
X535092Y35466D01*
X534967Y35426D01*
X534842Y35416D01*
G37*
G36*
G01X530118D02*
X529993Y35426D01*
X529868Y35466D01*
X529758Y35526D01*
X529658Y35606D01*
X529578Y35706D01*
X529518Y35816D01*
X529478Y35941D01*
X529468Y36066D01*
Y37196D01*
X529438Y37226D01*
X529338Y37366D01*
X529318Y37406D01*
X529303Y37441D01*
X529283Y37481D01*
X529268Y37521D01*
X529258Y37561D01*
X529243Y37606D01*
X529238Y37646D01*
X529228Y37686D01*
X529223Y37731D01*
Y37771D01*
X529218Y37816D01*
X529223Y37861D01*
Y37901D01*
X529228Y37946D01*
X529238Y37986D01*
X529243Y38026D01*
X529258Y38071D01*
X529268Y38111D01*
X529283Y38151D01*
X529303Y38191D01*
X529318Y38226D01*
X529338Y38266D01*
X529438Y38406D01*
X529468Y38436D01*
Y41866D01*
X529478Y41991D01*
X529518Y42116D01*
X529578Y42226D01*
X529658Y42326D01*
X529758Y42406D01*
X529868Y42466D01*
X529993Y42506D01*
X530118Y42516D01*
X530243Y42506D01*
X530368Y42466D01*
X530478Y42406D01*
X530578Y42326D01*
X530658Y42226D01*
X530718Y42116D01*
X530758Y41991D01*
X530768Y41866D01*
Y38436D01*
X530798Y38406D01*
X530898Y38266D01*
X530918Y38226D01*
X530933Y38191D01*
X530953Y38151D01*
X530968Y38111D01*
X530978Y38071D01*
X530993Y38026D01*
X530998Y37986D01*
X531008Y37946D01*
X531013Y37901D01*
Y37861D01*
X531018Y37816D01*
X531013Y37771D01*
Y37731D01*
X531008Y37686D01*
X530998Y37646D01*
X530993Y37606D01*
X530978Y37561D01*
X530968Y37521D01*
X530953Y37481D01*
X530933Y37441D01*
X530918Y37406D01*
X530898Y37366D01*
X530798Y37226D01*
X530768Y37196D01*
Y36066D01*
X530758Y35941D01*
X530718Y35816D01*
X530658Y35706D01*
X530578Y35606D01*
X530478Y35526D01*
X530368Y35466D01*
X530243Y35426D01*
X530118Y35416D01*
G37*
G36*
G01X553740D02*
X553615Y35426D01*
X553490Y35466D01*
X553380Y35526D01*
X553280Y35606D01*
X553200Y35706D01*
X553140Y35816D01*
X553100Y35941D01*
X553090Y36066D01*
Y37196D01*
X553060Y37226D01*
X552960Y37366D01*
X552940Y37406D01*
X552925Y37441D01*
X552905Y37481D01*
X552890Y37521D01*
X552880Y37561D01*
X552865Y37606D01*
X552860Y37646D01*
X552850Y37686D01*
X552845Y37731D01*
Y37771D01*
X552840Y37816D01*
X552845Y37861D01*
Y37901D01*
X552850Y37946D01*
X552860Y37986D01*
X552865Y38026D01*
X552880Y38071D01*
X552890Y38111D01*
X552905Y38151D01*
X552925Y38191D01*
X552940Y38226D01*
X552960Y38266D01*
X553060Y38406D01*
X553090Y38436D01*
Y41866D01*
X553100Y41991D01*
X553140Y42116D01*
X553200Y42226D01*
X553280Y42326D01*
X553380Y42406D01*
X553490Y42466D01*
X553615Y42506D01*
X553740Y42516D01*
X553865Y42506D01*
X553990Y42466D01*
X554100Y42406D01*
X554200Y42326D01*
X554280Y42226D01*
X554340Y42116D01*
X554380Y41991D01*
X554390Y41866D01*
Y38436D01*
X554420Y38406D01*
X554520Y38266D01*
X554540Y38226D01*
X554555Y38191D01*
X554575Y38151D01*
X554590Y38111D01*
X554600Y38071D01*
X554615Y38026D01*
X554620Y37986D01*
X554630Y37946D01*
X554635Y37901D01*
Y37861D01*
X554640Y37816D01*
X554635Y37771D01*
Y37731D01*
X554630Y37686D01*
X554620Y37646D01*
X554615Y37606D01*
X554600Y37561D01*
X554590Y37521D01*
X554575Y37481D01*
X554555Y37441D01*
X554540Y37406D01*
X554520Y37366D01*
X554420Y37226D01*
X554390Y37196D01*
Y36066D01*
X554380Y35941D01*
X554340Y35816D01*
X554280Y35706D01*
X554200Y35606D01*
X554100Y35526D01*
X553990Y35466D01*
X553865Y35426D01*
X553740Y35416D01*
G37*
G36*
G01X549015D02*
X548890Y35426D01*
X548765Y35466D01*
X548655Y35526D01*
X548555Y35606D01*
X548475Y35706D01*
X548415Y35816D01*
X548375Y35941D01*
X548365Y36066D01*
Y37196D01*
X548335Y37226D01*
X548235Y37366D01*
X548215Y37406D01*
X548200Y37441D01*
X548180Y37481D01*
X548165Y37521D01*
X548155Y37561D01*
X548140Y37606D01*
X548135Y37646D01*
X548125Y37686D01*
X548120Y37731D01*
Y37771D01*
X548115Y37816D01*
X548120Y37861D01*
Y37901D01*
X548125Y37946D01*
X548135Y37986D01*
X548140Y38026D01*
X548155Y38071D01*
X548165Y38111D01*
X548180Y38151D01*
X548200Y38191D01*
X548215Y38226D01*
X548235Y38266D01*
X548335Y38406D01*
X548365Y38436D01*
Y41866D01*
X548375Y41991D01*
X548415Y42116D01*
X548475Y42226D01*
X548555Y42326D01*
X548655Y42406D01*
X548765Y42466D01*
X548890Y42506D01*
X549015Y42516D01*
X549140Y42506D01*
X549265Y42466D01*
X549375Y42406D01*
X549475Y42326D01*
X549555Y42226D01*
X549615Y42116D01*
X549655Y41991D01*
X549665Y41866D01*
Y38436D01*
X549695Y38406D01*
X549795Y38266D01*
X549815Y38226D01*
X549830Y38191D01*
X549850Y38151D01*
X549865Y38111D01*
X549875Y38071D01*
X549890Y38026D01*
X549895Y37986D01*
X549905Y37946D01*
X549910Y37901D01*
Y37861D01*
X549915Y37816D01*
X549910Y37771D01*
Y37731D01*
X549905Y37686D01*
X549895Y37646D01*
X549890Y37606D01*
X549875Y37561D01*
X549865Y37521D01*
X549850Y37481D01*
X549830Y37441D01*
X549815Y37406D01*
X549795Y37366D01*
X549695Y37226D01*
X549665Y37196D01*
Y36066D01*
X549655Y35941D01*
X549615Y35816D01*
X549555Y35706D01*
X549475Y35606D01*
X549375Y35526D01*
X549265Y35466D01*
X549140Y35426D01*
X549015Y35416D01*
G37*
G36*
G01X544291D02*
X544166Y35426D01*
X544041Y35466D01*
X543931Y35526D01*
X543831Y35606D01*
X543751Y35706D01*
X543691Y35816D01*
X543651Y35941D01*
X543641Y36066D01*
Y37196D01*
X543611Y37226D01*
X543511Y37366D01*
X543491Y37406D01*
X543476Y37441D01*
X543456Y37481D01*
X543441Y37521D01*
X543431Y37561D01*
X543416Y37606D01*
X543411Y37646D01*
X543401Y37686D01*
X543396Y37731D01*
Y37771D01*
X543391Y37816D01*
X543396Y37861D01*
Y37901D01*
X543401Y37946D01*
X543411Y37986D01*
X543416Y38026D01*
X543431Y38071D01*
X543441Y38111D01*
X543456Y38151D01*
X543476Y38191D01*
X543491Y38226D01*
X543511Y38266D01*
X543611Y38406D01*
X543641Y38436D01*
Y41866D01*
X543651Y41991D01*
X543691Y42116D01*
X543751Y42226D01*
X543831Y42326D01*
X543931Y42406D01*
X544041Y42466D01*
X544166Y42506D01*
X544291Y42516D01*
X544416Y42506D01*
X544541Y42466D01*
X544651Y42406D01*
X544751Y42326D01*
X544831Y42226D01*
X544891Y42116D01*
X544931Y41991D01*
X544941Y41866D01*
Y38436D01*
X544971Y38406D01*
X545071Y38266D01*
X545091Y38226D01*
X545106Y38191D01*
X545126Y38151D01*
X545141Y38111D01*
X545151Y38071D01*
X545166Y38026D01*
X545171Y37986D01*
X545181Y37946D01*
X545186Y37901D01*
Y37861D01*
X545191Y37816D01*
X545186Y37771D01*
Y37731D01*
X545181Y37686D01*
X545171Y37646D01*
X545166Y37606D01*
X545151Y37561D01*
X545141Y37521D01*
X545126Y37481D01*
X545106Y37441D01*
X545091Y37406D01*
X545071Y37366D01*
X544971Y37226D01*
X544941Y37196D01*
Y36066D01*
X544931Y35941D01*
X544891Y35816D01*
X544831Y35706D01*
X544751Y35606D01*
X544651Y35526D01*
X544541Y35466D01*
X544416Y35426D01*
X544291Y35416D01*
G37*
G36*
G01X572638D02*
X572513Y35426D01*
X572388Y35466D01*
X572278Y35526D01*
X572178Y35606D01*
X572098Y35706D01*
X572038Y35816D01*
X571998Y35941D01*
X571988Y36066D01*
Y37196D01*
X571958Y37226D01*
X571858Y37366D01*
X571838Y37406D01*
X571823Y37441D01*
X571803Y37481D01*
X571788Y37521D01*
X571778Y37561D01*
X571763Y37606D01*
X571758Y37646D01*
X571748Y37686D01*
X571743Y37731D01*
Y37771D01*
X571738Y37816D01*
X571743Y37861D01*
Y37901D01*
X571748Y37946D01*
X571758Y37986D01*
X571763Y38026D01*
X571778Y38071D01*
X571788Y38111D01*
X571803Y38151D01*
X571823Y38191D01*
X571838Y38226D01*
X571858Y38266D01*
X571958Y38406D01*
X571988Y38436D01*
Y41866D01*
X571998Y41991D01*
X572038Y42116D01*
X572098Y42226D01*
X572178Y42326D01*
X572278Y42406D01*
X572388Y42466D01*
X572513Y42506D01*
X572638Y42516D01*
X572763Y42506D01*
X572888Y42466D01*
X572998Y42406D01*
X573098Y42326D01*
X573178Y42226D01*
X573238Y42116D01*
X573278Y41991D01*
X573288Y41866D01*
Y38436D01*
X573318Y38406D01*
X573418Y38266D01*
X573438Y38226D01*
X573453Y38191D01*
X573473Y38151D01*
X573488Y38111D01*
X573498Y38071D01*
X573513Y38026D01*
X573518Y37986D01*
X573528Y37946D01*
X573533Y37901D01*
Y37861D01*
X573538Y37816D01*
X573533Y37771D01*
Y37731D01*
X573528Y37686D01*
X573518Y37646D01*
X573513Y37606D01*
X573498Y37561D01*
X573488Y37521D01*
X573473Y37481D01*
X573453Y37441D01*
X573438Y37406D01*
X573418Y37366D01*
X573318Y37226D01*
X573288Y37196D01*
Y36066D01*
X573278Y35941D01*
X573238Y35816D01*
X573178Y35706D01*
X573098Y35606D01*
X572998Y35526D01*
X572888Y35466D01*
X572763Y35426D01*
X572638Y35416D01*
G37*
G36*
G01X567913D02*
X567788Y35426D01*
X567663Y35466D01*
X567553Y35526D01*
X567453Y35606D01*
X567373Y35706D01*
X567313Y35816D01*
X567273Y35941D01*
X567263Y36066D01*
Y37196D01*
X567233Y37226D01*
X567133Y37366D01*
X567113Y37406D01*
X567098Y37441D01*
X567078Y37481D01*
X567063Y37521D01*
X567053Y37561D01*
X567038Y37606D01*
X567033Y37646D01*
X567023Y37686D01*
X567018Y37731D01*
Y37771D01*
X567013Y37816D01*
X567018Y37861D01*
Y37901D01*
X567023Y37946D01*
X567033Y37986D01*
X567038Y38026D01*
X567053Y38071D01*
X567063Y38111D01*
X567078Y38151D01*
X567098Y38191D01*
X567113Y38226D01*
X567133Y38266D01*
X567233Y38406D01*
X567263Y38436D01*
Y41866D01*
X567273Y41991D01*
X567313Y42116D01*
X567373Y42226D01*
X567453Y42326D01*
X567553Y42406D01*
X567663Y42466D01*
X567788Y42506D01*
X567913Y42516D01*
X568038Y42506D01*
X568163Y42466D01*
X568273Y42406D01*
X568373Y42326D01*
X568453Y42226D01*
X568513Y42116D01*
X568553Y41991D01*
X568563Y41866D01*
Y38436D01*
X568593Y38406D01*
X568693Y38266D01*
X568713Y38226D01*
X568728Y38191D01*
X568748Y38151D01*
X568763Y38111D01*
X568773Y38071D01*
X568788Y38026D01*
X568793Y37986D01*
X568803Y37946D01*
X568808Y37901D01*
Y37861D01*
X568813Y37816D01*
X568808Y37771D01*
Y37731D01*
X568803Y37686D01*
X568793Y37646D01*
X568788Y37606D01*
X568773Y37561D01*
X568763Y37521D01*
X568748Y37481D01*
X568728Y37441D01*
X568713Y37406D01*
X568693Y37366D01*
X568593Y37226D01*
X568563Y37196D01*
Y36066D01*
X568553Y35941D01*
X568513Y35816D01*
X568453Y35706D01*
X568373Y35606D01*
X568273Y35526D01*
X568163Y35466D01*
X568038Y35426D01*
X567913Y35416D01*
G37*
G36*
G01X563189D02*
X563064Y35426D01*
X562939Y35466D01*
X562829Y35526D01*
X562729Y35606D01*
X562649Y35706D01*
X562589Y35816D01*
X562549Y35941D01*
X562539Y36066D01*
Y37196D01*
X562509Y37226D01*
X562409Y37366D01*
X562389Y37406D01*
X562374Y37441D01*
X562354Y37481D01*
X562339Y37521D01*
X562329Y37561D01*
X562314Y37606D01*
X562309Y37646D01*
X562299Y37686D01*
X562294Y37731D01*
Y37771D01*
X562289Y37816D01*
X562294Y37861D01*
Y37901D01*
X562299Y37946D01*
X562309Y37986D01*
X562314Y38026D01*
X562329Y38071D01*
X562339Y38111D01*
X562354Y38151D01*
X562374Y38191D01*
X562389Y38226D01*
X562409Y38266D01*
X562509Y38406D01*
X562539Y38436D01*
Y41866D01*
X562549Y41991D01*
X562589Y42116D01*
X562649Y42226D01*
X562729Y42326D01*
X562829Y42406D01*
X562939Y42466D01*
X563064Y42506D01*
X563189Y42516D01*
X563314Y42506D01*
X563439Y42466D01*
X563549Y42406D01*
X563649Y42326D01*
X563729Y42226D01*
X563789Y42116D01*
X563829Y41991D01*
X563839Y41866D01*
Y38436D01*
X563869Y38406D01*
X563969Y38266D01*
X563989Y38226D01*
X564004Y38191D01*
X564024Y38151D01*
X564039Y38111D01*
X564049Y38071D01*
X564064Y38026D01*
X564069Y37986D01*
X564079Y37946D01*
X564084Y37901D01*
Y37861D01*
X564089Y37816D01*
X564084Y37771D01*
Y37731D01*
X564079Y37686D01*
X564069Y37646D01*
X564064Y37606D01*
X564049Y37561D01*
X564039Y37521D01*
X564024Y37481D01*
X564004Y37441D01*
X563989Y37406D01*
X563969Y37366D01*
X563869Y37226D01*
X563839Y37196D01*
Y36066D01*
X563829Y35941D01*
X563789Y35816D01*
X563729Y35706D01*
X563649Y35606D01*
X563549Y35526D01*
X563439Y35466D01*
X563314Y35426D01*
X563189Y35416D01*
G37*
G36*
G01X558464D02*
X558339Y35426D01*
X558214Y35466D01*
X558104Y35526D01*
X558004Y35606D01*
X557924Y35706D01*
X557864Y35816D01*
X557824Y35941D01*
X557814Y36066D01*
Y37196D01*
X557784Y37226D01*
X557684Y37366D01*
X557664Y37406D01*
X557649Y37441D01*
X557629Y37481D01*
X557614Y37521D01*
X557604Y37561D01*
X557589Y37606D01*
X557584Y37646D01*
X557574Y37686D01*
X557569Y37731D01*
Y37771D01*
X557564Y37816D01*
X557569Y37861D01*
Y37901D01*
X557574Y37946D01*
X557584Y37986D01*
X557589Y38026D01*
X557604Y38071D01*
X557614Y38111D01*
X557629Y38151D01*
X557649Y38191D01*
X557664Y38226D01*
X557684Y38266D01*
X557784Y38406D01*
X557814Y38436D01*
Y41866D01*
X557824Y41991D01*
X557864Y42116D01*
X557924Y42226D01*
X558004Y42326D01*
X558104Y42406D01*
X558214Y42466D01*
X558339Y42506D01*
X558464Y42516D01*
X558589Y42506D01*
X558714Y42466D01*
X558824Y42406D01*
X558924Y42326D01*
X559004Y42226D01*
X559064Y42116D01*
X559104Y41991D01*
X559114Y41866D01*
Y38436D01*
X559144Y38406D01*
X559244Y38266D01*
X559264Y38226D01*
X559279Y38191D01*
X559299Y38151D01*
X559314Y38111D01*
X559324Y38071D01*
X559339Y38026D01*
X559344Y37986D01*
X559354Y37946D01*
X559359Y37901D01*
Y37861D01*
X559364Y37816D01*
X559359Y37771D01*
Y37731D01*
X559354Y37686D01*
X559344Y37646D01*
X559339Y37606D01*
X559324Y37561D01*
X559314Y37521D01*
X559299Y37481D01*
X559279Y37441D01*
X559264Y37406D01*
X559244Y37366D01*
X559144Y37226D01*
X559114Y37196D01*
Y36066D01*
X559104Y35941D01*
X559064Y35816D01*
X559004Y35706D01*
X558924Y35606D01*
X558824Y35526D01*
X558714Y35466D01*
X558589Y35426D01*
X558464Y35416D01*
G37*
G36*
G01X586811D02*
X586686Y35426D01*
X586561Y35466D01*
X586451Y35526D01*
X586351Y35606D01*
X586271Y35706D01*
X586211Y35816D01*
X586171Y35941D01*
X586161Y36066D01*
Y37196D01*
X586131Y37226D01*
X586031Y37366D01*
X586011Y37406D01*
X585996Y37441D01*
X585976Y37481D01*
X585961Y37521D01*
X585951Y37561D01*
X585936Y37606D01*
X585931Y37646D01*
X585921Y37686D01*
X585916Y37731D01*
Y37771D01*
X585911Y37816D01*
X585916Y37861D01*
Y37901D01*
X585921Y37946D01*
X585931Y37986D01*
X585936Y38026D01*
X585951Y38071D01*
X585961Y38111D01*
X585976Y38151D01*
X585996Y38191D01*
X586011Y38226D01*
X586031Y38266D01*
X586131Y38406D01*
X586161Y38436D01*
Y41866D01*
X586171Y41991D01*
X586211Y42116D01*
X586271Y42226D01*
X586351Y42326D01*
X586451Y42406D01*
X586561Y42466D01*
X586686Y42506D01*
X586811Y42516D01*
X586936Y42506D01*
X587061Y42466D01*
X587171Y42406D01*
X587271Y42326D01*
X587351Y42226D01*
X587411Y42116D01*
X587451Y41991D01*
X587461Y41866D01*
Y38436D01*
X587491Y38406D01*
X587591Y38266D01*
X587611Y38226D01*
X587626Y38191D01*
X587646Y38151D01*
X587661Y38111D01*
X587671Y38071D01*
X587686Y38026D01*
X587691Y37986D01*
X587701Y37946D01*
X587706Y37901D01*
Y37861D01*
X587711Y37816D01*
X587706Y37771D01*
Y37731D01*
X587701Y37686D01*
X587691Y37646D01*
X587686Y37606D01*
X587671Y37561D01*
X587661Y37521D01*
X587646Y37481D01*
X587626Y37441D01*
X587611Y37406D01*
X587591Y37366D01*
X587491Y37226D01*
X587461Y37196D01*
Y36066D01*
X587451Y35941D01*
X587411Y35816D01*
X587351Y35706D01*
X587271Y35606D01*
X587171Y35526D01*
X587061Y35466D01*
X586936Y35426D01*
X586811Y35416D01*
G37*
G36*
G01X582086D02*
X581961Y35426D01*
X581836Y35466D01*
X581726Y35526D01*
X581626Y35606D01*
X581546Y35706D01*
X581486Y35816D01*
X581446Y35941D01*
X581436Y36066D01*
Y37196D01*
X581406Y37226D01*
X581306Y37366D01*
X581286Y37406D01*
X581271Y37441D01*
X581251Y37481D01*
X581236Y37521D01*
X581226Y37561D01*
X581211Y37606D01*
X581206Y37646D01*
X581196Y37686D01*
X581191Y37731D01*
Y37771D01*
X581186Y37816D01*
X581191Y37861D01*
Y37901D01*
X581196Y37946D01*
X581206Y37986D01*
X581211Y38026D01*
X581226Y38071D01*
X581236Y38111D01*
X581251Y38151D01*
X581271Y38191D01*
X581286Y38226D01*
X581306Y38266D01*
X581406Y38406D01*
X581436Y38436D01*
Y41866D01*
X581446Y41991D01*
X581486Y42116D01*
X581546Y42226D01*
X581626Y42326D01*
X581726Y42406D01*
X581836Y42466D01*
X581961Y42506D01*
X582086Y42516D01*
X582211Y42506D01*
X582336Y42466D01*
X582446Y42406D01*
X582546Y42326D01*
X582626Y42226D01*
X582686Y42116D01*
X582726Y41991D01*
X582736Y41866D01*
Y38436D01*
X582766Y38406D01*
X582866Y38266D01*
X582886Y38226D01*
X582901Y38191D01*
X582921Y38151D01*
X582936Y38111D01*
X582946Y38071D01*
X582961Y38026D01*
X582966Y37986D01*
X582976Y37946D01*
X582981Y37901D01*
Y37861D01*
X582986Y37816D01*
X582981Y37771D01*
Y37731D01*
X582976Y37686D01*
X582966Y37646D01*
X582961Y37606D01*
X582946Y37561D01*
X582936Y37521D01*
X582921Y37481D01*
X582901Y37441D01*
X582886Y37406D01*
X582866Y37366D01*
X582766Y37226D01*
X582736Y37196D01*
Y36066D01*
X582726Y35941D01*
X582686Y35816D01*
X582626Y35706D01*
X582546Y35606D01*
X582446Y35526D01*
X582336Y35466D01*
X582211Y35426D01*
X582086Y35416D01*
G37*
G36*
G01X577362D02*
X577237Y35426D01*
X577112Y35466D01*
X577002Y35526D01*
X576902Y35606D01*
X576822Y35706D01*
X576762Y35816D01*
X576722Y35941D01*
X576712Y36066D01*
Y37196D01*
X576682Y37226D01*
X576582Y37366D01*
X576562Y37406D01*
X576547Y37441D01*
X576527Y37481D01*
X576512Y37521D01*
X576502Y37561D01*
X576487Y37606D01*
X576482Y37646D01*
X576472Y37686D01*
X576467Y37731D01*
Y37771D01*
X576462Y37816D01*
X576467Y37861D01*
Y37901D01*
X576472Y37946D01*
X576482Y37986D01*
X576487Y38026D01*
X576502Y38071D01*
X576512Y38111D01*
X576527Y38151D01*
X576547Y38191D01*
X576562Y38226D01*
X576582Y38266D01*
X576682Y38406D01*
X576712Y38436D01*
Y41866D01*
X576722Y41991D01*
X576762Y42116D01*
X576822Y42226D01*
X576902Y42326D01*
X577002Y42406D01*
X577112Y42466D01*
X577237Y42506D01*
X577362Y42516D01*
X577487Y42506D01*
X577612Y42466D01*
X577722Y42406D01*
X577822Y42326D01*
X577902Y42226D01*
X577962Y42116D01*
X578002Y41991D01*
X578012Y41866D01*
Y38436D01*
X578042Y38406D01*
X578142Y38266D01*
X578162Y38226D01*
X578177Y38191D01*
X578197Y38151D01*
X578212Y38111D01*
X578222Y38071D01*
X578237Y38026D01*
X578242Y37986D01*
X578252Y37946D01*
X578257Y37901D01*
Y37861D01*
X578262Y37816D01*
X578257Y37771D01*
Y37731D01*
X578252Y37686D01*
X578242Y37646D01*
X578237Y37606D01*
X578222Y37561D01*
X578212Y37521D01*
X578197Y37481D01*
X578177Y37441D01*
X578162Y37406D01*
X578142Y37366D01*
X578042Y37226D01*
X578012Y37196D01*
Y36066D01*
X578002Y35941D01*
X577962Y35816D01*
X577902Y35706D01*
X577822Y35606D01*
X577722Y35526D01*
X577612Y35466D01*
X577487Y35426D01*
X577362Y35416D01*
G37*
G36*
G01X600984D02*
X600859Y35426D01*
X600734Y35466D01*
X600624Y35526D01*
X600524Y35606D01*
X600444Y35706D01*
X600384Y35816D01*
X600344Y35941D01*
X600334Y36066D01*
Y37196D01*
X600304Y37226D01*
X600204Y37366D01*
X600184Y37406D01*
X600169Y37441D01*
X600149Y37481D01*
X600134Y37521D01*
X600124Y37561D01*
X600109Y37606D01*
X600104Y37646D01*
X600094Y37686D01*
X600089Y37731D01*
Y37771D01*
X600084Y37816D01*
X600089Y37861D01*
Y37901D01*
X600094Y37946D01*
X600104Y37986D01*
X600109Y38026D01*
X600124Y38071D01*
X600134Y38111D01*
X600149Y38151D01*
X600169Y38191D01*
X600184Y38226D01*
X600204Y38266D01*
X600304Y38406D01*
X600334Y38436D01*
Y41866D01*
X600344Y41991D01*
X600384Y42116D01*
X600444Y42226D01*
X600524Y42326D01*
X600624Y42406D01*
X600734Y42466D01*
X600859Y42506D01*
X600984Y42516D01*
X601109Y42506D01*
X601234Y42466D01*
X601344Y42406D01*
X601444Y42326D01*
X601524Y42226D01*
X601584Y42116D01*
X601624Y41991D01*
X601634Y41866D01*
Y38436D01*
X601664Y38406D01*
X601764Y38266D01*
X601784Y38226D01*
X601799Y38191D01*
X601819Y38151D01*
X601834Y38111D01*
X601844Y38071D01*
X601859Y38026D01*
X601864Y37986D01*
X601874Y37946D01*
X601879Y37901D01*
Y37861D01*
X601884Y37816D01*
X601879Y37771D01*
Y37731D01*
X601874Y37686D01*
X601864Y37646D01*
X601859Y37606D01*
X601844Y37561D01*
X601834Y37521D01*
X601819Y37481D01*
X601799Y37441D01*
X601784Y37406D01*
X601764Y37366D01*
X601664Y37226D01*
X601634Y37196D01*
Y36066D01*
X601624Y35941D01*
X601584Y35816D01*
X601524Y35706D01*
X601444Y35606D01*
X601344Y35526D01*
X601234Y35466D01*
X601109Y35426D01*
X600984Y35416D01*
G37*
G36*
G01X615157D02*
X615032Y35426D01*
X614907Y35466D01*
X614797Y35526D01*
X614697Y35606D01*
X614617Y35706D01*
X614557Y35816D01*
X614517Y35941D01*
X614507Y36066D01*
Y37196D01*
X614477Y37226D01*
X614377Y37366D01*
X614357Y37406D01*
X614342Y37441D01*
X614322Y37481D01*
X614307Y37521D01*
X614297Y37561D01*
X614282Y37606D01*
X614277Y37646D01*
X614267Y37686D01*
X614262Y37731D01*
Y37771D01*
X614257Y37816D01*
X614262Y37861D01*
Y37901D01*
X614267Y37946D01*
X614277Y37986D01*
X614282Y38026D01*
X614297Y38071D01*
X614307Y38111D01*
X614322Y38151D01*
X614342Y38191D01*
X614357Y38226D01*
X614377Y38266D01*
X614477Y38406D01*
X614507Y38436D01*
Y41866D01*
X614517Y41991D01*
X614557Y42116D01*
X614617Y42226D01*
X614697Y42326D01*
X614797Y42406D01*
X614907Y42466D01*
X615032Y42506D01*
X615157Y42516D01*
X615282Y42506D01*
X615407Y42466D01*
X615517Y42406D01*
X615617Y42326D01*
X615697Y42226D01*
X615757Y42116D01*
X615797Y41991D01*
X615807Y41866D01*
Y38436D01*
X615837Y38406D01*
X615937Y38266D01*
X615957Y38226D01*
X615972Y38191D01*
X615992Y38151D01*
X616007Y38111D01*
X616017Y38071D01*
X616032Y38026D01*
X616037Y37986D01*
X616047Y37946D01*
X616052Y37901D01*
Y37861D01*
X616057Y37816D01*
X616052Y37771D01*
Y37731D01*
X616047Y37686D01*
X616037Y37646D01*
X616032Y37606D01*
X616017Y37561D01*
X616007Y37521D01*
X615992Y37481D01*
X615972Y37441D01*
X615957Y37406D01*
X615937Y37366D01*
X615837Y37226D01*
X615807Y37196D01*
Y36066D01*
X615797Y35941D01*
X615757Y35816D01*
X615697Y35706D01*
X615617Y35606D01*
X615517Y35526D01*
X615407Y35466D01*
X615282Y35426D01*
X615157Y35416D01*
G37*
G36*
G01X610433D02*
X610308Y35426D01*
X610183Y35466D01*
X610073Y35526D01*
X609973Y35606D01*
X609893Y35706D01*
X609833Y35816D01*
X609793Y35941D01*
X609783Y36066D01*
Y37196D01*
X609753Y37226D01*
X609653Y37366D01*
X609633Y37406D01*
X609618Y37441D01*
X609598Y37481D01*
X609583Y37521D01*
X609573Y37561D01*
X609558Y37606D01*
X609553Y37646D01*
X609543Y37686D01*
X609538Y37731D01*
Y37771D01*
X609533Y37816D01*
X609538Y37861D01*
Y37901D01*
X609543Y37946D01*
X609553Y37986D01*
X609558Y38026D01*
X609573Y38071D01*
X609583Y38111D01*
X609598Y38151D01*
X609618Y38191D01*
X609633Y38226D01*
X609653Y38266D01*
X609753Y38406D01*
X609783Y38436D01*
Y41866D01*
X609793Y41991D01*
X609833Y42116D01*
X609893Y42226D01*
X609973Y42326D01*
X610073Y42406D01*
X610183Y42466D01*
X610308Y42506D01*
X610433Y42516D01*
X610558Y42506D01*
X610683Y42466D01*
X610793Y42406D01*
X610893Y42326D01*
X610973Y42226D01*
X611033Y42116D01*
X611073Y41991D01*
X611083Y41866D01*
Y38436D01*
X611113Y38406D01*
X611213Y38266D01*
X611233Y38226D01*
X611248Y38191D01*
X611268Y38151D01*
X611283Y38111D01*
X611293Y38071D01*
X611308Y38026D01*
X611313Y37986D01*
X611323Y37946D01*
X611328Y37901D01*
Y37861D01*
X611333Y37816D01*
X611328Y37771D01*
Y37731D01*
X611323Y37686D01*
X611313Y37646D01*
X611308Y37606D01*
X611293Y37561D01*
X611283Y37521D01*
X611268Y37481D01*
X611248Y37441D01*
X611233Y37406D01*
X611213Y37366D01*
X611113Y37226D01*
X611083Y37196D01*
Y36066D01*
X611073Y35941D01*
X611033Y35816D01*
X610973Y35706D01*
X610893Y35606D01*
X610793Y35526D01*
X610683Y35466D01*
X610558Y35426D01*
X610433Y35416D01*
G37*
G36*
G01X605708D02*
X605583Y35426D01*
X605458Y35466D01*
X605348Y35526D01*
X605248Y35606D01*
X605168Y35706D01*
X605108Y35816D01*
X605068Y35941D01*
X605058Y36066D01*
Y37196D01*
X605028Y37226D01*
X604928Y37366D01*
X604908Y37406D01*
X604893Y37441D01*
X604873Y37481D01*
X604858Y37521D01*
X604848Y37561D01*
X604833Y37606D01*
X604828Y37646D01*
X604818Y37686D01*
X604813Y37731D01*
Y37771D01*
X604808Y37816D01*
X604813Y37861D01*
Y37901D01*
X604818Y37946D01*
X604828Y37986D01*
X604833Y38026D01*
X604848Y38071D01*
X604858Y38111D01*
X604873Y38151D01*
X604893Y38191D01*
X604908Y38226D01*
X604928Y38266D01*
X605028Y38406D01*
X605058Y38436D01*
Y41866D01*
X605068Y41991D01*
X605108Y42116D01*
X605168Y42226D01*
X605248Y42326D01*
X605348Y42406D01*
X605458Y42466D01*
X605583Y42506D01*
X605708Y42516D01*
X605833Y42506D01*
X605958Y42466D01*
X606068Y42406D01*
X606168Y42326D01*
X606248Y42226D01*
X606308Y42116D01*
X606348Y41991D01*
X606358Y41866D01*
Y38436D01*
X606388Y38406D01*
X606488Y38266D01*
X606508Y38226D01*
X606523Y38191D01*
X606543Y38151D01*
X606558Y38111D01*
X606568Y38071D01*
X606583Y38026D01*
X606588Y37986D01*
X606598Y37946D01*
X606603Y37901D01*
Y37861D01*
X606608Y37816D01*
X606603Y37771D01*
Y37731D01*
X606598Y37686D01*
X606588Y37646D01*
X606583Y37606D01*
X606568Y37561D01*
X606558Y37521D01*
X606543Y37481D01*
X606523Y37441D01*
X606508Y37406D01*
X606488Y37366D01*
X606388Y37226D01*
X606358Y37196D01*
Y36066D01*
X606348Y35941D01*
X606308Y35816D01*
X606248Y35706D01*
X606168Y35606D01*
X606068Y35526D01*
X605958Y35466D01*
X605833Y35426D01*
X605708Y35416D01*
G37*
G36*
G01X634055D02*
X633930Y35426D01*
X633805Y35466D01*
X633695Y35526D01*
X633595Y35606D01*
X633515Y35706D01*
X633455Y35816D01*
X633415Y35941D01*
X633405Y36066D01*
Y37196D01*
X633375Y37226D01*
X633275Y37366D01*
X633255Y37406D01*
X633240Y37441D01*
X633220Y37481D01*
X633205Y37521D01*
X633195Y37561D01*
X633180Y37606D01*
X633175Y37646D01*
X633165Y37686D01*
X633160Y37731D01*
Y37771D01*
X633155Y37816D01*
X633160Y37861D01*
Y37901D01*
X633165Y37946D01*
X633175Y37986D01*
X633180Y38026D01*
X633195Y38071D01*
X633205Y38111D01*
X633220Y38151D01*
X633240Y38191D01*
X633255Y38226D01*
X633275Y38266D01*
X633375Y38406D01*
X633405Y38436D01*
Y41866D01*
X633415Y41991D01*
X633455Y42116D01*
X633515Y42226D01*
X633595Y42326D01*
X633695Y42406D01*
X633805Y42466D01*
X633930Y42506D01*
X634055Y42516D01*
X634180Y42506D01*
X634305Y42466D01*
X634415Y42406D01*
X634515Y42326D01*
X634595Y42226D01*
X634655Y42116D01*
X634695Y41991D01*
X634705Y41866D01*
Y38436D01*
X634735Y38406D01*
X634835Y38266D01*
X634855Y38226D01*
X634870Y38191D01*
X634890Y38151D01*
X634905Y38111D01*
X634915Y38071D01*
X634930Y38026D01*
X634935Y37986D01*
X634945Y37946D01*
X634950Y37901D01*
Y37861D01*
X634955Y37816D01*
X634950Y37771D01*
Y37731D01*
X634945Y37686D01*
X634935Y37646D01*
X634930Y37606D01*
X634915Y37561D01*
X634905Y37521D01*
X634890Y37481D01*
X634870Y37441D01*
X634855Y37406D01*
X634835Y37366D01*
X634735Y37226D01*
X634705Y37196D01*
Y36066D01*
X634695Y35941D01*
X634655Y35816D01*
X634595Y35706D01*
X634515Y35606D01*
X634415Y35526D01*
X634305Y35466D01*
X634180Y35426D01*
X634055Y35416D01*
G37*
G36*
G01X629330D02*
X629205Y35426D01*
X629080Y35466D01*
X628970Y35526D01*
X628870Y35606D01*
X628790Y35706D01*
X628730Y35816D01*
X628690Y35941D01*
X628680Y36066D01*
Y37196D01*
X628650Y37226D01*
X628550Y37366D01*
X628530Y37406D01*
X628515Y37441D01*
X628495Y37481D01*
X628480Y37521D01*
X628470Y37561D01*
X628455Y37606D01*
X628450Y37646D01*
X628440Y37686D01*
X628435Y37731D01*
Y37771D01*
X628430Y37816D01*
X628435Y37861D01*
Y37901D01*
X628440Y37946D01*
X628450Y37986D01*
X628455Y38026D01*
X628470Y38071D01*
X628480Y38111D01*
X628495Y38151D01*
X628515Y38191D01*
X628530Y38226D01*
X628550Y38266D01*
X628650Y38406D01*
X628680Y38436D01*
Y41866D01*
X628690Y41991D01*
X628730Y42116D01*
X628790Y42226D01*
X628870Y42326D01*
X628970Y42406D01*
X629080Y42466D01*
X629205Y42506D01*
X629330Y42516D01*
X629455Y42506D01*
X629580Y42466D01*
X629690Y42406D01*
X629790Y42326D01*
X629870Y42226D01*
X629930Y42116D01*
X629970Y41991D01*
X629980Y41866D01*
Y38436D01*
X630010Y38406D01*
X630110Y38266D01*
X630130Y38226D01*
X630145Y38191D01*
X630165Y38151D01*
X630180Y38111D01*
X630190Y38071D01*
X630205Y38026D01*
X630210Y37986D01*
X630220Y37946D01*
X630225Y37901D01*
Y37861D01*
X630230Y37816D01*
X630225Y37771D01*
Y37731D01*
X630220Y37686D01*
X630210Y37646D01*
X630205Y37606D01*
X630190Y37561D01*
X630180Y37521D01*
X630165Y37481D01*
X630145Y37441D01*
X630130Y37406D01*
X630110Y37366D01*
X630010Y37226D01*
X629980Y37196D01*
Y36066D01*
X629970Y35941D01*
X629930Y35816D01*
X629870Y35706D01*
X629790Y35606D01*
X629690Y35526D01*
X629580Y35466D01*
X629455Y35426D01*
X629330Y35416D01*
G37*
G36*
G01X624606D02*
X624481Y35426D01*
X624356Y35466D01*
X624246Y35526D01*
X624146Y35606D01*
X624066Y35706D01*
X624006Y35816D01*
X623966Y35941D01*
X623956Y36066D01*
Y37196D01*
X623926Y37226D01*
X623826Y37366D01*
X623806Y37406D01*
X623791Y37441D01*
X623771Y37481D01*
X623756Y37521D01*
X623746Y37561D01*
X623731Y37606D01*
X623726Y37646D01*
X623716Y37686D01*
X623711Y37731D01*
Y37771D01*
X623706Y37816D01*
X623711Y37861D01*
Y37901D01*
X623716Y37946D01*
X623726Y37986D01*
X623731Y38026D01*
X623746Y38071D01*
X623756Y38111D01*
X623771Y38151D01*
X623791Y38191D01*
X623806Y38226D01*
X623826Y38266D01*
X623926Y38406D01*
X623956Y38436D01*
Y41866D01*
X623966Y41991D01*
X624006Y42116D01*
X624066Y42226D01*
X624146Y42326D01*
X624246Y42406D01*
X624356Y42466D01*
X624481Y42506D01*
X624606Y42516D01*
X624731Y42506D01*
X624856Y42466D01*
X624966Y42406D01*
X625066Y42326D01*
X625146Y42226D01*
X625206Y42116D01*
X625246Y41991D01*
X625256Y41866D01*
Y38436D01*
X625286Y38406D01*
X625386Y38266D01*
X625406Y38226D01*
X625421Y38191D01*
X625441Y38151D01*
X625456Y38111D01*
X625466Y38071D01*
X625481Y38026D01*
X625486Y37986D01*
X625496Y37946D01*
X625501Y37901D01*
Y37861D01*
X625506Y37816D01*
X625501Y37771D01*
Y37731D01*
X625496Y37686D01*
X625486Y37646D01*
X625481Y37606D01*
X625466Y37561D01*
X625456Y37521D01*
X625441Y37481D01*
X625421Y37441D01*
X625406Y37406D01*
X625386Y37366D01*
X625286Y37226D01*
X625256Y37196D01*
Y36066D01*
X625246Y35941D01*
X625206Y35816D01*
X625146Y35706D01*
X625066Y35606D01*
X624966Y35526D01*
X624856Y35466D01*
X624731Y35426D01*
X624606Y35416D01*
G37*
G36*
G01X619882D02*
X619757Y35426D01*
X619632Y35466D01*
X619522Y35526D01*
X619422Y35606D01*
X619342Y35706D01*
X619282Y35816D01*
X619242Y35941D01*
X619232Y36066D01*
Y37196D01*
X619202Y37226D01*
X619102Y37366D01*
X619082Y37406D01*
X619067Y37441D01*
X619047Y37481D01*
X619032Y37521D01*
X619022Y37561D01*
X619007Y37606D01*
X619002Y37646D01*
X618992Y37686D01*
X618987Y37731D01*
Y37771D01*
X618982Y37816D01*
X618987Y37861D01*
Y37901D01*
X618992Y37946D01*
X619002Y37986D01*
X619007Y38026D01*
X619022Y38071D01*
X619032Y38111D01*
X619047Y38151D01*
X619067Y38191D01*
X619082Y38226D01*
X619102Y38266D01*
X619202Y38406D01*
X619232Y38436D01*
Y41866D01*
X619242Y41991D01*
X619282Y42116D01*
X619342Y42226D01*
X619422Y42326D01*
X619522Y42406D01*
X619632Y42466D01*
X619757Y42506D01*
X619882Y42516D01*
X620007Y42506D01*
X620132Y42466D01*
X620242Y42406D01*
X620342Y42326D01*
X620422Y42226D01*
X620482Y42116D01*
X620522Y41991D01*
X620532Y41866D01*
Y38436D01*
X620562Y38406D01*
X620662Y38266D01*
X620682Y38226D01*
X620697Y38191D01*
X620717Y38151D01*
X620732Y38111D01*
X620742Y38071D01*
X620757Y38026D01*
X620762Y37986D01*
X620772Y37946D01*
X620777Y37901D01*
Y37861D01*
X620782Y37816D01*
X620777Y37771D01*
Y37731D01*
X620772Y37686D01*
X620762Y37646D01*
X620757Y37606D01*
X620742Y37561D01*
X620732Y37521D01*
X620717Y37481D01*
X620697Y37441D01*
X620682Y37406D01*
X620662Y37366D01*
X620562Y37226D01*
X620532Y37196D01*
Y36066D01*
X620522Y35941D01*
X620482Y35816D01*
X620422Y35706D01*
X620342Y35606D01*
X620242Y35526D01*
X620132Y35466D01*
X620007Y35426D01*
X619882Y35416D01*
G37*
G36*
G01X648228D02*
X648103Y35426D01*
X647978Y35466D01*
X647868Y35526D01*
X647768Y35606D01*
X647688Y35706D01*
X647628Y35816D01*
X647588Y35941D01*
X647578Y36066D01*
Y37196D01*
X647548Y37226D01*
X647448Y37366D01*
X647428Y37406D01*
X647413Y37441D01*
X647393Y37481D01*
X647378Y37521D01*
X647368Y37561D01*
X647353Y37606D01*
X647348Y37646D01*
X647338Y37686D01*
X647333Y37731D01*
Y37771D01*
X647328Y37816D01*
X647333Y37861D01*
Y37901D01*
X647338Y37946D01*
X647348Y37986D01*
X647353Y38026D01*
X647368Y38071D01*
X647378Y38111D01*
X647393Y38151D01*
X647413Y38191D01*
X647428Y38226D01*
X647448Y38266D01*
X647548Y38406D01*
X647578Y38436D01*
Y41866D01*
X647588Y41991D01*
X647628Y42116D01*
X647688Y42226D01*
X647768Y42326D01*
X647868Y42406D01*
X647978Y42466D01*
X648103Y42506D01*
X648228Y42516D01*
X648353Y42506D01*
X648478Y42466D01*
X648588Y42406D01*
X648688Y42326D01*
X648768Y42226D01*
X648828Y42116D01*
X648868Y41991D01*
X648878Y41866D01*
Y38436D01*
X648908Y38406D01*
X649008Y38266D01*
X649028Y38226D01*
X649043Y38191D01*
X649063Y38151D01*
X649078Y38111D01*
X649088Y38071D01*
X649103Y38026D01*
X649108Y37986D01*
X649118Y37946D01*
X649123Y37901D01*
Y37861D01*
X649128Y37816D01*
X649123Y37771D01*
Y37731D01*
X649118Y37686D01*
X649108Y37646D01*
X649103Y37606D01*
X649088Y37561D01*
X649078Y37521D01*
X649063Y37481D01*
X649043Y37441D01*
X649028Y37406D01*
X649008Y37366D01*
X648908Y37226D01*
X648878Y37196D01*
Y36066D01*
X648868Y35941D01*
X648828Y35816D01*
X648768Y35706D01*
X648688Y35606D01*
X648588Y35526D01*
X648478Y35466D01*
X648353Y35426D01*
X648228Y35416D01*
G37*
G36*
G01X643504D02*
X643379Y35426D01*
X643254Y35466D01*
X643144Y35526D01*
X643044Y35606D01*
X642964Y35706D01*
X642904Y35816D01*
X642864Y35941D01*
X642854Y36066D01*
Y37196D01*
X642824Y37226D01*
X642724Y37366D01*
X642704Y37406D01*
X642689Y37441D01*
X642669Y37481D01*
X642654Y37521D01*
X642644Y37561D01*
X642629Y37606D01*
X642624Y37646D01*
X642614Y37686D01*
X642609Y37731D01*
Y37771D01*
X642604Y37816D01*
X642609Y37861D01*
Y37901D01*
X642614Y37946D01*
X642624Y37986D01*
X642629Y38026D01*
X642644Y38071D01*
X642654Y38111D01*
X642669Y38151D01*
X642689Y38191D01*
X642704Y38226D01*
X642724Y38266D01*
X642824Y38406D01*
X642854Y38436D01*
Y41866D01*
X642864Y41991D01*
X642904Y42116D01*
X642964Y42226D01*
X643044Y42326D01*
X643144Y42406D01*
X643254Y42466D01*
X643379Y42506D01*
X643504Y42516D01*
X643629Y42506D01*
X643754Y42466D01*
X643864Y42406D01*
X643964Y42326D01*
X644044Y42226D01*
X644104Y42116D01*
X644144Y41991D01*
X644154Y41866D01*
Y38436D01*
X644184Y38406D01*
X644284Y38266D01*
X644304Y38226D01*
X644319Y38191D01*
X644339Y38151D01*
X644354Y38111D01*
X644364Y38071D01*
X644379Y38026D01*
X644384Y37986D01*
X644394Y37946D01*
X644399Y37901D01*
Y37861D01*
X644404Y37816D01*
X644399Y37771D01*
Y37731D01*
X644394Y37686D01*
X644384Y37646D01*
X644379Y37606D01*
X644364Y37561D01*
X644354Y37521D01*
X644339Y37481D01*
X644319Y37441D01*
X644304Y37406D01*
X644284Y37366D01*
X644184Y37226D01*
X644154Y37196D01*
Y36066D01*
X644144Y35941D01*
X644104Y35816D01*
X644044Y35706D01*
X643964Y35606D01*
X643864Y35526D01*
X643754Y35466D01*
X643629Y35426D01*
X643504Y35416D01*
G37*
G36*
G01X638779D02*
X638654Y35426D01*
X638529Y35466D01*
X638419Y35526D01*
X638319Y35606D01*
X638239Y35706D01*
X638179Y35816D01*
X638139Y35941D01*
X638129Y36066D01*
Y37196D01*
X638099Y37226D01*
X637999Y37366D01*
X637979Y37406D01*
X637964Y37441D01*
X637944Y37481D01*
X637929Y37521D01*
X637919Y37561D01*
X637904Y37606D01*
X637899Y37646D01*
X637889Y37686D01*
X637884Y37731D01*
Y37771D01*
X637879Y37816D01*
X637884Y37861D01*
Y37901D01*
X637889Y37946D01*
X637899Y37986D01*
X637904Y38026D01*
X637919Y38071D01*
X637929Y38111D01*
X637944Y38151D01*
X637964Y38191D01*
X637979Y38226D01*
X637999Y38266D01*
X638099Y38406D01*
X638129Y38436D01*
Y41866D01*
X638139Y41991D01*
X638179Y42116D01*
X638239Y42226D01*
X638319Y42326D01*
X638419Y42406D01*
X638529Y42466D01*
X638654Y42506D01*
X638779Y42516D01*
X638904Y42506D01*
X639029Y42466D01*
X639139Y42406D01*
X639239Y42326D01*
X639319Y42226D01*
X639379Y42116D01*
X639419Y41991D01*
X639429Y41866D01*
Y38436D01*
X639459Y38406D01*
X639559Y38266D01*
X639579Y38226D01*
X639594Y38191D01*
X639614Y38151D01*
X639629Y38111D01*
X639639Y38071D01*
X639654Y38026D01*
X639659Y37986D01*
X639669Y37946D01*
X639674Y37901D01*
Y37861D01*
X639679Y37816D01*
X639674Y37771D01*
Y37731D01*
X639669Y37686D01*
X639659Y37646D01*
X639654Y37606D01*
X639639Y37561D01*
X639629Y37521D01*
X639614Y37481D01*
X639594Y37441D01*
X639579Y37406D01*
X639559Y37366D01*
X639459Y37226D01*
X639429Y37196D01*
Y36066D01*
X639419Y35941D01*
X639379Y35816D01*
X639319Y35706D01*
X639239Y35606D01*
X639139Y35526D01*
X639029Y35466D01*
X638904Y35426D01*
X638779Y35416D01*
G37*
G36*
G01X662401D02*
X662276Y35426D01*
X662151Y35466D01*
X662041Y35526D01*
X661941Y35606D01*
X661861Y35706D01*
X661801Y35816D01*
X661761Y35941D01*
X661751Y36066D01*
Y37196D01*
X661721Y37226D01*
X661621Y37366D01*
X661601Y37406D01*
X661586Y37441D01*
X661566Y37481D01*
X661551Y37521D01*
X661541Y37561D01*
X661526Y37606D01*
X661521Y37646D01*
X661511Y37686D01*
X661506Y37731D01*
Y37771D01*
X661501Y37816D01*
X661506Y37861D01*
Y37901D01*
X661511Y37946D01*
X661521Y37986D01*
X661526Y38026D01*
X661541Y38071D01*
X661551Y38111D01*
X661566Y38151D01*
X661586Y38191D01*
X661601Y38226D01*
X661621Y38266D01*
X661721Y38406D01*
X661751Y38436D01*
Y41866D01*
X661761Y41991D01*
X661801Y42116D01*
X661861Y42226D01*
X661941Y42326D01*
X662041Y42406D01*
X662151Y42466D01*
X662276Y42506D01*
X662401Y42516D01*
X662526Y42506D01*
X662651Y42466D01*
X662761Y42406D01*
X662861Y42326D01*
X662941Y42226D01*
X663001Y42116D01*
X663041Y41991D01*
X663051Y41866D01*
Y38436D01*
X663081Y38406D01*
X663181Y38266D01*
X663201Y38226D01*
X663216Y38191D01*
X663236Y38151D01*
X663251Y38111D01*
X663261Y38071D01*
X663276Y38026D01*
X663281Y37986D01*
X663291Y37946D01*
X663296Y37901D01*
Y37861D01*
X663301Y37816D01*
X663296Y37771D01*
Y37731D01*
X663291Y37686D01*
X663281Y37646D01*
X663276Y37606D01*
X663261Y37561D01*
X663251Y37521D01*
X663236Y37481D01*
X663216Y37441D01*
X663201Y37406D01*
X663181Y37366D01*
X663081Y37226D01*
X663051Y37196D01*
Y36066D01*
X663041Y35941D01*
X663001Y35816D01*
X662941Y35706D01*
X662861Y35606D01*
X662761Y35526D01*
X662651Y35466D01*
X662526Y35426D01*
X662401Y35416D01*
G37*
G36*
G01X657677D02*
X657552Y35426D01*
X657427Y35466D01*
X657317Y35526D01*
X657217Y35606D01*
X657137Y35706D01*
X657077Y35816D01*
X657037Y35941D01*
X657027Y36066D01*
Y37196D01*
X656997Y37226D01*
X656897Y37366D01*
X656877Y37406D01*
X656862Y37441D01*
X656842Y37481D01*
X656827Y37521D01*
X656817Y37561D01*
X656802Y37606D01*
X656797Y37646D01*
X656787Y37686D01*
X656782Y37731D01*
Y37771D01*
X656777Y37816D01*
X656782Y37861D01*
Y37901D01*
X656787Y37946D01*
X656797Y37986D01*
X656802Y38026D01*
X656817Y38071D01*
X656827Y38111D01*
X656842Y38151D01*
X656862Y38191D01*
X656877Y38226D01*
X656897Y38266D01*
X656997Y38406D01*
X657027Y38436D01*
Y41866D01*
X657037Y41991D01*
X657077Y42116D01*
X657137Y42226D01*
X657217Y42326D01*
X657317Y42406D01*
X657427Y42466D01*
X657552Y42506D01*
X657677Y42516D01*
X657802Y42506D01*
X657927Y42466D01*
X658037Y42406D01*
X658137Y42326D01*
X658217Y42226D01*
X658277Y42116D01*
X658317Y41991D01*
X658327Y41866D01*
Y38436D01*
X658357Y38406D01*
X658457Y38266D01*
X658477Y38226D01*
X658492Y38191D01*
X658512Y38151D01*
X658527Y38111D01*
X658537Y38071D01*
X658552Y38026D01*
X658557Y37986D01*
X658567Y37946D01*
X658572Y37901D01*
Y37861D01*
X658577Y37816D01*
X658572Y37771D01*
Y37731D01*
X658567Y37686D01*
X658557Y37646D01*
X658552Y37606D01*
X658537Y37561D01*
X658527Y37521D01*
X658512Y37481D01*
X658492Y37441D01*
X658477Y37406D01*
X658457Y37366D01*
X658357Y37226D01*
X658327Y37196D01*
Y36066D01*
X658317Y35941D01*
X658277Y35816D01*
X658217Y35706D01*
X658137Y35606D01*
X658037Y35526D01*
X657927Y35466D01*
X657802Y35426D01*
X657677Y35416D01*
G37*
G36*
G01X652952D02*
X652827Y35426D01*
X652702Y35466D01*
X652592Y35526D01*
X652492Y35606D01*
X652412Y35706D01*
X652352Y35816D01*
X652312Y35941D01*
X652302Y36066D01*
Y37196D01*
X652272Y37226D01*
X652172Y37366D01*
X652152Y37406D01*
X652137Y37441D01*
X652117Y37481D01*
X652102Y37521D01*
X652092Y37561D01*
X652077Y37606D01*
X652072Y37646D01*
X652062Y37686D01*
X652057Y37731D01*
Y37771D01*
X652052Y37816D01*
X652057Y37861D01*
Y37901D01*
X652062Y37946D01*
X652072Y37986D01*
X652077Y38026D01*
X652092Y38071D01*
X652102Y38111D01*
X652117Y38151D01*
X652137Y38191D01*
X652152Y38226D01*
X652172Y38266D01*
X652272Y38406D01*
X652302Y38436D01*
Y41866D01*
X652312Y41991D01*
X652352Y42116D01*
X652412Y42226D01*
X652492Y42326D01*
X652592Y42406D01*
X652702Y42466D01*
X652827Y42506D01*
X652952Y42516D01*
X653077Y42506D01*
X653202Y42466D01*
X653312Y42406D01*
X653412Y42326D01*
X653492Y42226D01*
X653552Y42116D01*
X653592Y41991D01*
X653602Y41866D01*
Y38436D01*
X653632Y38406D01*
X653732Y38266D01*
X653752Y38226D01*
X653767Y38191D01*
X653787Y38151D01*
X653802Y38111D01*
X653812Y38071D01*
X653827Y38026D01*
X653832Y37986D01*
X653842Y37946D01*
X653847Y37901D01*
Y37861D01*
X653852Y37816D01*
X653847Y37771D01*
Y37731D01*
X653842Y37686D01*
X653832Y37646D01*
X653827Y37606D01*
X653812Y37561D01*
X653802Y37521D01*
X653787Y37481D01*
X653767Y37441D01*
X653752Y37406D01*
X653732Y37366D01*
X653632Y37226D01*
X653602Y37196D01*
Y36066D01*
X653592Y35941D01*
X653552Y35816D01*
X653492Y35706D01*
X653412Y35606D01*
X653312Y35526D01*
X653202Y35466D01*
X653077Y35426D01*
X652952Y35416D01*
G37*
G36*
G01X676575D02*
X676450Y35426D01*
X676325Y35466D01*
X676215Y35526D01*
X676115Y35606D01*
X676035Y35706D01*
X675975Y35816D01*
X675935Y35941D01*
X675925Y36066D01*
Y37196D01*
X675895Y37226D01*
X675795Y37366D01*
X675775Y37406D01*
X675760Y37441D01*
X675740Y37481D01*
X675725Y37521D01*
X675715Y37561D01*
X675700Y37606D01*
X675695Y37646D01*
X675685Y37686D01*
X675680Y37731D01*
Y37771D01*
X675675Y37816D01*
X675680Y37861D01*
Y37901D01*
X675685Y37946D01*
X675695Y37986D01*
X675700Y38026D01*
X675715Y38071D01*
X675725Y38111D01*
X675740Y38151D01*
X675760Y38191D01*
X675775Y38226D01*
X675795Y38266D01*
X675895Y38406D01*
X675925Y38436D01*
Y41866D01*
X675935Y41991D01*
X675975Y42116D01*
X676035Y42226D01*
X676115Y42326D01*
X676215Y42406D01*
X676325Y42466D01*
X676450Y42506D01*
X676575Y42516D01*
X676700Y42506D01*
X676825Y42466D01*
X676935Y42406D01*
X677035Y42326D01*
X677115Y42226D01*
X677175Y42116D01*
X677215Y41991D01*
X677225Y41866D01*
Y38436D01*
X677255Y38406D01*
X677355Y38266D01*
X677375Y38226D01*
X677390Y38191D01*
X677410Y38151D01*
X677425Y38111D01*
X677435Y38071D01*
X677450Y38026D01*
X677455Y37986D01*
X677465Y37946D01*
X677470Y37901D01*
Y37861D01*
X677475Y37816D01*
X677470Y37771D01*
Y37731D01*
X677465Y37686D01*
X677455Y37646D01*
X677450Y37606D01*
X677435Y37561D01*
X677425Y37521D01*
X677410Y37481D01*
X677390Y37441D01*
X677375Y37406D01*
X677355Y37366D01*
X677255Y37226D01*
X677225Y37196D01*
Y36066D01*
X677215Y35941D01*
X677175Y35816D01*
X677115Y35706D01*
X677035Y35606D01*
X676935Y35526D01*
X676825Y35466D01*
X676700Y35426D01*
X676575Y35416D01*
G37*
G36*
G01X671850D02*
X671725Y35426D01*
X671600Y35466D01*
X671490Y35526D01*
X671390Y35606D01*
X671310Y35706D01*
X671250Y35816D01*
X671210Y35941D01*
X671200Y36066D01*
Y37196D01*
X671170Y37226D01*
X671070Y37366D01*
X671050Y37406D01*
X671035Y37441D01*
X671015Y37481D01*
X671000Y37521D01*
X670990Y37561D01*
X670975Y37606D01*
X670970Y37646D01*
X670960Y37686D01*
X670955Y37731D01*
Y37771D01*
X670950Y37816D01*
X670955Y37861D01*
Y37901D01*
X670960Y37946D01*
X670970Y37986D01*
X670975Y38026D01*
X670990Y38071D01*
X671000Y38111D01*
X671015Y38151D01*
X671035Y38191D01*
X671050Y38226D01*
X671070Y38266D01*
X671170Y38406D01*
X671200Y38436D01*
Y41866D01*
X671210Y41991D01*
X671250Y42116D01*
X671310Y42226D01*
X671390Y42326D01*
X671490Y42406D01*
X671600Y42466D01*
X671725Y42506D01*
X671850Y42516D01*
X671975Y42506D01*
X672100Y42466D01*
X672210Y42406D01*
X672310Y42326D01*
X672390Y42226D01*
X672450Y42116D01*
X672490Y41991D01*
X672500Y41866D01*
Y38436D01*
X672530Y38406D01*
X672630Y38266D01*
X672650Y38226D01*
X672665Y38191D01*
X672685Y38151D01*
X672700Y38111D01*
X672710Y38071D01*
X672725Y38026D01*
X672730Y37986D01*
X672740Y37946D01*
X672745Y37901D01*
Y37861D01*
X672750Y37816D01*
X672745Y37771D01*
Y37731D01*
X672740Y37686D01*
X672730Y37646D01*
X672725Y37606D01*
X672710Y37561D01*
X672700Y37521D01*
X672685Y37481D01*
X672665Y37441D01*
X672650Y37406D01*
X672630Y37366D01*
X672530Y37226D01*
X672500Y37196D01*
Y36066D01*
X672490Y35941D01*
X672450Y35816D01*
X672390Y35706D01*
X672310Y35606D01*
X672210Y35526D01*
X672100Y35466D01*
X671975Y35426D01*
X671850Y35416D01*
G37*
G36*
G01X667126D02*
X667001Y35426D01*
X666876Y35466D01*
X666766Y35526D01*
X666666Y35606D01*
X666586Y35706D01*
X666526Y35816D01*
X666486Y35941D01*
X666476Y36066D01*
Y37196D01*
X666446Y37226D01*
X666346Y37366D01*
X666326Y37406D01*
X666311Y37441D01*
X666291Y37481D01*
X666276Y37521D01*
X666266Y37561D01*
X666251Y37606D01*
X666246Y37646D01*
X666236Y37686D01*
X666231Y37731D01*
Y37771D01*
X666226Y37816D01*
X666231Y37861D01*
Y37901D01*
X666236Y37946D01*
X666246Y37986D01*
X666251Y38026D01*
X666266Y38071D01*
X666276Y38111D01*
X666291Y38151D01*
X666311Y38191D01*
X666326Y38226D01*
X666346Y38266D01*
X666446Y38406D01*
X666476Y38436D01*
Y41866D01*
X666486Y41991D01*
X666526Y42116D01*
X666586Y42226D01*
X666666Y42326D01*
X666766Y42406D01*
X666876Y42466D01*
X667001Y42506D01*
X667126Y42516D01*
X667251Y42506D01*
X667376Y42466D01*
X667486Y42406D01*
X667586Y42326D01*
X667666Y42226D01*
X667726Y42116D01*
X667766Y41991D01*
X667776Y41866D01*
Y38436D01*
X667806Y38406D01*
X667906Y38266D01*
X667926Y38226D01*
X667941Y38191D01*
X667961Y38151D01*
X667976Y38111D01*
X667986Y38071D01*
X668001Y38026D01*
X668006Y37986D01*
X668016Y37946D01*
X668021Y37901D01*
Y37861D01*
X668026Y37816D01*
X668021Y37771D01*
Y37731D01*
X668016Y37686D01*
X668006Y37646D01*
X668001Y37606D01*
X667986Y37561D01*
X667976Y37521D01*
X667961Y37481D01*
X667941Y37441D01*
X667926Y37406D01*
X667906Y37366D01*
X667806Y37226D01*
X667776Y37196D01*
Y36066D01*
X667766Y35941D01*
X667726Y35816D01*
X667666Y35706D01*
X667586Y35606D01*
X667486Y35526D01*
X667376Y35466D01*
X667251Y35426D01*
X667126Y35416D01*
G37*
G36*
G01X695472D02*
X695347Y35426D01*
X695222Y35466D01*
X695112Y35526D01*
X695012Y35606D01*
X694932Y35706D01*
X694872Y35816D01*
X694832Y35941D01*
X694822Y36066D01*
Y37196D01*
X694792Y37226D01*
X694692Y37366D01*
X694672Y37406D01*
X694657Y37441D01*
X694637Y37481D01*
X694622Y37521D01*
X694612Y37561D01*
X694597Y37606D01*
X694592Y37646D01*
X694582Y37686D01*
X694577Y37731D01*
Y37771D01*
X694572Y37816D01*
X694577Y37861D01*
Y37901D01*
X694582Y37946D01*
X694592Y37986D01*
X694597Y38026D01*
X694612Y38071D01*
X694622Y38111D01*
X694637Y38151D01*
X694657Y38191D01*
X694672Y38226D01*
X694692Y38266D01*
X694792Y38406D01*
X694822Y38436D01*
Y41866D01*
X694832Y41991D01*
X694872Y42116D01*
X694932Y42226D01*
X695012Y42326D01*
X695112Y42406D01*
X695222Y42466D01*
X695347Y42506D01*
X695472Y42516D01*
X695597Y42506D01*
X695722Y42466D01*
X695832Y42406D01*
X695932Y42326D01*
X696012Y42226D01*
X696072Y42116D01*
X696112Y41991D01*
X696122Y41866D01*
Y38436D01*
X696152Y38406D01*
X696252Y38266D01*
X696272Y38226D01*
X696287Y38191D01*
X696307Y38151D01*
X696322Y38111D01*
X696332Y38071D01*
X696347Y38026D01*
X696352Y37986D01*
X696362Y37946D01*
X696367Y37901D01*
Y37861D01*
X696372Y37816D01*
X696367Y37771D01*
Y37731D01*
X696362Y37686D01*
X696352Y37646D01*
X696347Y37606D01*
X696332Y37561D01*
X696322Y37521D01*
X696307Y37481D01*
X696287Y37441D01*
X696272Y37406D01*
X696252Y37366D01*
X696152Y37226D01*
X696122Y37196D01*
Y36066D01*
X696112Y35941D01*
X696072Y35816D01*
X696012Y35706D01*
X695932Y35606D01*
X695832Y35526D01*
X695722Y35466D01*
X695597Y35426D01*
X695472Y35416D01*
G37*
G36*
G01X690748D02*
X690623Y35426D01*
X690498Y35466D01*
X690388Y35526D01*
X690288Y35606D01*
X690208Y35706D01*
X690148Y35816D01*
X690108Y35941D01*
X690098Y36066D01*
Y37196D01*
X690068Y37226D01*
X689968Y37366D01*
X689948Y37406D01*
X689933Y37441D01*
X689913Y37481D01*
X689898Y37521D01*
X689888Y37561D01*
X689873Y37606D01*
X689868Y37646D01*
X689858Y37686D01*
X689853Y37731D01*
Y37771D01*
X689848Y37816D01*
X689853Y37861D01*
Y37901D01*
X689858Y37946D01*
X689868Y37986D01*
X689873Y38026D01*
X689888Y38071D01*
X689898Y38111D01*
X689913Y38151D01*
X689933Y38191D01*
X689948Y38226D01*
X689968Y38266D01*
X690068Y38406D01*
X690098Y38436D01*
Y41866D01*
X690108Y41991D01*
X690148Y42116D01*
X690208Y42226D01*
X690288Y42326D01*
X690388Y42406D01*
X690498Y42466D01*
X690623Y42506D01*
X690748Y42516D01*
X690873Y42506D01*
X690998Y42466D01*
X691108Y42406D01*
X691208Y42326D01*
X691288Y42226D01*
X691348Y42116D01*
X691388Y41991D01*
X691398Y41866D01*
Y38436D01*
X691428Y38406D01*
X691528Y38266D01*
X691548Y38226D01*
X691563Y38191D01*
X691583Y38151D01*
X691598Y38111D01*
X691608Y38071D01*
X691623Y38026D01*
X691628Y37986D01*
X691638Y37946D01*
X691643Y37901D01*
Y37861D01*
X691648Y37816D01*
X691643Y37771D01*
Y37731D01*
X691638Y37686D01*
X691628Y37646D01*
X691623Y37606D01*
X691608Y37561D01*
X691598Y37521D01*
X691583Y37481D01*
X691563Y37441D01*
X691548Y37406D01*
X691528Y37366D01*
X691428Y37226D01*
X691398Y37196D01*
Y36066D01*
X691388Y35941D01*
X691348Y35816D01*
X691288Y35706D01*
X691208Y35606D01*
X691108Y35526D01*
X690998Y35466D01*
X690873Y35426D01*
X690748Y35416D01*
G37*
G36*
G01X686023D02*
X685898Y35426D01*
X685773Y35466D01*
X685663Y35526D01*
X685563Y35606D01*
X685483Y35706D01*
X685423Y35816D01*
X685383Y35941D01*
X685373Y36066D01*
Y37196D01*
X685343Y37226D01*
X685243Y37366D01*
X685223Y37406D01*
X685208Y37441D01*
X685188Y37481D01*
X685173Y37521D01*
X685163Y37561D01*
X685148Y37606D01*
X685143Y37646D01*
X685133Y37686D01*
X685128Y37731D01*
Y37771D01*
X685123Y37816D01*
X685128Y37861D01*
Y37901D01*
X685133Y37946D01*
X685143Y37986D01*
X685148Y38026D01*
X685163Y38071D01*
X685173Y38111D01*
X685188Y38151D01*
X685208Y38191D01*
X685223Y38226D01*
X685243Y38266D01*
X685343Y38406D01*
X685373Y38436D01*
Y41866D01*
X685383Y41991D01*
X685423Y42116D01*
X685483Y42226D01*
X685563Y42326D01*
X685663Y42406D01*
X685773Y42466D01*
X685898Y42506D01*
X686023Y42516D01*
X686148Y42506D01*
X686273Y42466D01*
X686383Y42406D01*
X686483Y42326D01*
X686563Y42226D01*
X686623Y42116D01*
X686663Y41991D01*
X686673Y41866D01*
Y38436D01*
X686703Y38406D01*
X686803Y38266D01*
X686823Y38226D01*
X686838Y38191D01*
X686858Y38151D01*
X686873Y38111D01*
X686883Y38071D01*
X686898Y38026D01*
X686903Y37986D01*
X686913Y37946D01*
X686918Y37901D01*
Y37861D01*
X686923Y37816D01*
X686918Y37771D01*
Y37731D01*
X686913Y37686D01*
X686903Y37646D01*
X686898Y37606D01*
X686883Y37561D01*
X686873Y37521D01*
X686858Y37481D01*
X686838Y37441D01*
X686823Y37406D01*
X686803Y37366D01*
X686703Y37226D01*
X686673Y37196D01*
Y36066D01*
X686663Y35941D01*
X686623Y35816D01*
X686563Y35706D01*
X686483Y35606D01*
X686383Y35526D01*
X686273Y35466D01*
X686148Y35426D01*
X686023Y35416D01*
G37*
G36*
G01X681299D02*
X681174Y35426D01*
X681049Y35466D01*
X680939Y35526D01*
X680839Y35606D01*
X680759Y35706D01*
X680699Y35816D01*
X680659Y35941D01*
X680649Y36066D01*
Y37196D01*
X680619Y37226D01*
X680519Y37366D01*
X680499Y37406D01*
X680484Y37441D01*
X680464Y37481D01*
X680449Y37521D01*
X680439Y37561D01*
X680424Y37606D01*
X680419Y37646D01*
X680409Y37686D01*
X680404Y37731D01*
Y37771D01*
X680399Y37816D01*
X680404Y37861D01*
Y37901D01*
X680409Y37946D01*
X680419Y37986D01*
X680424Y38026D01*
X680439Y38071D01*
X680449Y38111D01*
X680464Y38151D01*
X680484Y38191D01*
X680499Y38226D01*
X680519Y38266D01*
X680619Y38406D01*
X680649Y38436D01*
Y41866D01*
X680659Y41991D01*
X680699Y42116D01*
X680759Y42226D01*
X680839Y42326D01*
X680939Y42406D01*
X681049Y42466D01*
X681174Y42506D01*
X681299Y42516D01*
X681424Y42506D01*
X681549Y42466D01*
X681659Y42406D01*
X681759Y42326D01*
X681839Y42226D01*
X681899Y42116D01*
X681939Y41991D01*
X681949Y41866D01*
Y38436D01*
X681979Y38406D01*
X682079Y38266D01*
X682099Y38226D01*
X682114Y38191D01*
X682134Y38151D01*
X682149Y38111D01*
X682159Y38071D01*
X682174Y38026D01*
X682179Y37986D01*
X682189Y37946D01*
X682194Y37901D01*
Y37861D01*
X682199Y37816D01*
X682194Y37771D01*
Y37731D01*
X682189Y37686D01*
X682179Y37646D01*
X682174Y37606D01*
X682159Y37561D01*
X682149Y37521D01*
X682134Y37481D01*
X682114Y37441D01*
X682099Y37406D01*
X682079Y37366D01*
X681979Y37226D01*
X681949Y37196D01*
Y36066D01*
X681939Y35941D01*
X681899Y35816D01*
X681839Y35706D01*
X681759Y35606D01*
X681659Y35526D01*
X681549Y35466D01*
X681424Y35426D01*
X681299Y35416D01*
G37*
G36*
G01X709645D02*
X709520Y35426D01*
X709395Y35466D01*
X709285Y35526D01*
X709185Y35606D01*
X709105Y35706D01*
X709045Y35816D01*
X709005Y35941D01*
X708995Y36066D01*
Y37196D01*
X708965Y37226D01*
X708865Y37366D01*
X708845Y37406D01*
X708830Y37441D01*
X708810Y37481D01*
X708795Y37521D01*
X708785Y37561D01*
X708770Y37606D01*
X708765Y37646D01*
X708755Y37686D01*
X708750Y37731D01*
Y37771D01*
X708745Y37816D01*
X708750Y37861D01*
Y37901D01*
X708755Y37946D01*
X708765Y37986D01*
X708770Y38026D01*
X708785Y38071D01*
X708795Y38111D01*
X708810Y38151D01*
X708830Y38191D01*
X708845Y38226D01*
X708865Y38266D01*
X708965Y38406D01*
X708995Y38436D01*
Y41866D01*
X709005Y41991D01*
X709045Y42116D01*
X709105Y42226D01*
X709185Y42326D01*
X709285Y42406D01*
X709395Y42466D01*
X709520Y42506D01*
X709645Y42516D01*
X709770Y42506D01*
X709895Y42466D01*
X710005Y42406D01*
X710105Y42326D01*
X710185Y42226D01*
X710245Y42116D01*
X710285Y41991D01*
X710295Y41866D01*
Y38436D01*
X710325Y38406D01*
X710425Y38266D01*
X710445Y38226D01*
X710460Y38191D01*
X710480Y38151D01*
X710495Y38111D01*
X710505Y38071D01*
X710520Y38026D01*
X710525Y37986D01*
X710535Y37946D01*
X710540Y37901D01*
Y37861D01*
X710545Y37816D01*
X710540Y37771D01*
Y37731D01*
X710535Y37686D01*
X710525Y37646D01*
X710520Y37606D01*
X710505Y37561D01*
X710495Y37521D01*
X710480Y37481D01*
X710460Y37441D01*
X710445Y37406D01*
X710425Y37366D01*
X710325Y37226D01*
X710295Y37196D01*
Y36066D01*
X710285Y35941D01*
X710245Y35816D01*
X710185Y35706D01*
X710105Y35606D01*
X710005Y35526D01*
X709895Y35466D01*
X709770Y35426D01*
X709645Y35416D01*
G37*
G36*
G01X704921D02*
X704796Y35426D01*
X704671Y35466D01*
X704561Y35526D01*
X704461Y35606D01*
X704381Y35706D01*
X704321Y35816D01*
X704281Y35941D01*
X704271Y36066D01*
Y37196D01*
X704241Y37226D01*
X704141Y37366D01*
X704121Y37406D01*
X704106Y37441D01*
X704086Y37481D01*
X704071Y37521D01*
X704061Y37561D01*
X704046Y37606D01*
X704041Y37646D01*
X704031Y37686D01*
X704026Y37731D01*
Y37771D01*
X704021Y37816D01*
X704026Y37861D01*
Y37901D01*
X704031Y37946D01*
X704041Y37986D01*
X704046Y38026D01*
X704061Y38071D01*
X704071Y38111D01*
X704086Y38151D01*
X704106Y38191D01*
X704121Y38226D01*
X704141Y38266D01*
X704241Y38406D01*
X704271Y38436D01*
Y41866D01*
X704281Y41991D01*
X704321Y42116D01*
X704381Y42226D01*
X704461Y42326D01*
X704561Y42406D01*
X704671Y42466D01*
X704796Y42506D01*
X704921Y42516D01*
X705046Y42506D01*
X705171Y42466D01*
X705281Y42406D01*
X705381Y42326D01*
X705461Y42226D01*
X705521Y42116D01*
X705561Y41991D01*
X705571Y41866D01*
Y38436D01*
X705601Y38406D01*
X705701Y38266D01*
X705721Y38226D01*
X705736Y38191D01*
X705756Y38151D01*
X705771Y38111D01*
X705781Y38071D01*
X705796Y38026D01*
X705801Y37986D01*
X705811Y37946D01*
X705816Y37901D01*
Y37861D01*
X705821Y37816D01*
X705816Y37771D01*
Y37731D01*
X705811Y37686D01*
X705801Y37646D01*
X705796Y37606D01*
X705781Y37561D01*
X705771Y37521D01*
X705756Y37481D01*
X705736Y37441D01*
X705721Y37406D01*
X705701Y37366D01*
X705601Y37226D01*
X705571Y37196D01*
Y36066D01*
X705561Y35941D01*
X705521Y35816D01*
X705461Y35706D01*
X705381Y35606D01*
X705281Y35526D01*
X705171Y35466D01*
X705046Y35426D01*
X704921Y35416D01*
G37*
G36*
G01X700197D02*
X700072Y35426D01*
X699947Y35466D01*
X699837Y35526D01*
X699737Y35606D01*
X699657Y35706D01*
X699597Y35816D01*
X699557Y35941D01*
X699547Y36066D01*
Y37196D01*
X699517Y37226D01*
X699417Y37366D01*
X699397Y37406D01*
X699382Y37441D01*
X699362Y37481D01*
X699347Y37521D01*
X699337Y37561D01*
X699322Y37606D01*
X699317Y37646D01*
X699307Y37686D01*
X699302Y37731D01*
Y37771D01*
X699297Y37816D01*
X699302Y37861D01*
Y37901D01*
X699307Y37946D01*
X699317Y37986D01*
X699322Y38026D01*
X699337Y38071D01*
X699347Y38111D01*
X699362Y38151D01*
X699382Y38191D01*
X699397Y38226D01*
X699417Y38266D01*
X699517Y38406D01*
X699547Y38436D01*
Y41866D01*
X699557Y41991D01*
X699597Y42116D01*
X699657Y42226D01*
X699737Y42326D01*
X699837Y42406D01*
X699947Y42466D01*
X700072Y42506D01*
X700197Y42516D01*
X700322Y42506D01*
X700447Y42466D01*
X700557Y42406D01*
X700657Y42326D01*
X700737Y42226D01*
X700797Y42116D01*
X700837Y41991D01*
X700847Y41866D01*
Y38436D01*
X700877Y38406D01*
X700977Y38266D01*
X700997Y38226D01*
X701012Y38191D01*
X701032Y38151D01*
X701047Y38111D01*
X701057Y38071D01*
X701072Y38026D01*
X701077Y37986D01*
X701087Y37946D01*
X701092Y37901D01*
Y37861D01*
X701097Y37816D01*
X701092Y37771D01*
Y37731D01*
X701087Y37686D01*
X701077Y37646D01*
X701072Y37606D01*
X701057Y37561D01*
X701047Y37521D01*
X701032Y37481D01*
X701012Y37441D01*
X700997Y37406D01*
X700977Y37366D01*
X700877Y37226D01*
X700847Y37196D01*
Y36066D01*
X700837Y35941D01*
X700797Y35816D01*
X700737Y35706D01*
X700657Y35606D01*
X700557Y35526D01*
X700447Y35466D01*
X700322Y35426D01*
X700197Y35416D01*
G37*
G36*
G01X723819D02*
X723694Y35426D01*
X723569Y35466D01*
X723459Y35526D01*
X723359Y35606D01*
X723279Y35706D01*
X723219Y35816D01*
X723179Y35941D01*
X723169Y36066D01*
Y37196D01*
X723139Y37226D01*
X723039Y37366D01*
X723019Y37406D01*
X723004Y37441D01*
X722984Y37481D01*
X722969Y37521D01*
X722959Y37561D01*
X722944Y37606D01*
X722939Y37646D01*
X722929Y37686D01*
X722924Y37731D01*
Y37771D01*
X722919Y37816D01*
X722924Y37861D01*
Y37901D01*
X722929Y37946D01*
X722939Y37986D01*
X722944Y38026D01*
X722959Y38071D01*
X722969Y38111D01*
X722984Y38151D01*
X723004Y38191D01*
X723019Y38226D01*
X723039Y38266D01*
X723139Y38406D01*
X723169Y38436D01*
Y41866D01*
X723179Y41991D01*
X723219Y42116D01*
X723279Y42226D01*
X723359Y42326D01*
X723459Y42406D01*
X723569Y42466D01*
X723694Y42506D01*
X723819Y42516D01*
X723944Y42506D01*
X724069Y42466D01*
X724179Y42406D01*
X724279Y42326D01*
X724359Y42226D01*
X724419Y42116D01*
X724459Y41991D01*
X724469Y41866D01*
Y38436D01*
X724499Y38406D01*
X724599Y38266D01*
X724619Y38226D01*
X724634Y38191D01*
X724654Y38151D01*
X724669Y38111D01*
X724679Y38071D01*
X724694Y38026D01*
X724699Y37986D01*
X724709Y37946D01*
X724714Y37901D01*
Y37861D01*
X724719Y37816D01*
X724714Y37771D01*
Y37731D01*
X724709Y37686D01*
X724699Y37646D01*
X724694Y37606D01*
X724679Y37561D01*
X724669Y37521D01*
X724654Y37481D01*
X724634Y37441D01*
X724619Y37406D01*
X724599Y37366D01*
X724499Y37226D01*
X724469Y37196D01*
Y36066D01*
X724459Y35941D01*
X724419Y35816D01*
X724359Y35706D01*
X724279Y35606D01*
X724179Y35526D01*
X724069Y35466D01*
X723944Y35426D01*
X723819Y35416D01*
G37*
G36*
G01X719094D02*
X718969Y35426D01*
X718844Y35466D01*
X718734Y35526D01*
X718634Y35606D01*
X718554Y35706D01*
X718494Y35816D01*
X718454Y35941D01*
X718444Y36066D01*
Y37196D01*
X718414Y37226D01*
X718314Y37366D01*
X718294Y37406D01*
X718279Y37441D01*
X718259Y37481D01*
X718244Y37521D01*
X718234Y37561D01*
X718219Y37606D01*
X718214Y37646D01*
X718204Y37686D01*
X718199Y37731D01*
Y37771D01*
X718194Y37816D01*
X718199Y37861D01*
Y37901D01*
X718204Y37946D01*
X718214Y37986D01*
X718219Y38026D01*
X718234Y38071D01*
X718244Y38111D01*
X718259Y38151D01*
X718279Y38191D01*
X718294Y38226D01*
X718314Y38266D01*
X718414Y38406D01*
X718444Y38436D01*
Y41866D01*
X718454Y41991D01*
X718494Y42116D01*
X718554Y42226D01*
X718634Y42326D01*
X718734Y42406D01*
X718844Y42466D01*
X718969Y42506D01*
X719094Y42516D01*
X719219Y42506D01*
X719344Y42466D01*
X719454Y42406D01*
X719554Y42326D01*
X719634Y42226D01*
X719694Y42116D01*
X719734Y41991D01*
X719744Y41866D01*
Y38436D01*
X719774Y38406D01*
X719874Y38266D01*
X719894Y38226D01*
X719909Y38191D01*
X719929Y38151D01*
X719944Y38111D01*
X719954Y38071D01*
X719969Y38026D01*
X719974Y37986D01*
X719984Y37946D01*
X719989Y37901D01*
Y37861D01*
X719994Y37816D01*
X719989Y37771D01*
Y37731D01*
X719984Y37686D01*
X719974Y37646D01*
X719969Y37606D01*
X719954Y37561D01*
X719944Y37521D01*
X719929Y37481D01*
X719909Y37441D01*
X719894Y37406D01*
X719874Y37366D01*
X719774Y37226D01*
X719744Y37196D01*
Y36066D01*
X719734Y35941D01*
X719694Y35816D01*
X719634Y35706D01*
X719554Y35606D01*
X719454Y35526D01*
X719344Y35466D01*
X719219Y35426D01*
X719094Y35416D01*
G37*
G36*
G01X714370D02*
X714245Y35426D01*
X714120Y35466D01*
X714010Y35526D01*
X713910Y35606D01*
X713830Y35706D01*
X713770Y35816D01*
X713730Y35941D01*
X713720Y36066D01*
Y37196D01*
X713690Y37226D01*
X713590Y37366D01*
X713570Y37406D01*
X713555Y37441D01*
X713535Y37481D01*
X713520Y37521D01*
X713510Y37561D01*
X713495Y37606D01*
X713490Y37646D01*
X713480Y37686D01*
X713475Y37731D01*
Y37771D01*
X713470Y37816D01*
X713475Y37861D01*
Y37901D01*
X713480Y37946D01*
X713490Y37986D01*
X713495Y38026D01*
X713510Y38071D01*
X713520Y38111D01*
X713535Y38151D01*
X713555Y38191D01*
X713570Y38226D01*
X713590Y38266D01*
X713690Y38406D01*
X713720Y38436D01*
Y41866D01*
X713730Y41991D01*
X713770Y42116D01*
X713830Y42226D01*
X713910Y42326D01*
X714010Y42406D01*
X714120Y42466D01*
X714245Y42506D01*
X714370Y42516D01*
X714495Y42506D01*
X714620Y42466D01*
X714730Y42406D01*
X714830Y42326D01*
X714910Y42226D01*
X714970Y42116D01*
X715010Y41991D01*
X715020Y41866D01*
Y38436D01*
X715050Y38406D01*
X715150Y38266D01*
X715170Y38226D01*
X715185Y38191D01*
X715205Y38151D01*
X715220Y38111D01*
X715230Y38071D01*
X715245Y38026D01*
X715250Y37986D01*
X715260Y37946D01*
X715265Y37901D01*
Y37861D01*
X715270Y37816D01*
X715265Y37771D01*
Y37731D01*
X715260Y37686D01*
X715250Y37646D01*
X715245Y37606D01*
X715230Y37561D01*
X715220Y37521D01*
X715205Y37481D01*
X715185Y37441D01*
X715170Y37406D01*
X715150Y37366D01*
X715050Y37226D01*
X715020Y37196D01*
Y36066D01*
X715010Y35941D01*
X714970Y35816D01*
X714910Y35706D01*
X714830Y35606D01*
X714730Y35526D01*
X714620Y35466D01*
X714495Y35426D01*
X714370Y35416D01*
G37*
G36*
G01X737992D02*
X737867Y35426D01*
X737742Y35466D01*
X737632Y35526D01*
X737532Y35606D01*
X737452Y35706D01*
X737392Y35816D01*
X737352Y35941D01*
X737342Y36066D01*
Y37196D01*
X737312Y37226D01*
X737212Y37366D01*
X737192Y37406D01*
X737177Y37441D01*
X737157Y37481D01*
X737142Y37521D01*
X737132Y37561D01*
X737117Y37606D01*
X737112Y37646D01*
X737102Y37686D01*
X737097Y37731D01*
Y37771D01*
X737092Y37816D01*
X737097Y37861D01*
Y37901D01*
X737102Y37946D01*
X737112Y37986D01*
X737117Y38026D01*
X737132Y38071D01*
X737142Y38111D01*
X737157Y38151D01*
X737177Y38191D01*
X737192Y38226D01*
X737212Y38266D01*
X737312Y38406D01*
X737342Y38436D01*
Y41866D01*
X737352Y41991D01*
X737392Y42116D01*
X737452Y42226D01*
X737532Y42326D01*
X737632Y42406D01*
X737742Y42466D01*
X737867Y42506D01*
X737992Y42516D01*
X738117Y42506D01*
X738242Y42466D01*
X738352Y42406D01*
X738452Y42326D01*
X738532Y42226D01*
X738592Y42116D01*
X738632Y41991D01*
X738642Y41866D01*
Y38436D01*
X738672Y38406D01*
X738772Y38266D01*
X738792Y38226D01*
X738807Y38191D01*
X738827Y38151D01*
X738842Y38111D01*
X738852Y38071D01*
X738867Y38026D01*
X738872Y37986D01*
X738882Y37946D01*
X738887Y37901D01*
Y37861D01*
X738892Y37816D01*
X738887Y37771D01*
Y37731D01*
X738882Y37686D01*
X738872Y37646D01*
X738867Y37606D01*
X738852Y37561D01*
X738842Y37521D01*
X738827Y37481D01*
X738807Y37441D01*
X738792Y37406D01*
X738772Y37366D01*
X738672Y37226D01*
X738642Y37196D01*
Y36066D01*
X738632Y35941D01*
X738592Y35816D01*
X738532Y35706D01*
X738452Y35606D01*
X738352Y35526D01*
X738242Y35466D01*
X738117Y35426D01*
X737992Y35416D01*
G37*
G36*
G01X733267D02*
X733142Y35426D01*
X733017Y35466D01*
X732907Y35526D01*
X732807Y35606D01*
X732727Y35706D01*
X732667Y35816D01*
X732627Y35941D01*
X732617Y36066D01*
Y37196D01*
X732587Y37226D01*
X732487Y37366D01*
X732467Y37406D01*
X732452Y37441D01*
X732432Y37481D01*
X732417Y37521D01*
X732407Y37561D01*
X732392Y37606D01*
X732387Y37646D01*
X732377Y37686D01*
X732372Y37731D01*
Y37771D01*
X732367Y37816D01*
X732372Y37861D01*
Y37901D01*
X732377Y37946D01*
X732387Y37986D01*
X732392Y38026D01*
X732407Y38071D01*
X732417Y38111D01*
X732432Y38151D01*
X732452Y38191D01*
X732467Y38226D01*
X732487Y38266D01*
X732587Y38406D01*
X732617Y38436D01*
Y41866D01*
X732627Y41991D01*
X732667Y42116D01*
X732727Y42226D01*
X732807Y42326D01*
X732907Y42406D01*
X733017Y42466D01*
X733142Y42506D01*
X733267Y42516D01*
X733392Y42506D01*
X733517Y42466D01*
X733627Y42406D01*
X733727Y42326D01*
X733807Y42226D01*
X733867Y42116D01*
X733907Y41991D01*
X733917Y41866D01*
Y38436D01*
X733947Y38406D01*
X734047Y38266D01*
X734067Y38226D01*
X734082Y38191D01*
X734102Y38151D01*
X734117Y38111D01*
X734127Y38071D01*
X734142Y38026D01*
X734147Y37986D01*
X734157Y37946D01*
X734162Y37901D01*
Y37861D01*
X734167Y37816D01*
X734162Y37771D01*
Y37731D01*
X734157Y37686D01*
X734147Y37646D01*
X734142Y37606D01*
X734127Y37561D01*
X734117Y37521D01*
X734102Y37481D01*
X734082Y37441D01*
X734067Y37406D01*
X734047Y37366D01*
X733947Y37226D01*
X733917Y37196D01*
Y36066D01*
X733907Y35941D01*
X733867Y35816D01*
X733807Y35706D01*
X733727Y35606D01*
X733627Y35526D01*
X733517Y35466D01*
X733392Y35426D01*
X733267Y35416D01*
G37*
G36*
G01X728543D02*
X728418Y35426D01*
X728293Y35466D01*
X728183Y35526D01*
X728083Y35606D01*
X728003Y35706D01*
X727943Y35816D01*
X727903Y35941D01*
X727893Y36066D01*
Y37196D01*
X727863Y37226D01*
X727763Y37366D01*
X727743Y37406D01*
X727728Y37441D01*
X727708Y37481D01*
X727693Y37521D01*
X727683Y37561D01*
X727668Y37606D01*
X727663Y37646D01*
X727653Y37686D01*
X727648Y37731D01*
Y37771D01*
X727643Y37816D01*
X727648Y37861D01*
Y37901D01*
X727653Y37946D01*
X727663Y37986D01*
X727668Y38026D01*
X727683Y38071D01*
X727693Y38111D01*
X727708Y38151D01*
X727728Y38191D01*
X727743Y38226D01*
X727763Y38266D01*
X727863Y38406D01*
X727893Y38436D01*
Y41866D01*
X727903Y41991D01*
X727943Y42116D01*
X728003Y42226D01*
X728083Y42326D01*
X728183Y42406D01*
X728293Y42466D01*
X728418Y42506D01*
X728543Y42516D01*
X728668Y42506D01*
X728793Y42466D01*
X728903Y42406D01*
X729003Y42326D01*
X729083Y42226D01*
X729143Y42116D01*
X729183Y41991D01*
X729193Y41866D01*
Y38436D01*
X729223Y38406D01*
X729323Y38266D01*
X729343Y38226D01*
X729358Y38191D01*
X729378Y38151D01*
X729393Y38111D01*
X729403Y38071D01*
X729418Y38026D01*
X729423Y37986D01*
X729433Y37946D01*
X729438Y37901D01*
Y37861D01*
X729443Y37816D01*
X729438Y37771D01*
Y37731D01*
X729433Y37686D01*
X729423Y37646D01*
X729418Y37606D01*
X729403Y37561D01*
X729393Y37521D01*
X729378Y37481D01*
X729358Y37441D01*
X729343Y37406D01*
X729323Y37366D01*
X729223Y37226D01*
X729193Y37196D01*
Y36066D01*
X729183Y35941D01*
X729143Y35816D01*
X729083Y35706D01*
X729003Y35606D01*
X728903Y35526D01*
X728793Y35466D01*
X728668Y35426D01*
X728543Y35416D01*
G37*
G36*
G01X752165D02*
X752040Y35426D01*
X751915Y35466D01*
X751805Y35526D01*
X751705Y35606D01*
X751625Y35706D01*
X751565Y35816D01*
X751525Y35941D01*
X751515Y36066D01*
Y37196D01*
X751485Y37226D01*
X751385Y37366D01*
X751365Y37406D01*
X751350Y37441D01*
X751330Y37481D01*
X751315Y37521D01*
X751305Y37561D01*
X751290Y37606D01*
X751285Y37646D01*
X751275Y37686D01*
X751270Y37731D01*
Y37771D01*
X751265Y37816D01*
X751270Y37861D01*
Y37901D01*
X751275Y37946D01*
X751285Y37986D01*
X751290Y38026D01*
X751305Y38071D01*
X751315Y38111D01*
X751330Y38151D01*
X751350Y38191D01*
X751365Y38226D01*
X751385Y38266D01*
X751485Y38406D01*
X751515Y38436D01*
Y41866D01*
X751525Y41991D01*
X751565Y42116D01*
X751625Y42226D01*
X751705Y42326D01*
X751805Y42406D01*
X751915Y42466D01*
X752040Y42506D01*
X752165Y42516D01*
X752290Y42506D01*
X752415Y42466D01*
X752525Y42406D01*
X752625Y42326D01*
X752705Y42226D01*
X752765Y42116D01*
X752805Y41991D01*
X752815Y41866D01*
Y38436D01*
X752845Y38406D01*
X752945Y38266D01*
X752965Y38226D01*
X752980Y38191D01*
X753000Y38151D01*
X753015Y38111D01*
X753025Y38071D01*
X753040Y38026D01*
X753045Y37986D01*
X753055Y37946D01*
X753060Y37901D01*
Y37861D01*
X753065Y37816D01*
X753060Y37771D01*
Y37731D01*
X753055Y37686D01*
X753045Y37646D01*
X753040Y37606D01*
X753025Y37561D01*
X753015Y37521D01*
X753000Y37481D01*
X752980Y37441D01*
X752965Y37406D01*
X752945Y37366D01*
X752845Y37226D01*
X752815Y37196D01*
Y36066D01*
X752805Y35941D01*
X752765Y35816D01*
X752705Y35706D01*
X752625Y35606D01*
X752525Y35526D01*
X752415Y35466D01*
X752290Y35426D01*
X752165Y35416D01*
G37*
G36*
G01X747441D02*
X747316Y35426D01*
X747191Y35466D01*
X747081Y35526D01*
X746981Y35606D01*
X746901Y35706D01*
X746841Y35816D01*
X746801Y35941D01*
X746791Y36066D01*
Y37196D01*
X746761Y37226D01*
X746661Y37366D01*
X746641Y37406D01*
X746626Y37441D01*
X746606Y37481D01*
X746591Y37521D01*
X746581Y37561D01*
X746566Y37606D01*
X746561Y37646D01*
X746551Y37686D01*
X746546Y37731D01*
Y37771D01*
X746541Y37816D01*
X746546Y37861D01*
Y37901D01*
X746551Y37946D01*
X746561Y37986D01*
X746566Y38026D01*
X746581Y38071D01*
X746591Y38111D01*
X746606Y38151D01*
X746626Y38191D01*
X746641Y38226D01*
X746661Y38266D01*
X746761Y38406D01*
X746791Y38436D01*
Y41866D01*
X746801Y41991D01*
X746841Y42116D01*
X746901Y42226D01*
X746981Y42326D01*
X747081Y42406D01*
X747191Y42466D01*
X747316Y42506D01*
X747441Y42516D01*
X747566Y42506D01*
X747691Y42466D01*
X747801Y42406D01*
X747901Y42326D01*
X747981Y42226D01*
X748041Y42116D01*
X748081Y41991D01*
X748091Y41866D01*
Y38436D01*
X748121Y38406D01*
X748221Y38266D01*
X748241Y38226D01*
X748256Y38191D01*
X748276Y38151D01*
X748291Y38111D01*
X748301Y38071D01*
X748316Y38026D01*
X748321Y37986D01*
X748331Y37946D01*
X748336Y37901D01*
Y37861D01*
X748341Y37816D01*
X748336Y37771D01*
Y37731D01*
X748331Y37686D01*
X748321Y37646D01*
X748316Y37606D01*
X748301Y37561D01*
X748291Y37521D01*
X748276Y37481D01*
X748256Y37441D01*
X748241Y37406D01*
X748221Y37366D01*
X748121Y37226D01*
X748091Y37196D01*
Y36066D01*
X748081Y35941D01*
X748041Y35816D01*
X747981Y35706D01*
X747901Y35606D01*
X747801Y35526D01*
X747691Y35466D01*
X747566Y35426D01*
X747441Y35416D01*
G37*
G36*
G01X742716D02*
X742591Y35426D01*
X742466Y35466D01*
X742356Y35526D01*
X742256Y35606D01*
X742176Y35706D01*
X742116Y35816D01*
X742076Y35941D01*
X742066Y36066D01*
Y37196D01*
X742036Y37226D01*
X741936Y37366D01*
X741916Y37406D01*
X741901Y37441D01*
X741881Y37481D01*
X741866Y37521D01*
X741856Y37561D01*
X741841Y37606D01*
X741836Y37646D01*
X741826Y37686D01*
X741821Y37731D01*
Y37771D01*
X741816Y37816D01*
X741821Y37861D01*
Y37901D01*
X741826Y37946D01*
X741836Y37986D01*
X741841Y38026D01*
X741856Y38071D01*
X741866Y38111D01*
X741881Y38151D01*
X741901Y38191D01*
X741916Y38226D01*
X741936Y38266D01*
X742036Y38406D01*
X742066Y38436D01*
Y41866D01*
X742076Y41991D01*
X742116Y42116D01*
X742176Y42226D01*
X742256Y42326D01*
X742356Y42406D01*
X742466Y42466D01*
X742591Y42506D01*
X742716Y42516D01*
X742841Y42506D01*
X742966Y42466D01*
X743076Y42406D01*
X743176Y42326D01*
X743256Y42226D01*
X743316Y42116D01*
X743356Y41991D01*
X743366Y41866D01*
Y38436D01*
X743396Y38406D01*
X743496Y38266D01*
X743516Y38226D01*
X743531Y38191D01*
X743551Y38151D01*
X743566Y38111D01*
X743576Y38071D01*
X743591Y38026D01*
X743596Y37986D01*
X743606Y37946D01*
X743611Y37901D01*
Y37861D01*
X743616Y37816D01*
X743611Y37771D01*
Y37731D01*
X743606Y37686D01*
X743596Y37646D01*
X743591Y37606D01*
X743576Y37561D01*
X743566Y37521D01*
X743551Y37481D01*
X743531Y37441D01*
X743516Y37406D01*
X743496Y37366D01*
X743396Y37226D01*
X743366Y37196D01*
Y36066D01*
X743356Y35941D01*
X743316Y35816D01*
X743256Y35706D01*
X743176Y35606D01*
X743076Y35526D01*
X742966Y35466D01*
X742841Y35426D01*
X742716Y35416D01*
G37*
G54D111*
X551500Y187500D03*
X562000Y85000D03*
X570500Y190500D03*
X558500Y194500D03*
X572100Y196600D03*
X595350Y193050D03*
X609500Y200500D03*
X806200Y91000D03*
Y97000D03*
Y103000D03*
Y109000D03*
G36*
G01X499410Y249980D02*
X499535Y249970D01*
X499660Y249930D01*
X499770Y249870D01*
X499870Y249790D01*
X499950Y249690D01*
X500010Y249580D01*
X500050Y249455D01*
X500060Y249330D01*
Y247205D01*
X500090Y247175D01*
X500115Y247140D01*
X500145Y247105D01*
X500165Y247070D01*
X500190Y247035D01*
X500230Y246955D01*
X500275Y246835D01*
X500285Y246795D01*
X500295Y246750D01*
X500300Y246710D01*
X500310Y246665D01*
Y246495D01*
X500300Y246450D01*
X500295Y246410D01*
X500285Y246365D01*
X500275Y246325D01*
X500230Y246205D01*
X500190Y246125D01*
X500165Y246090D01*
X500145Y246055D01*
X500115Y246020D01*
X500090Y245985D01*
X500060Y245955D01*
Y243530D01*
X500050Y243405D01*
X500010Y243280D01*
X499950Y243170D01*
X499870Y243070D01*
X499770Y242990D01*
X499660Y242930D01*
X499535Y242890D01*
X499410Y242880D01*
X499285Y242890D01*
X499160Y242930D01*
X499050Y242990D01*
X498950Y243070D01*
X498870Y243170D01*
X498810Y243280D01*
X498770Y243405D01*
X498760Y243530D01*
Y245960D01*
X498730Y245990D01*
X498630Y246130D01*
X498610Y246170D01*
X498595Y246205D01*
X498575Y246245D01*
X498560Y246285D01*
X498550Y246325D01*
X498535Y246370D01*
X498530Y246410D01*
X498520Y246450D01*
X498515Y246495D01*
Y246535D01*
X498510Y246580D01*
X498515Y246625D01*
Y246665D01*
X498520Y246710D01*
X498530Y246750D01*
X498535Y246790D01*
X498550Y246835D01*
X498560Y246875D01*
X498575Y246915D01*
X498595Y246955D01*
X498610Y246990D01*
X498630Y247030D01*
X498730Y247170D01*
X498760Y247200D01*
Y249330D01*
X498770Y249455D01*
X498810Y249580D01*
X498870Y249690D01*
X498950Y249790D01*
X499050Y249870D01*
X499160Y249930D01*
X499285Y249970D01*
X499410Y249980D01*
G37*
G36*
G01X504134D02*
X504259Y249970D01*
X504384Y249930D01*
X504494Y249870D01*
X504594Y249790D01*
X504674Y249690D01*
X504734Y249580D01*
X504774Y249455D01*
X504784Y249330D01*
Y247205D01*
X504814Y247175D01*
X504839Y247140D01*
X504869Y247105D01*
X504889Y247070D01*
X504914Y247035D01*
X504954Y246955D01*
X504999Y246835D01*
X505009Y246795D01*
X505019Y246750D01*
X505024Y246710D01*
X505034Y246665D01*
Y246495D01*
X505024Y246450D01*
X505019Y246410D01*
X505009Y246365D01*
X504999Y246325D01*
X504954Y246205D01*
X504914Y246125D01*
X504889Y246090D01*
X504869Y246055D01*
X504839Y246020D01*
X504814Y245985D01*
X504784Y245955D01*
Y243530D01*
X504774Y243405D01*
X504734Y243280D01*
X504674Y243170D01*
X504594Y243070D01*
X504494Y242990D01*
X504384Y242930D01*
X504259Y242890D01*
X504134Y242880D01*
X504009Y242890D01*
X503884Y242930D01*
X503774Y242990D01*
X503674Y243070D01*
X503594Y243170D01*
X503534Y243280D01*
X503494Y243405D01*
X503484Y243530D01*
Y245960D01*
X503454Y245990D01*
X503354Y246130D01*
X503334Y246170D01*
X503319Y246205D01*
X503299Y246245D01*
X503284Y246285D01*
X503274Y246325D01*
X503259Y246370D01*
X503254Y246410D01*
X503244Y246450D01*
X503239Y246495D01*
Y246535D01*
X503234Y246580D01*
X503239Y246625D01*
Y246665D01*
X503244Y246710D01*
X503254Y246750D01*
X503259Y246790D01*
X503274Y246835D01*
X503284Y246875D01*
X503299Y246915D01*
X503319Y246955D01*
X503334Y246990D01*
X503354Y247030D01*
X503454Y247170D01*
X503484Y247200D01*
Y249330D01*
X503494Y249455D01*
X503534Y249580D01*
X503594Y249690D01*
X503674Y249790D01*
X503774Y249870D01*
X503884Y249930D01*
X504009Y249970D01*
X504134Y249980D01*
G37*
G36*
G01X508859D02*
X508984Y249970D01*
X509109Y249930D01*
X509219Y249870D01*
X509319Y249790D01*
X509399Y249690D01*
X509459Y249580D01*
X509499Y249455D01*
X509509Y249330D01*
Y247205D01*
X509539Y247175D01*
X509564Y247140D01*
X509594Y247105D01*
X509614Y247070D01*
X509639Y247035D01*
X509679Y246955D01*
X509724Y246835D01*
X509734Y246795D01*
X509744Y246750D01*
X509749Y246710D01*
X509759Y246665D01*
Y246495D01*
X509749Y246450D01*
X509744Y246410D01*
X509734Y246365D01*
X509724Y246325D01*
X509679Y246205D01*
X509639Y246125D01*
X509614Y246090D01*
X509594Y246055D01*
X509564Y246020D01*
X509539Y245985D01*
X509509Y245955D01*
Y243530D01*
X509499Y243405D01*
X509459Y243280D01*
X509399Y243170D01*
X509319Y243070D01*
X509219Y242990D01*
X509109Y242930D01*
X508984Y242890D01*
X508859Y242880D01*
X508734Y242890D01*
X508609Y242930D01*
X508499Y242990D01*
X508399Y243070D01*
X508319Y243170D01*
X508259Y243280D01*
X508219Y243405D01*
X508209Y243530D01*
Y245960D01*
X508179Y245990D01*
X508079Y246130D01*
X508059Y246170D01*
X508044Y246205D01*
X508024Y246245D01*
X508009Y246285D01*
X507999Y246325D01*
X507984Y246370D01*
X507979Y246410D01*
X507969Y246450D01*
X507964Y246495D01*
Y246535D01*
X507959Y246580D01*
X507964Y246625D01*
Y246665D01*
X507969Y246710D01*
X507979Y246750D01*
X507984Y246790D01*
X507999Y246835D01*
X508009Y246875D01*
X508024Y246915D01*
X508044Y246955D01*
X508059Y246990D01*
X508079Y247030D01*
X508179Y247170D01*
X508209Y247200D01*
Y249330D01*
X508219Y249455D01*
X508259Y249580D01*
X508319Y249690D01*
X508399Y249790D01*
X508499Y249870D01*
X508609Y249930D01*
X508734Y249970D01*
X508859Y249980D01*
G37*
G36*
G01X513583D02*
X513708Y249970D01*
X513833Y249930D01*
X513943Y249870D01*
X514043Y249790D01*
X514123Y249690D01*
X514183Y249580D01*
X514223Y249455D01*
X514233Y249330D01*
Y247205D01*
X514263Y247175D01*
X514288Y247140D01*
X514318Y247105D01*
X514338Y247070D01*
X514363Y247035D01*
X514403Y246955D01*
X514448Y246835D01*
X514458Y246795D01*
X514468Y246750D01*
X514473Y246710D01*
X514483Y246665D01*
Y246495D01*
X514473Y246450D01*
X514468Y246410D01*
X514458Y246365D01*
X514448Y246325D01*
X514403Y246205D01*
X514363Y246125D01*
X514338Y246090D01*
X514318Y246055D01*
X514288Y246020D01*
X514263Y245985D01*
X514233Y245955D01*
Y243530D01*
X514223Y243405D01*
X514183Y243280D01*
X514123Y243170D01*
X514043Y243070D01*
X513943Y242990D01*
X513833Y242930D01*
X513708Y242890D01*
X513583Y242880D01*
X513458Y242890D01*
X513333Y242930D01*
X513223Y242990D01*
X513123Y243070D01*
X513043Y243170D01*
X512983Y243280D01*
X512943Y243405D01*
X512933Y243530D01*
Y245960D01*
X512903Y245990D01*
X512803Y246130D01*
X512783Y246170D01*
X512768Y246205D01*
X512748Y246245D01*
X512733Y246285D01*
X512723Y246325D01*
X512708Y246370D01*
X512703Y246410D01*
X512693Y246450D01*
X512688Y246495D01*
Y246535D01*
X512683Y246580D01*
X512688Y246625D01*
Y246665D01*
X512693Y246710D01*
X512703Y246750D01*
X512708Y246790D01*
X512723Y246835D01*
X512733Y246875D01*
X512748Y246915D01*
X512768Y246955D01*
X512783Y246990D01*
X512803Y247030D01*
X512903Y247170D01*
X512933Y247200D01*
Y249330D01*
X512943Y249455D01*
X512983Y249580D01*
X513043Y249690D01*
X513123Y249790D01*
X513223Y249870D01*
X513333Y249930D01*
X513458Y249970D01*
X513583Y249980D01*
G37*
G36*
G01X518307D02*
X518432Y249970D01*
X518557Y249930D01*
X518667Y249870D01*
X518767Y249790D01*
X518847Y249690D01*
X518907Y249580D01*
X518947Y249455D01*
X518957Y249330D01*
Y247205D01*
X518987Y247175D01*
X519012Y247140D01*
X519042Y247105D01*
X519062Y247070D01*
X519087Y247035D01*
X519127Y246955D01*
X519172Y246835D01*
X519182Y246795D01*
X519192Y246750D01*
X519197Y246710D01*
X519207Y246665D01*
Y246495D01*
X519197Y246450D01*
X519192Y246410D01*
X519182Y246365D01*
X519172Y246325D01*
X519127Y246205D01*
X519087Y246125D01*
X519062Y246090D01*
X519042Y246055D01*
X519012Y246020D01*
X518987Y245985D01*
X518957Y245955D01*
Y243530D01*
X518947Y243405D01*
X518907Y243280D01*
X518847Y243170D01*
X518767Y243070D01*
X518667Y242990D01*
X518557Y242930D01*
X518432Y242890D01*
X518307Y242880D01*
X518182Y242890D01*
X518057Y242930D01*
X517947Y242990D01*
X517847Y243070D01*
X517767Y243170D01*
X517707Y243280D01*
X517667Y243405D01*
X517657Y243530D01*
Y245960D01*
X517627Y245990D01*
X517527Y246130D01*
X517507Y246170D01*
X517492Y246205D01*
X517472Y246245D01*
X517457Y246285D01*
X517447Y246325D01*
X517432Y246370D01*
X517427Y246410D01*
X517417Y246450D01*
X517412Y246495D01*
Y246535D01*
X517407Y246580D01*
X517412Y246625D01*
Y246665D01*
X517417Y246710D01*
X517427Y246750D01*
X517432Y246790D01*
X517447Y246835D01*
X517457Y246875D01*
X517472Y246915D01*
X517492Y246955D01*
X517507Y246990D01*
X517527Y247030D01*
X517627Y247170D01*
X517657Y247200D01*
Y249330D01*
X517667Y249455D01*
X517707Y249580D01*
X517767Y249690D01*
X517847Y249790D01*
X517947Y249870D01*
X518057Y249930D01*
X518182Y249970D01*
X518307Y249980D01*
G37*
G36*
G01X523032D02*
X523157Y249970D01*
X523282Y249930D01*
X523392Y249870D01*
X523492Y249790D01*
X523572Y249690D01*
X523632Y249580D01*
X523672Y249455D01*
X523682Y249330D01*
Y247205D01*
X523712Y247175D01*
X523737Y247140D01*
X523767Y247105D01*
X523787Y247070D01*
X523812Y247035D01*
X523852Y246955D01*
X523897Y246835D01*
X523907Y246795D01*
X523917Y246750D01*
X523922Y246710D01*
X523932Y246665D01*
Y246495D01*
X523922Y246450D01*
X523917Y246410D01*
X523907Y246365D01*
X523897Y246325D01*
X523852Y246205D01*
X523812Y246125D01*
X523787Y246090D01*
X523767Y246055D01*
X523737Y246020D01*
X523712Y245985D01*
X523682Y245955D01*
Y243530D01*
X523672Y243405D01*
X523632Y243280D01*
X523572Y243170D01*
X523492Y243070D01*
X523392Y242990D01*
X523282Y242930D01*
X523157Y242890D01*
X523032Y242880D01*
X522907Y242890D01*
X522782Y242930D01*
X522672Y242990D01*
X522572Y243070D01*
X522492Y243170D01*
X522432Y243280D01*
X522392Y243405D01*
X522382Y243530D01*
Y245960D01*
X522352Y245990D01*
X522252Y246130D01*
X522232Y246170D01*
X522217Y246205D01*
X522197Y246245D01*
X522182Y246285D01*
X522172Y246325D01*
X522157Y246370D01*
X522152Y246410D01*
X522142Y246450D01*
X522137Y246495D01*
Y246535D01*
X522132Y246580D01*
X522137Y246625D01*
Y246665D01*
X522142Y246710D01*
X522152Y246750D01*
X522157Y246790D01*
X522172Y246835D01*
X522182Y246875D01*
X522197Y246915D01*
X522217Y246955D01*
X522232Y246990D01*
X522252Y247030D01*
X522352Y247170D01*
X522382Y247200D01*
Y249330D01*
X522392Y249455D01*
X522432Y249580D01*
X522492Y249690D01*
X522572Y249790D01*
X522672Y249870D01*
X522782Y249930D01*
X522907Y249970D01*
X523032Y249980D01*
G37*
G36*
G01X527756D02*
X527881Y249970D01*
X528006Y249930D01*
X528116Y249870D01*
X528216Y249790D01*
X528296Y249690D01*
X528356Y249580D01*
X528396Y249455D01*
X528406Y249330D01*
Y247205D01*
X528436Y247175D01*
X528461Y247140D01*
X528491Y247105D01*
X528511Y247070D01*
X528536Y247035D01*
X528576Y246955D01*
X528621Y246835D01*
X528631Y246795D01*
X528641Y246750D01*
X528646Y246710D01*
X528656Y246665D01*
Y246495D01*
X528646Y246450D01*
X528641Y246410D01*
X528631Y246365D01*
X528621Y246325D01*
X528576Y246205D01*
X528536Y246125D01*
X528511Y246090D01*
X528491Y246055D01*
X528461Y246020D01*
X528436Y245985D01*
X528406Y245955D01*
Y243530D01*
X528396Y243405D01*
X528356Y243280D01*
X528296Y243170D01*
X528216Y243070D01*
X528116Y242990D01*
X528006Y242930D01*
X527881Y242890D01*
X527756Y242880D01*
X527631Y242890D01*
X527506Y242930D01*
X527396Y242990D01*
X527296Y243070D01*
X527216Y243170D01*
X527156Y243280D01*
X527116Y243405D01*
X527106Y243530D01*
Y245960D01*
X527076Y245990D01*
X526976Y246130D01*
X526956Y246170D01*
X526941Y246205D01*
X526921Y246245D01*
X526906Y246285D01*
X526896Y246325D01*
X526881Y246370D01*
X526876Y246410D01*
X526866Y246450D01*
X526861Y246495D01*
Y246535D01*
X526856Y246580D01*
X526861Y246625D01*
Y246665D01*
X526866Y246710D01*
X526876Y246750D01*
X526881Y246790D01*
X526896Y246835D01*
X526906Y246875D01*
X526921Y246915D01*
X526941Y246955D01*
X526956Y246990D01*
X526976Y247030D01*
X527076Y247170D01*
X527106Y247200D01*
Y249330D01*
X527116Y249455D01*
X527156Y249580D01*
X527216Y249690D01*
X527296Y249790D01*
X527396Y249870D01*
X527506Y249930D01*
X527631Y249970D01*
X527756Y249980D01*
G37*
G36*
G01X532481D02*
X532606Y249970D01*
X532731Y249930D01*
X532841Y249870D01*
X532941Y249790D01*
X533021Y249690D01*
X533081Y249580D01*
X533121Y249455D01*
X533131Y249330D01*
Y247205D01*
X533161Y247175D01*
X533186Y247140D01*
X533216Y247105D01*
X533236Y247070D01*
X533261Y247035D01*
X533301Y246955D01*
X533346Y246835D01*
X533356Y246795D01*
X533366Y246750D01*
X533371Y246710D01*
X533381Y246665D01*
Y246495D01*
X533371Y246450D01*
X533366Y246410D01*
X533356Y246365D01*
X533346Y246325D01*
X533301Y246205D01*
X533261Y246125D01*
X533236Y246090D01*
X533216Y246055D01*
X533186Y246020D01*
X533161Y245985D01*
X533131Y245955D01*
Y243530D01*
X533121Y243405D01*
X533081Y243280D01*
X533021Y243170D01*
X532941Y243070D01*
X532841Y242990D01*
X532731Y242930D01*
X532606Y242890D01*
X532481Y242880D01*
X532356Y242890D01*
X532231Y242930D01*
X532121Y242990D01*
X532021Y243070D01*
X531941Y243170D01*
X531881Y243280D01*
X531841Y243405D01*
X531831Y243530D01*
Y245960D01*
X531801Y245990D01*
X531701Y246130D01*
X531681Y246170D01*
X531666Y246205D01*
X531646Y246245D01*
X531631Y246285D01*
X531621Y246325D01*
X531606Y246370D01*
X531601Y246410D01*
X531591Y246450D01*
X531586Y246495D01*
Y246535D01*
X531581Y246580D01*
X531586Y246625D01*
Y246665D01*
X531591Y246710D01*
X531601Y246750D01*
X531606Y246790D01*
X531621Y246835D01*
X531631Y246875D01*
X531646Y246915D01*
X531666Y246955D01*
X531681Y246990D01*
X531701Y247030D01*
X531801Y247170D01*
X531831Y247200D01*
Y249330D01*
X531841Y249455D01*
X531881Y249580D01*
X531941Y249690D01*
X532021Y249790D01*
X532121Y249870D01*
X532231Y249930D01*
X532356Y249970D01*
X532481Y249980D01*
G37*
G36*
G01X537205D02*
X537330Y249970D01*
X537455Y249930D01*
X537565Y249870D01*
X537665Y249790D01*
X537745Y249690D01*
X537805Y249580D01*
X537845Y249455D01*
X537855Y249330D01*
Y247205D01*
X537885Y247175D01*
X537910Y247140D01*
X537940Y247105D01*
X537960Y247070D01*
X537985Y247035D01*
X538025Y246955D01*
X538070Y246835D01*
X538080Y246795D01*
X538090Y246750D01*
X538095Y246710D01*
X538105Y246665D01*
Y246495D01*
X538095Y246450D01*
X538090Y246410D01*
X538080Y246365D01*
X538070Y246325D01*
X538025Y246205D01*
X537985Y246125D01*
X537960Y246090D01*
X537940Y246055D01*
X537910Y246020D01*
X537885Y245985D01*
X537855Y245955D01*
Y243530D01*
X537845Y243405D01*
X537805Y243280D01*
X537745Y243170D01*
X537665Y243070D01*
X537565Y242990D01*
X537455Y242930D01*
X537330Y242890D01*
X537205Y242880D01*
X537080Y242890D01*
X536955Y242930D01*
X536845Y242990D01*
X536745Y243070D01*
X536665Y243170D01*
X536605Y243280D01*
X536565Y243405D01*
X536555Y243530D01*
Y245960D01*
X536525Y245990D01*
X536425Y246130D01*
X536405Y246170D01*
X536390Y246205D01*
X536370Y246245D01*
X536355Y246285D01*
X536345Y246325D01*
X536330Y246370D01*
X536325Y246410D01*
X536315Y246450D01*
X536310Y246495D01*
Y246535D01*
X536305Y246580D01*
X536310Y246625D01*
Y246665D01*
X536315Y246710D01*
X536325Y246750D01*
X536330Y246790D01*
X536345Y246835D01*
X536355Y246875D01*
X536370Y246915D01*
X536390Y246955D01*
X536405Y246990D01*
X536425Y247030D01*
X536525Y247170D01*
X536555Y247200D01*
Y249330D01*
X536565Y249455D01*
X536605Y249580D01*
X536665Y249690D01*
X536745Y249790D01*
X536845Y249870D01*
X536955Y249930D01*
X537080Y249970D01*
X537205Y249980D01*
G37*
G36*
G01X541929D02*
X542054Y249970D01*
X542179Y249930D01*
X542289Y249870D01*
X542389Y249790D01*
X542469Y249690D01*
X542529Y249580D01*
X542569Y249455D01*
X542579Y249330D01*
Y247205D01*
X542609Y247175D01*
X542634Y247140D01*
X542664Y247105D01*
X542684Y247070D01*
X542709Y247035D01*
X542749Y246955D01*
X542794Y246835D01*
X542804Y246795D01*
X542814Y246750D01*
X542819Y246710D01*
X542829Y246665D01*
Y246495D01*
X542819Y246450D01*
X542814Y246410D01*
X542804Y246365D01*
X542794Y246325D01*
X542749Y246205D01*
X542709Y246125D01*
X542684Y246090D01*
X542664Y246055D01*
X542634Y246020D01*
X542609Y245985D01*
X542579Y245955D01*
Y243530D01*
X542569Y243405D01*
X542529Y243280D01*
X542469Y243170D01*
X542389Y243070D01*
X542289Y242990D01*
X542179Y242930D01*
X542054Y242890D01*
X541929Y242880D01*
X541804Y242890D01*
X541679Y242930D01*
X541569Y242990D01*
X541469Y243070D01*
X541389Y243170D01*
X541329Y243280D01*
X541289Y243405D01*
X541279Y243530D01*
Y245960D01*
X541249Y245990D01*
X541149Y246130D01*
X541129Y246170D01*
X541114Y246205D01*
X541094Y246245D01*
X541079Y246285D01*
X541069Y246325D01*
X541054Y246370D01*
X541049Y246410D01*
X541039Y246450D01*
X541034Y246495D01*
Y246535D01*
X541029Y246580D01*
X541034Y246625D01*
Y246665D01*
X541039Y246710D01*
X541049Y246750D01*
X541054Y246790D01*
X541069Y246835D01*
X541079Y246875D01*
X541094Y246915D01*
X541114Y246955D01*
X541129Y246990D01*
X541149Y247030D01*
X541249Y247170D01*
X541279Y247200D01*
Y249330D01*
X541289Y249455D01*
X541329Y249580D01*
X541389Y249690D01*
X541469Y249790D01*
X541569Y249870D01*
X541679Y249930D01*
X541804Y249970D01*
X541929Y249980D01*
G37*
G36*
G01X546654D02*
X546779Y249970D01*
X546904Y249930D01*
X547014Y249870D01*
X547114Y249790D01*
X547194Y249690D01*
X547254Y249580D01*
X547294Y249455D01*
X547304Y249330D01*
Y247205D01*
X547334Y247175D01*
X547359Y247140D01*
X547389Y247105D01*
X547409Y247070D01*
X547434Y247035D01*
X547474Y246955D01*
X547519Y246835D01*
X547529Y246795D01*
X547539Y246750D01*
X547544Y246710D01*
X547554Y246665D01*
Y246495D01*
X547544Y246450D01*
X547539Y246410D01*
X547529Y246365D01*
X547519Y246325D01*
X547474Y246205D01*
X547434Y246125D01*
X547409Y246090D01*
X547389Y246055D01*
X547359Y246020D01*
X547334Y245985D01*
X547304Y245955D01*
Y243530D01*
X547294Y243405D01*
X547254Y243280D01*
X547194Y243170D01*
X547114Y243070D01*
X547014Y242990D01*
X546904Y242930D01*
X546779Y242890D01*
X546654Y242880D01*
X546529Y242890D01*
X546404Y242930D01*
X546294Y242990D01*
X546194Y243070D01*
X546114Y243170D01*
X546054Y243280D01*
X546014Y243405D01*
X546004Y243530D01*
Y245960D01*
X545974Y245990D01*
X545874Y246130D01*
X545854Y246170D01*
X545839Y246205D01*
X545819Y246245D01*
X545804Y246285D01*
X545794Y246325D01*
X545779Y246370D01*
X545774Y246410D01*
X545764Y246450D01*
X545759Y246495D01*
Y246535D01*
X545754Y246580D01*
X545759Y246625D01*
Y246665D01*
X545764Y246710D01*
X545774Y246750D01*
X545779Y246790D01*
X545794Y246835D01*
X545804Y246875D01*
X545819Y246915D01*
X545839Y246955D01*
X545854Y246990D01*
X545874Y247030D01*
X545974Y247170D01*
X546004Y247200D01*
Y249330D01*
X546014Y249455D01*
X546054Y249580D01*
X546114Y249690D01*
X546194Y249790D01*
X546294Y249870D01*
X546404Y249930D01*
X546529Y249970D01*
X546654Y249980D01*
G37*
G36*
G01X551378D02*
X551503Y249970D01*
X551628Y249930D01*
X551738Y249870D01*
X551838Y249790D01*
X551918Y249690D01*
X551978Y249580D01*
X552018Y249455D01*
X552028Y249330D01*
Y247205D01*
X552058Y247175D01*
X552083Y247140D01*
X552113Y247105D01*
X552133Y247070D01*
X552158Y247035D01*
X552198Y246955D01*
X552243Y246835D01*
X552253Y246795D01*
X552263Y246750D01*
X552268Y246710D01*
X552278Y246665D01*
Y246495D01*
X552268Y246450D01*
X552263Y246410D01*
X552253Y246365D01*
X552243Y246325D01*
X552198Y246205D01*
X552158Y246125D01*
X552133Y246090D01*
X552113Y246055D01*
X552083Y246020D01*
X552058Y245985D01*
X552028Y245955D01*
Y243530D01*
X552018Y243405D01*
X551978Y243280D01*
X551918Y243170D01*
X551838Y243070D01*
X551738Y242990D01*
X551628Y242930D01*
X551503Y242890D01*
X551378Y242880D01*
X551253Y242890D01*
X551128Y242930D01*
X551018Y242990D01*
X550918Y243070D01*
X550838Y243170D01*
X550778Y243280D01*
X550738Y243405D01*
X550728Y243530D01*
Y245960D01*
X550698Y245990D01*
X550598Y246130D01*
X550578Y246170D01*
X550563Y246205D01*
X550543Y246245D01*
X550528Y246285D01*
X550518Y246325D01*
X550503Y246370D01*
X550498Y246410D01*
X550488Y246450D01*
X550483Y246495D01*
Y246535D01*
X550478Y246580D01*
X550483Y246625D01*
Y246665D01*
X550488Y246710D01*
X550498Y246750D01*
X550503Y246790D01*
X550518Y246835D01*
X550528Y246875D01*
X550543Y246915D01*
X550563Y246955D01*
X550578Y246990D01*
X550598Y247030D01*
X550698Y247170D01*
X550728Y247200D01*
Y249330D01*
X550738Y249455D01*
X550778Y249580D01*
X550838Y249690D01*
X550918Y249790D01*
X551018Y249870D01*
X551128Y249930D01*
X551253Y249970D01*
X551378Y249980D01*
G37*
G36*
G01X556103D02*
X556228Y249970D01*
X556353Y249930D01*
X556463Y249870D01*
X556563Y249790D01*
X556643Y249690D01*
X556703Y249580D01*
X556743Y249455D01*
X556753Y249330D01*
Y247205D01*
X556783Y247175D01*
X556808Y247140D01*
X556838Y247105D01*
X556858Y247070D01*
X556883Y247035D01*
X556923Y246955D01*
X556968Y246835D01*
X556978Y246795D01*
X556988Y246750D01*
X556993Y246710D01*
X557003Y246665D01*
Y246495D01*
X556993Y246450D01*
X556988Y246410D01*
X556978Y246365D01*
X556968Y246325D01*
X556923Y246205D01*
X556883Y246125D01*
X556858Y246090D01*
X556838Y246055D01*
X556808Y246020D01*
X556783Y245985D01*
X556753Y245955D01*
Y243530D01*
X556743Y243405D01*
X556703Y243280D01*
X556643Y243170D01*
X556563Y243070D01*
X556463Y242990D01*
X556353Y242930D01*
X556228Y242890D01*
X556103Y242880D01*
X555978Y242890D01*
X555853Y242930D01*
X555743Y242990D01*
X555643Y243070D01*
X555563Y243170D01*
X555503Y243280D01*
X555463Y243405D01*
X555453Y243530D01*
Y245960D01*
X555423Y245990D01*
X555323Y246130D01*
X555303Y246170D01*
X555288Y246205D01*
X555268Y246245D01*
X555253Y246285D01*
X555243Y246325D01*
X555228Y246370D01*
X555223Y246410D01*
X555213Y246450D01*
X555208Y246495D01*
Y246535D01*
X555203Y246580D01*
X555208Y246625D01*
Y246665D01*
X555213Y246710D01*
X555223Y246750D01*
X555228Y246790D01*
X555243Y246835D01*
X555253Y246875D01*
X555268Y246915D01*
X555288Y246955D01*
X555303Y246990D01*
X555323Y247030D01*
X555423Y247170D01*
X555453Y247200D01*
Y249330D01*
X555463Y249455D01*
X555503Y249580D01*
X555563Y249690D01*
X555643Y249790D01*
X555743Y249870D01*
X555853Y249930D01*
X555978Y249970D01*
X556103Y249980D01*
G37*
G36*
G01X560827D02*
X560952Y249970D01*
X561077Y249930D01*
X561187Y249870D01*
X561287Y249790D01*
X561367Y249690D01*
X561427Y249580D01*
X561467Y249455D01*
X561477Y249330D01*
Y247205D01*
X561507Y247175D01*
X561532Y247140D01*
X561562Y247105D01*
X561582Y247070D01*
X561607Y247035D01*
X561647Y246955D01*
X561692Y246835D01*
X561702Y246795D01*
X561712Y246750D01*
X561717Y246710D01*
X561727Y246665D01*
Y246495D01*
X561717Y246450D01*
X561712Y246410D01*
X561702Y246365D01*
X561692Y246325D01*
X561647Y246205D01*
X561607Y246125D01*
X561582Y246090D01*
X561562Y246055D01*
X561532Y246020D01*
X561507Y245985D01*
X561477Y245955D01*
Y243530D01*
X561467Y243405D01*
X561427Y243280D01*
X561367Y243170D01*
X561287Y243070D01*
X561187Y242990D01*
X561077Y242930D01*
X560952Y242890D01*
X560827Y242880D01*
X560702Y242890D01*
X560577Y242930D01*
X560467Y242990D01*
X560367Y243070D01*
X560287Y243170D01*
X560227Y243280D01*
X560187Y243405D01*
X560177Y243530D01*
Y245960D01*
X560147Y245990D01*
X560047Y246130D01*
X560027Y246170D01*
X560012Y246205D01*
X559992Y246245D01*
X559977Y246285D01*
X559967Y246325D01*
X559952Y246370D01*
X559947Y246410D01*
X559937Y246450D01*
X559932Y246495D01*
Y246535D01*
X559927Y246580D01*
X559932Y246625D01*
Y246665D01*
X559937Y246710D01*
X559947Y246750D01*
X559952Y246790D01*
X559967Y246835D01*
X559977Y246875D01*
X559992Y246915D01*
X560012Y246955D01*
X560027Y246990D01*
X560047Y247030D01*
X560147Y247170D01*
X560177Y247200D01*
Y249330D01*
X560187Y249455D01*
X560227Y249580D01*
X560287Y249690D01*
X560367Y249790D01*
X560467Y249870D01*
X560577Y249930D01*
X560702Y249970D01*
X560827Y249980D01*
G37*
G36*
G01X565551D02*
X565676Y249970D01*
X565801Y249930D01*
X565911Y249870D01*
X566011Y249790D01*
X566091Y249690D01*
X566151Y249580D01*
X566191Y249455D01*
X566201Y249330D01*
Y247205D01*
X566231Y247175D01*
X566256Y247140D01*
X566286Y247105D01*
X566306Y247070D01*
X566331Y247035D01*
X566371Y246955D01*
X566416Y246835D01*
X566426Y246795D01*
X566436Y246750D01*
X566441Y246710D01*
X566451Y246665D01*
Y246495D01*
X566441Y246450D01*
X566436Y246410D01*
X566426Y246365D01*
X566416Y246325D01*
X566371Y246205D01*
X566331Y246125D01*
X566306Y246090D01*
X566286Y246055D01*
X566256Y246020D01*
X566231Y245985D01*
X566201Y245955D01*
Y243530D01*
X566191Y243405D01*
X566151Y243280D01*
X566091Y243170D01*
X566011Y243070D01*
X565911Y242990D01*
X565801Y242930D01*
X565676Y242890D01*
X565551Y242880D01*
X565426Y242890D01*
X565301Y242930D01*
X565191Y242990D01*
X565091Y243070D01*
X565011Y243170D01*
X564951Y243280D01*
X564911Y243405D01*
X564901Y243530D01*
Y245960D01*
X564871Y245990D01*
X564771Y246130D01*
X564751Y246170D01*
X564736Y246205D01*
X564716Y246245D01*
X564701Y246285D01*
X564691Y246325D01*
X564676Y246370D01*
X564671Y246410D01*
X564661Y246450D01*
X564656Y246495D01*
Y246535D01*
X564651Y246580D01*
X564656Y246625D01*
Y246665D01*
X564661Y246710D01*
X564671Y246750D01*
X564676Y246790D01*
X564691Y246835D01*
X564701Y246875D01*
X564716Y246915D01*
X564736Y246955D01*
X564751Y246990D01*
X564771Y247030D01*
X564871Y247170D01*
X564901Y247200D01*
Y249330D01*
X564911Y249455D01*
X564951Y249580D01*
X565011Y249690D01*
X565091Y249790D01*
X565191Y249870D01*
X565301Y249930D01*
X565426Y249970D01*
X565551Y249980D01*
G37*
G36*
G01X570276D02*
X570401Y249970D01*
X570526Y249930D01*
X570636Y249870D01*
X570736Y249790D01*
X570816Y249690D01*
X570876Y249580D01*
X570916Y249455D01*
X570926Y249330D01*
Y247205D01*
X570956Y247175D01*
X570981Y247140D01*
X571011Y247105D01*
X571031Y247070D01*
X571056Y247035D01*
X571096Y246955D01*
X571141Y246835D01*
X571151Y246795D01*
X571161Y246750D01*
X571166Y246710D01*
X571176Y246665D01*
Y246495D01*
X571166Y246450D01*
X571161Y246410D01*
X571151Y246365D01*
X571141Y246325D01*
X571096Y246205D01*
X571056Y246125D01*
X571031Y246090D01*
X571011Y246055D01*
X570981Y246020D01*
X570956Y245985D01*
X570926Y245955D01*
Y243530D01*
X570916Y243405D01*
X570876Y243280D01*
X570816Y243170D01*
X570736Y243070D01*
X570636Y242990D01*
X570526Y242930D01*
X570401Y242890D01*
X570276Y242880D01*
X570151Y242890D01*
X570026Y242930D01*
X569916Y242990D01*
X569816Y243070D01*
X569736Y243170D01*
X569676Y243280D01*
X569636Y243405D01*
X569626Y243530D01*
Y245960D01*
X569596Y245990D01*
X569496Y246130D01*
X569476Y246170D01*
X569461Y246205D01*
X569441Y246245D01*
X569426Y246285D01*
X569416Y246325D01*
X569401Y246370D01*
X569396Y246410D01*
X569386Y246450D01*
X569381Y246495D01*
Y246535D01*
X569376Y246580D01*
X569381Y246625D01*
Y246665D01*
X569386Y246710D01*
X569396Y246750D01*
X569401Y246790D01*
X569416Y246835D01*
X569426Y246875D01*
X569441Y246915D01*
X569461Y246955D01*
X569476Y246990D01*
X569496Y247030D01*
X569596Y247170D01*
X569626Y247200D01*
Y249330D01*
X569636Y249455D01*
X569676Y249580D01*
X569736Y249690D01*
X569816Y249790D01*
X569916Y249870D01*
X570026Y249930D01*
X570151Y249970D01*
X570276Y249980D01*
G37*
G36*
G01X575000D02*
X575125Y249970D01*
X575250Y249930D01*
X575360Y249870D01*
X575460Y249790D01*
X575540Y249690D01*
X575600Y249580D01*
X575640Y249455D01*
X575650Y249330D01*
Y247205D01*
X575680Y247175D01*
X575705Y247140D01*
X575735Y247105D01*
X575755Y247070D01*
X575780Y247035D01*
X575820Y246955D01*
X575865Y246835D01*
X575875Y246795D01*
X575885Y246750D01*
X575890Y246710D01*
X575900Y246665D01*
Y246495D01*
X575890Y246450D01*
X575885Y246410D01*
X575875Y246365D01*
X575865Y246325D01*
X575820Y246205D01*
X575780Y246125D01*
X575755Y246090D01*
X575735Y246055D01*
X575705Y246020D01*
X575680Y245985D01*
X575650Y245955D01*
Y243530D01*
X575640Y243405D01*
X575600Y243280D01*
X575540Y243170D01*
X575460Y243070D01*
X575360Y242990D01*
X575250Y242930D01*
X575125Y242890D01*
X575000Y242880D01*
X574875Y242890D01*
X574750Y242930D01*
X574640Y242990D01*
X574540Y243070D01*
X574460Y243170D01*
X574400Y243280D01*
X574360Y243405D01*
X574350Y243530D01*
Y245960D01*
X574320Y245990D01*
X574220Y246130D01*
X574200Y246170D01*
X574185Y246205D01*
X574165Y246245D01*
X574150Y246285D01*
X574140Y246325D01*
X574125Y246370D01*
X574120Y246410D01*
X574110Y246450D01*
X574105Y246495D01*
Y246535D01*
X574100Y246580D01*
X574105Y246625D01*
Y246665D01*
X574110Y246710D01*
X574120Y246750D01*
X574125Y246790D01*
X574140Y246835D01*
X574150Y246875D01*
X574165Y246915D01*
X574185Y246955D01*
X574200Y246990D01*
X574220Y247030D01*
X574320Y247170D01*
X574350Y247200D01*
Y249330D01*
X574360Y249455D01*
X574400Y249580D01*
X574460Y249690D01*
X574540Y249790D01*
X574640Y249870D01*
X574750Y249930D01*
X574875Y249970D01*
X575000Y249980D01*
G37*
G36*
G01X579725D02*
X579850Y249970D01*
X579975Y249930D01*
X580085Y249870D01*
X580185Y249790D01*
X580265Y249690D01*
X580325Y249580D01*
X580365Y249455D01*
X580375Y249330D01*
Y247205D01*
X580405Y247175D01*
X580430Y247140D01*
X580460Y247105D01*
X580480Y247070D01*
X580505Y247035D01*
X580545Y246955D01*
X580590Y246835D01*
X580600Y246795D01*
X580610Y246750D01*
X580615Y246710D01*
X580625Y246665D01*
Y246495D01*
X580615Y246450D01*
X580610Y246410D01*
X580600Y246365D01*
X580590Y246325D01*
X580545Y246205D01*
X580505Y246125D01*
X580480Y246090D01*
X580460Y246055D01*
X580430Y246020D01*
X580405Y245985D01*
X580375Y245955D01*
Y243530D01*
X580365Y243405D01*
X580325Y243280D01*
X580265Y243170D01*
X580185Y243070D01*
X580085Y242990D01*
X579975Y242930D01*
X579850Y242890D01*
X579725Y242880D01*
X579600Y242890D01*
X579475Y242930D01*
X579365Y242990D01*
X579265Y243070D01*
X579185Y243170D01*
X579125Y243280D01*
X579085Y243405D01*
X579075Y243530D01*
Y245960D01*
X579045Y245990D01*
X578945Y246130D01*
X578925Y246170D01*
X578910Y246205D01*
X578890Y246245D01*
X578875Y246285D01*
X578865Y246325D01*
X578850Y246370D01*
X578845Y246410D01*
X578835Y246450D01*
X578830Y246495D01*
Y246535D01*
X578825Y246580D01*
X578830Y246625D01*
Y246665D01*
X578835Y246710D01*
X578845Y246750D01*
X578850Y246790D01*
X578865Y246835D01*
X578875Y246875D01*
X578890Y246915D01*
X578910Y246955D01*
X578925Y246990D01*
X578945Y247030D01*
X579045Y247170D01*
X579075Y247200D01*
Y249330D01*
X579085Y249455D01*
X579125Y249580D01*
X579185Y249690D01*
X579265Y249790D01*
X579365Y249870D01*
X579475Y249930D01*
X579600Y249970D01*
X579725Y249980D01*
G37*
G36*
G01X584449D02*
X584574Y249970D01*
X584699Y249930D01*
X584809Y249870D01*
X584909Y249790D01*
X584989Y249690D01*
X585049Y249580D01*
X585089Y249455D01*
X585099Y249330D01*
Y247205D01*
X585129Y247175D01*
X585154Y247140D01*
X585184Y247105D01*
X585204Y247070D01*
X585229Y247035D01*
X585269Y246955D01*
X585314Y246835D01*
X585324Y246795D01*
X585334Y246750D01*
X585339Y246710D01*
X585349Y246665D01*
Y246495D01*
X585339Y246450D01*
X585334Y246410D01*
X585324Y246365D01*
X585314Y246325D01*
X585269Y246205D01*
X585229Y246125D01*
X585204Y246090D01*
X585184Y246055D01*
X585154Y246020D01*
X585129Y245985D01*
X585099Y245955D01*
Y243530D01*
X585089Y243405D01*
X585049Y243280D01*
X584989Y243170D01*
X584909Y243070D01*
X584809Y242990D01*
X584699Y242930D01*
X584574Y242890D01*
X584449Y242880D01*
X584324Y242890D01*
X584199Y242930D01*
X584089Y242990D01*
X583989Y243070D01*
X583909Y243170D01*
X583849Y243280D01*
X583809Y243405D01*
X583799Y243530D01*
Y245960D01*
X583769Y245990D01*
X583669Y246130D01*
X583649Y246170D01*
X583634Y246205D01*
X583614Y246245D01*
X583599Y246285D01*
X583589Y246325D01*
X583574Y246370D01*
X583569Y246410D01*
X583559Y246450D01*
X583554Y246495D01*
Y246535D01*
X583549Y246580D01*
X583554Y246625D01*
Y246665D01*
X583559Y246710D01*
X583569Y246750D01*
X583574Y246790D01*
X583589Y246835D01*
X583599Y246875D01*
X583614Y246915D01*
X583634Y246955D01*
X583649Y246990D01*
X583669Y247030D01*
X583769Y247170D01*
X583799Y247200D01*
Y249330D01*
X583809Y249455D01*
X583849Y249580D01*
X583909Y249690D01*
X583989Y249790D01*
X584089Y249870D01*
X584199Y249930D01*
X584324Y249970D01*
X584449Y249980D01*
G37*
G36*
G01X589173D02*
X589298Y249970D01*
X589423Y249930D01*
X589533Y249870D01*
X589633Y249790D01*
X589713Y249690D01*
X589773Y249580D01*
X589813Y249455D01*
X589823Y249330D01*
Y247205D01*
X589853Y247175D01*
X589878Y247140D01*
X589908Y247105D01*
X589928Y247070D01*
X589953Y247035D01*
X589993Y246955D01*
X590038Y246835D01*
X590048Y246795D01*
X590058Y246750D01*
X590063Y246710D01*
X590073Y246665D01*
Y246495D01*
X590063Y246450D01*
X590058Y246410D01*
X590048Y246365D01*
X590038Y246325D01*
X589993Y246205D01*
X589953Y246125D01*
X589928Y246090D01*
X589908Y246055D01*
X589878Y246020D01*
X589853Y245985D01*
X589823Y245955D01*
Y243530D01*
X589813Y243405D01*
X589773Y243280D01*
X589713Y243170D01*
X589633Y243070D01*
X589533Y242990D01*
X589423Y242930D01*
X589298Y242890D01*
X589173Y242880D01*
X589048Y242890D01*
X588923Y242930D01*
X588813Y242990D01*
X588713Y243070D01*
X588633Y243170D01*
X588573Y243280D01*
X588533Y243405D01*
X588523Y243530D01*
Y245960D01*
X588493Y245990D01*
X588393Y246130D01*
X588373Y246170D01*
X588358Y246205D01*
X588338Y246245D01*
X588323Y246285D01*
X588313Y246325D01*
X588298Y246370D01*
X588293Y246410D01*
X588283Y246450D01*
X588278Y246495D01*
Y246535D01*
X588273Y246580D01*
X588278Y246625D01*
Y246665D01*
X588283Y246710D01*
X588293Y246750D01*
X588298Y246790D01*
X588313Y246835D01*
X588323Y246875D01*
X588338Y246915D01*
X588358Y246955D01*
X588373Y246990D01*
X588393Y247030D01*
X588493Y247170D01*
X588523Y247200D01*
Y249330D01*
X588533Y249455D01*
X588573Y249580D01*
X588633Y249690D01*
X588713Y249790D01*
X588813Y249870D01*
X588923Y249930D01*
X589048Y249970D01*
X589173Y249980D01*
G37*
G36*
G01X593898D02*
X594023Y249970D01*
X594148Y249930D01*
X594258Y249870D01*
X594358Y249790D01*
X594438Y249690D01*
X594498Y249580D01*
X594538Y249455D01*
X594548Y249330D01*
Y247205D01*
X594578Y247175D01*
X594603Y247140D01*
X594633Y247105D01*
X594653Y247070D01*
X594678Y247035D01*
X594718Y246955D01*
X594763Y246835D01*
X594773Y246795D01*
X594783Y246750D01*
X594788Y246710D01*
X594798Y246665D01*
Y246495D01*
X594788Y246450D01*
X594783Y246410D01*
X594773Y246365D01*
X594763Y246325D01*
X594718Y246205D01*
X594678Y246125D01*
X594653Y246090D01*
X594633Y246055D01*
X594603Y246020D01*
X594578Y245985D01*
X594548Y245955D01*
Y243530D01*
X594538Y243405D01*
X594498Y243280D01*
X594438Y243170D01*
X594358Y243070D01*
X594258Y242990D01*
X594148Y242930D01*
X594023Y242890D01*
X593898Y242880D01*
X593773Y242890D01*
X593648Y242930D01*
X593538Y242990D01*
X593438Y243070D01*
X593358Y243170D01*
X593298Y243280D01*
X593258Y243405D01*
X593248Y243530D01*
Y245960D01*
X593218Y245990D01*
X593118Y246130D01*
X593098Y246170D01*
X593083Y246205D01*
X593063Y246245D01*
X593048Y246285D01*
X593038Y246325D01*
X593023Y246370D01*
X593018Y246410D01*
X593008Y246450D01*
X593003Y246495D01*
Y246535D01*
X592998Y246580D01*
X593003Y246625D01*
Y246665D01*
X593008Y246710D01*
X593018Y246750D01*
X593023Y246790D01*
X593038Y246835D01*
X593048Y246875D01*
X593063Y246915D01*
X593083Y246955D01*
X593098Y246990D01*
X593118Y247030D01*
X593218Y247170D01*
X593248Y247200D01*
Y249330D01*
X593258Y249455D01*
X593298Y249580D01*
X593358Y249690D01*
X593438Y249790D01*
X593538Y249870D01*
X593648Y249930D01*
X593773Y249970D01*
X593898Y249980D01*
G37*
G36*
G01X598622D02*
X598747Y249970D01*
X598872Y249930D01*
X598982Y249870D01*
X599082Y249790D01*
X599162Y249690D01*
X599222Y249580D01*
X599262Y249455D01*
X599272Y249330D01*
Y247205D01*
X599302Y247175D01*
X599327Y247140D01*
X599357Y247105D01*
X599377Y247070D01*
X599402Y247035D01*
X599442Y246955D01*
X599487Y246835D01*
X599497Y246795D01*
X599507Y246750D01*
X599512Y246710D01*
X599522Y246665D01*
Y246495D01*
X599512Y246450D01*
X599507Y246410D01*
X599497Y246365D01*
X599487Y246325D01*
X599442Y246205D01*
X599402Y246125D01*
X599377Y246090D01*
X599357Y246055D01*
X599327Y246020D01*
X599302Y245985D01*
X599272Y245955D01*
Y243530D01*
X599262Y243405D01*
X599222Y243280D01*
X599162Y243170D01*
X599082Y243070D01*
X598982Y242990D01*
X598872Y242930D01*
X598747Y242890D01*
X598622Y242880D01*
X598497Y242890D01*
X598372Y242930D01*
X598262Y242990D01*
X598162Y243070D01*
X598082Y243170D01*
X598022Y243280D01*
X597982Y243405D01*
X597972Y243530D01*
Y245960D01*
X597942Y245990D01*
X597842Y246130D01*
X597822Y246170D01*
X597807Y246205D01*
X597787Y246245D01*
X597772Y246285D01*
X597762Y246325D01*
X597747Y246370D01*
X597742Y246410D01*
X597732Y246450D01*
X597727Y246495D01*
Y246535D01*
X597722Y246580D01*
X597727Y246625D01*
Y246665D01*
X597732Y246710D01*
X597742Y246750D01*
X597747Y246790D01*
X597762Y246835D01*
X597772Y246875D01*
X597787Y246915D01*
X597807Y246955D01*
X597822Y246990D01*
X597842Y247030D01*
X597942Y247170D01*
X597972Y247200D01*
Y249330D01*
X597982Y249455D01*
X598022Y249580D01*
X598082Y249690D01*
X598162Y249790D01*
X598262Y249870D01*
X598372Y249930D01*
X598497Y249970D01*
X598622Y249980D01*
G37*
G36*
G01X603347D02*
X603472Y249970D01*
X603597Y249930D01*
X603707Y249870D01*
X603807Y249790D01*
X603887Y249690D01*
X603947Y249580D01*
X603987Y249455D01*
X603997Y249330D01*
Y247205D01*
X604027Y247175D01*
X604052Y247140D01*
X604082Y247105D01*
X604102Y247070D01*
X604127Y247035D01*
X604167Y246955D01*
X604212Y246835D01*
X604222Y246795D01*
X604232Y246750D01*
X604237Y246710D01*
X604247Y246665D01*
Y246495D01*
X604237Y246450D01*
X604232Y246410D01*
X604222Y246365D01*
X604212Y246325D01*
X604167Y246205D01*
X604127Y246125D01*
X604102Y246090D01*
X604082Y246055D01*
X604052Y246020D01*
X604027Y245985D01*
X603997Y245955D01*
Y243530D01*
X603987Y243405D01*
X603947Y243280D01*
X603887Y243170D01*
X603807Y243070D01*
X603707Y242990D01*
X603597Y242930D01*
X603472Y242890D01*
X603347Y242880D01*
X603222Y242890D01*
X603097Y242930D01*
X602987Y242990D01*
X602887Y243070D01*
X602807Y243170D01*
X602747Y243280D01*
X602707Y243405D01*
X602697Y243530D01*
Y245960D01*
X602667Y245990D01*
X602567Y246130D01*
X602547Y246170D01*
X602532Y246205D01*
X602512Y246245D01*
X602497Y246285D01*
X602487Y246325D01*
X602472Y246370D01*
X602467Y246410D01*
X602457Y246450D01*
X602452Y246495D01*
Y246535D01*
X602447Y246580D01*
X602452Y246625D01*
Y246665D01*
X602457Y246710D01*
X602467Y246750D01*
X602472Y246790D01*
X602487Y246835D01*
X602497Y246875D01*
X602512Y246915D01*
X602532Y246955D01*
X602547Y246990D01*
X602567Y247030D01*
X602667Y247170D01*
X602697Y247200D01*
Y249330D01*
X602707Y249455D01*
X602747Y249580D01*
X602807Y249690D01*
X602887Y249790D01*
X602987Y249870D01*
X603097Y249930D01*
X603222Y249970D01*
X603347Y249980D01*
G37*
G36*
G01X608071D02*
X608196Y249970D01*
X608321Y249930D01*
X608431Y249870D01*
X608531Y249790D01*
X608611Y249690D01*
X608671Y249580D01*
X608711Y249455D01*
X608721Y249330D01*
Y247205D01*
X608751Y247175D01*
X608776Y247140D01*
X608806Y247105D01*
X608826Y247070D01*
X608851Y247035D01*
X608891Y246955D01*
X608936Y246835D01*
X608946Y246795D01*
X608956Y246750D01*
X608961Y246710D01*
X608971Y246665D01*
Y246495D01*
X608961Y246450D01*
X608956Y246410D01*
X608946Y246365D01*
X608936Y246325D01*
X608891Y246205D01*
X608851Y246125D01*
X608826Y246090D01*
X608806Y246055D01*
X608776Y246020D01*
X608751Y245985D01*
X608721Y245955D01*
Y243530D01*
X608711Y243405D01*
X608671Y243280D01*
X608611Y243170D01*
X608531Y243070D01*
X608431Y242990D01*
X608321Y242930D01*
X608196Y242890D01*
X608071Y242880D01*
X607946Y242890D01*
X607821Y242930D01*
X607711Y242990D01*
X607611Y243070D01*
X607531Y243170D01*
X607471Y243280D01*
X607431Y243405D01*
X607421Y243530D01*
Y245960D01*
X607391Y245990D01*
X607291Y246130D01*
X607271Y246170D01*
X607256Y246205D01*
X607236Y246245D01*
X607221Y246285D01*
X607211Y246325D01*
X607196Y246370D01*
X607191Y246410D01*
X607181Y246450D01*
X607176Y246495D01*
Y246535D01*
X607171Y246580D01*
X607176Y246625D01*
Y246665D01*
X607181Y246710D01*
X607191Y246750D01*
X607196Y246790D01*
X607211Y246835D01*
X607221Y246875D01*
X607236Y246915D01*
X607256Y246955D01*
X607271Y246990D01*
X607291Y247030D01*
X607391Y247170D01*
X607421Y247200D01*
Y249330D01*
X607431Y249455D01*
X607471Y249580D01*
X607531Y249690D01*
X607611Y249790D01*
X607711Y249870D01*
X607821Y249930D01*
X607946Y249970D01*
X608071Y249980D01*
G37*
G36*
G01X612796D02*
X612921Y249970D01*
X613046Y249930D01*
X613156Y249870D01*
X613256Y249790D01*
X613336Y249690D01*
X613396Y249580D01*
X613436Y249455D01*
X613446Y249330D01*
Y247205D01*
X613476Y247175D01*
X613501Y247140D01*
X613531Y247105D01*
X613551Y247070D01*
X613576Y247035D01*
X613616Y246955D01*
X613661Y246835D01*
X613671Y246795D01*
X613681Y246750D01*
X613686Y246710D01*
X613696Y246665D01*
Y246495D01*
X613686Y246450D01*
X613681Y246410D01*
X613671Y246365D01*
X613661Y246325D01*
X613616Y246205D01*
X613576Y246125D01*
X613551Y246090D01*
X613531Y246055D01*
X613501Y246020D01*
X613476Y245985D01*
X613446Y245955D01*
Y243530D01*
X613436Y243405D01*
X613396Y243280D01*
X613336Y243170D01*
X613256Y243070D01*
X613156Y242990D01*
X613046Y242930D01*
X612921Y242890D01*
X612796Y242880D01*
X612671Y242890D01*
X612546Y242930D01*
X612436Y242990D01*
X612336Y243070D01*
X612256Y243170D01*
X612196Y243280D01*
X612156Y243405D01*
X612146Y243530D01*
Y245960D01*
X612116Y245990D01*
X612016Y246130D01*
X611996Y246170D01*
X611981Y246205D01*
X611961Y246245D01*
X611946Y246285D01*
X611936Y246325D01*
X611921Y246370D01*
X611916Y246410D01*
X611906Y246450D01*
X611901Y246495D01*
Y246535D01*
X611896Y246580D01*
X611901Y246625D01*
Y246665D01*
X611906Y246710D01*
X611916Y246750D01*
X611921Y246790D01*
X611936Y246835D01*
X611946Y246875D01*
X611961Y246915D01*
X611981Y246955D01*
X611996Y246990D01*
X612016Y247030D01*
X612116Y247170D01*
X612146Y247200D01*
Y249330D01*
X612156Y249455D01*
X612196Y249580D01*
X612256Y249690D01*
X612336Y249790D01*
X612436Y249870D01*
X612546Y249930D01*
X612671Y249970D01*
X612796Y249980D01*
G37*
G36*
G01X617520D02*
X617645Y249970D01*
X617770Y249930D01*
X617880Y249870D01*
X617980Y249790D01*
X618060Y249690D01*
X618120Y249580D01*
X618160Y249455D01*
X618170Y249330D01*
Y247205D01*
X618200Y247175D01*
X618225Y247140D01*
X618255Y247105D01*
X618275Y247070D01*
X618300Y247035D01*
X618340Y246955D01*
X618385Y246835D01*
X618395Y246795D01*
X618405Y246750D01*
X618410Y246710D01*
X618420Y246665D01*
Y246495D01*
X618410Y246450D01*
X618405Y246410D01*
X618395Y246365D01*
X618385Y246325D01*
X618340Y246205D01*
X618300Y246125D01*
X618275Y246090D01*
X618255Y246055D01*
X618225Y246020D01*
X618200Y245985D01*
X618170Y245955D01*
Y243530D01*
X618160Y243405D01*
X618120Y243280D01*
X618060Y243170D01*
X617980Y243070D01*
X617880Y242990D01*
X617770Y242930D01*
X617645Y242890D01*
X617520Y242880D01*
X617395Y242890D01*
X617270Y242930D01*
X617160Y242990D01*
X617060Y243070D01*
X616980Y243170D01*
X616920Y243280D01*
X616880Y243405D01*
X616870Y243530D01*
Y245960D01*
X616840Y245990D01*
X616740Y246130D01*
X616720Y246170D01*
X616705Y246205D01*
X616685Y246245D01*
X616670Y246285D01*
X616660Y246325D01*
X616645Y246370D01*
X616640Y246410D01*
X616630Y246450D01*
X616625Y246495D01*
Y246535D01*
X616620Y246580D01*
X616625Y246625D01*
Y246665D01*
X616630Y246710D01*
X616640Y246750D01*
X616645Y246790D01*
X616660Y246835D01*
X616670Y246875D01*
X616685Y246915D01*
X616705Y246955D01*
X616720Y246990D01*
X616740Y247030D01*
X616840Y247170D01*
X616870Y247200D01*
Y249330D01*
X616880Y249455D01*
X616920Y249580D01*
X616980Y249690D01*
X617060Y249790D01*
X617160Y249870D01*
X617270Y249930D01*
X617395Y249970D01*
X617520Y249980D01*
G37*
G36*
G01X622244D02*
X622369Y249970D01*
X622494Y249930D01*
X622604Y249870D01*
X622704Y249790D01*
X622784Y249690D01*
X622844Y249580D01*
X622884Y249455D01*
X622894Y249330D01*
Y247205D01*
X622924Y247175D01*
X622949Y247140D01*
X622979Y247105D01*
X622999Y247070D01*
X623024Y247035D01*
X623064Y246955D01*
X623109Y246835D01*
X623119Y246795D01*
X623129Y246750D01*
X623134Y246710D01*
X623144Y246665D01*
Y246495D01*
X623134Y246450D01*
X623129Y246410D01*
X623119Y246365D01*
X623109Y246325D01*
X623064Y246205D01*
X623024Y246125D01*
X622999Y246090D01*
X622979Y246055D01*
X622949Y246020D01*
X622924Y245985D01*
X622894Y245955D01*
Y243530D01*
X622884Y243405D01*
X622844Y243280D01*
X622784Y243170D01*
X622704Y243070D01*
X622604Y242990D01*
X622494Y242930D01*
X622369Y242890D01*
X622244Y242880D01*
X622119Y242890D01*
X621994Y242930D01*
X621884Y242990D01*
X621784Y243070D01*
X621704Y243170D01*
X621644Y243280D01*
X621604Y243405D01*
X621594Y243530D01*
Y245960D01*
X621564Y245990D01*
X621464Y246130D01*
X621444Y246170D01*
X621429Y246205D01*
X621409Y246245D01*
X621394Y246285D01*
X621384Y246325D01*
X621369Y246370D01*
X621364Y246410D01*
X621354Y246450D01*
X621349Y246495D01*
Y246535D01*
X621344Y246580D01*
X621349Y246625D01*
Y246665D01*
X621354Y246710D01*
X621364Y246750D01*
X621369Y246790D01*
X621384Y246835D01*
X621394Y246875D01*
X621409Y246915D01*
X621429Y246955D01*
X621444Y246990D01*
X621464Y247030D01*
X621564Y247170D01*
X621594Y247200D01*
Y249330D01*
X621604Y249455D01*
X621644Y249580D01*
X621704Y249690D01*
X621784Y249790D01*
X621884Y249870D01*
X621994Y249930D01*
X622119Y249970D01*
X622244Y249980D01*
G37*
G36*
G01X626969D02*
X627094Y249970D01*
X627219Y249930D01*
X627329Y249870D01*
X627429Y249790D01*
X627509Y249690D01*
X627569Y249580D01*
X627609Y249455D01*
X627619Y249330D01*
Y247205D01*
X627649Y247175D01*
X627674Y247140D01*
X627704Y247105D01*
X627724Y247070D01*
X627749Y247035D01*
X627789Y246955D01*
X627834Y246835D01*
X627844Y246795D01*
X627854Y246750D01*
X627859Y246710D01*
X627869Y246665D01*
Y246495D01*
X627859Y246450D01*
X627854Y246410D01*
X627844Y246365D01*
X627834Y246325D01*
X627789Y246205D01*
X627749Y246125D01*
X627724Y246090D01*
X627704Y246055D01*
X627674Y246020D01*
X627649Y245985D01*
X627619Y245955D01*
Y243530D01*
X627609Y243405D01*
X627569Y243280D01*
X627509Y243170D01*
X627429Y243070D01*
X627329Y242990D01*
X627219Y242930D01*
X627094Y242890D01*
X626969Y242880D01*
X626844Y242890D01*
X626719Y242930D01*
X626609Y242990D01*
X626509Y243070D01*
X626429Y243170D01*
X626369Y243280D01*
X626329Y243405D01*
X626319Y243530D01*
Y245960D01*
X626289Y245990D01*
X626189Y246130D01*
X626169Y246170D01*
X626154Y246205D01*
X626134Y246245D01*
X626119Y246285D01*
X626109Y246325D01*
X626094Y246370D01*
X626089Y246410D01*
X626079Y246450D01*
X626074Y246495D01*
Y246535D01*
X626069Y246580D01*
X626074Y246625D01*
Y246665D01*
X626079Y246710D01*
X626089Y246750D01*
X626094Y246790D01*
X626109Y246835D01*
X626119Y246875D01*
X626134Y246915D01*
X626154Y246955D01*
X626169Y246990D01*
X626189Y247030D01*
X626289Y247170D01*
X626319Y247200D01*
Y249330D01*
X626329Y249455D01*
X626369Y249580D01*
X626429Y249690D01*
X626509Y249790D01*
X626609Y249870D01*
X626719Y249930D01*
X626844Y249970D01*
X626969Y249980D01*
G37*
G36*
G01X631693D02*
X631818Y249970D01*
X631943Y249930D01*
X632053Y249870D01*
X632153Y249790D01*
X632233Y249690D01*
X632293Y249580D01*
X632333Y249455D01*
X632343Y249330D01*
Y247205D01*
X632373Y247175D01*
X632398Y247140D01*
X632428Y247105D01*
X632448Y247070D01*
X632473Y247035D01*
X632513Y246955D01*
X632558Y246835D01*
X632568Y246795D01*
X632578Y246750D01*
X632583Y246710D01*
X632593Y246665D01*
Y246495D01*
X632583Y246450D01*
X632578Y246410D01*
X632568Y246365D01*
X632558Y246325D01*
X632513Y246205D01*
X632473Y246125D01*
X632448Y246090D01*
X632428Y246055D01*
X632398Y246020D01*
X632373Y245985D01*
X632343Y245955D01*
Y243530D01*
X632333Y243405D01*
X632293Y243280D01*
X632233Y243170D01*
X632153Y243070D01*
X632053Y242990D01*
X631943Y242930D01*
X631818Y242890D01*
X631693Y242880D01*
X631568Y242890D01*
X631443Y242930D01*
X631333Y242990D01*
X631233Y243070D01*
X631153Y243170D01*
X631093Y243280D01*
X631053Y243405D01*
X631043Y243530D01*
Y245960D01*
X631013Y245990D01*
X630913Y246130D01*
X630893Y246170D01*
X630878Y246205D01*
X630858Y246245D01*
X630843Y246285D01*
X630833Y246325D01*
X630818Y246370D01*
X630813Y246410D01*
X630803Y246450D01*
X630798Y246495D01*
Y246535D01*
X630793Y246580D01*
X630798Y246625D01*
Y246665D01*
X630803Y246710D01*
X630813Y246750D01*
X630818Y246790D01*
X630833Y246835D01*
X630843Y246875D01*
X630858Y246915D01*
X630878Y246955D01*
X630893Y246990D01*
X630913Y247030D01*
X631013Y247170D01*
X631043Y247200D01*
Y249330D01*
X631053Y249455D01*
X631093Y249580D01*
X631153Y249690D01*
X631233Y249790D01*
X631333Y249870D01*
X631443Y249930D01*
X631568Y249970D01*
X631693Y249980D01*
G37*
G36*
G01X636418D02*
X636543Y249970D01*
X636668Y249930D01*
X636778Y249870D01*
X636878Y249790D01*
X636958Y249690D01*
X637018Y249580D01*
X637058Y249455D01*
X637068Y249330D01*
Y247205D01*
X637098Y247175D01*
X637123Y247140D01*
X637153Y247105D01*
X637173Y247070D01*
X637198Y247035D01*
X637238Y246955D01*
X637283Y246835D01*
X637293Y246795D01*
X637303Y246750D01*
X637308Y246710D01*
X637318Y246665D01*
Y246495D01*
X637308Y246450D01*
X637303Y246410D01*
X637293Y246365D01*
X637283Y246325D01*
X637238Y246205D01*
X637198Y246125D01*
X637173Y246090D01*
X637153Y246055D01*
X637123Y246020D01*
X637098Y245985D01*
X637068Y245955D01*
Y243530D01*
X637058Y243405D01*
X637018Y243280D01*
X636958Y243170D01*
X636878Y243070D01*
X636778Y242990D01*
X636668Y242930D01*
X636543Y242890D01*
X636418Y242880D01*
X636293Y242890D01*
X636168Y242930D01*
X636058Y242990D01*
X635958Y243070D01*
X635878Y243170D01*
X635818Y243280D01*
X635778Y243405D01*
X635768Y243530D01*
Y245960D01*
X635738Y245990D01*
X635638Y246130D01*
X635618Y246170D01*
X635603Y246205D01*
X635583Y246245D01*
X635568Y246285D01*
X635558Y246325D01*
X635543Y246370D01*
X635538Y246410D01*
X635528Y246450D01*
X635523Y246495D01*
Y246535D01*
X635518Y246580D01*
X635523Y246625D01*
Y246665D01*
X635528Y246710D01*
X635538Y246750D01*
X635543Y246790D01*
X635558Y246835D01*
X635568Y246875D01*
X635583Y246915D01*
X635603Y246955D01*
X635618Y246990D01*
X635638Y247030D01*
X635738Y247170D01*
X635768Y247200D01*
Y249330D01*
X635778Y249455D01*
X635818Y249580D01*
X635878Y249690D01*
X635958Y249790D01*
X636058Y249870D01*
X636168Y249930D01*
X636293Y249970D01*
X636418Y249980D01*
G37*
G36*
G01X641142D02*
X641267Y249970D01*
X641392Y249930D01*
X641502Y249870D01*
X641602Y249790D01*
X641682Y249690D01*
X641742Y249580D01*
X641782Y249455D01*
X641792Y249330D01*
Y247205D01*
X641822Y247175D01*
X641847Y247140D01*
X641877Y247105D01*
X641897Y247070D01*
X641922Y247035D01*
X641962Y246955D01*
X642007Y246835D01*
X642017Y246795D01*
X642027Y246750D01*
X642032Y246710D01*
X642042Y246665D01*
Y246495D01*
X642032Y246450D01*
X642027Y246410D01*
X642017Y246365D01*
X642007Y246325D01*
X641962Y246205D01*
X641922Y246125D01*
X641897Y246090D01*
X641877Y246055D01*
X641847Y246020D01*
X641822Y245985D01*
X641792Y245955D01*
Y243530D01*
X641782Y243405D01*
X641742Y243280D01*
X641682Y243170D01*
X641602Y243070D01*
X641502Y242990D01*
X641392Y242930D01*
X641267Y242890D01*
X641142Y242880D01*
X641017Y242890D01*
X640892Y242930D01*
X640782Y242990D01*
X640682Y243070D01*
X640602Y243170D01*
X640542Y243280D01*
X640502Y243405D01*
X640492Y243530D01*
Y245960D01*
X640462Y245990D01*
X640362Y246130D01*
X640342Y246170D01*
X640327Y246205D01*
X640307Y246245D01*
X640292Y246285D01*
X640282Y246325D01*
X640267Y246370D01*
X640262Y246410D01*
X640252Y246450D01*
X640247Y246495D01*
Y246535D01*
X640242Y246580D01*
X640247Y246625D01*
Y246665D01*
X640252Y246710D01*
X640262Y246750D01*
X640267Y246790D01*
X640282Y246835D01*
X640292Y246875D01*
X640307Y246915D01*
X640327Y246955D01*
X640342Y246990D01*
X640362Y247030D01*
X640462Y247170D01*
X640492Y247200D01*
Y249330D01*
X640502Y249455D01*
X640542Y249580D01*
X640602Y249690D01*
X640682Y249790D01*
X640782Y249870D01*
X640892Y249930D01*
X641017Y249970D01*
X641142Y249980D01*
G37*
G36*
G01X645866D02*
X645991Y249970D01*
X646116Y249930D01*
X646226Y249870D01*
X646326Y249790D01*
X646406Y249690D01*
X646466Y249580D01*
X646506Y249455D01*
X646516Y249330D01*
Y247205D01*
X646546Y247175D01*
X646571Y247140D01*
X646601Y247105D01*
X646621Y247070D01*
X646646Y247035D01*
X646686Y246955D01*
X646731Y246835D01*
X646741Y246795D01*
X646751Y246750D01*
X646756Y246710D01*
X646766Y246665D01*
Y246495D01*
X646756Y246450D01*
X646751Y246410D01*
X646741Y246365D01*
X646731Y246325D01*
X646686Y246205D01*
X646646Y246125D01*
X646621Y246090D01*
X646601Y246055D01*
X646571Y246020D01*
X646546Y245985D01*
X646516Y245955D01*
Y243530D01*
X646506Y243405D01*
X646466Y243280D01*
X646406Y243170D01*
X646326Y243070D01*
X646226Y242990D01*
X646116Y242930D01*
X645991Y242890D01*
X645866Y242880D01*
X645741Y242890D01*
X645616Y242930D01*
X645506Y242990D01*
X645406Y243070D01*
X645326Y243170D01*
X645266Y243280D01*
X645226Y243405D01*
X645216Y243530D01*
Y245960D01*
X645186Y245990D01*
X645086Y246130D01*
X645066Y246170D01*
X645051Y246205D01*
X645031Y246245D01*
X645016Y246285D01*
X645006Y246325D01*
X644991Y246370D01*
X644986Y246410D01*
X644976Y246450D01*
X644971Y246495D01*
Y246535D01*
X644966Y246580D01*
X644971Y246625D01*
Y246665D01*
X644976Y246710D01*
X644986Y246750D01*
X644991Y246790D01*
X645006Y246835D01*
X645016Y246875D01*
X645031Y246915D01*
X645051Y246955D01*
X645066Y246990D01*
X645086Y247030D01*
X645186Y247170D01*
X645216Y247200D01*
Y249330D01*
X645226Y249455D01*
X645266Y249580D01*
X645326Y249690D01*
X645406Y249790D01*
X645506Y249870D01*
X645616Y249930D01*
X645741Y249970D01*
X645866Y249980D01*
G37*
G36*
G01X650591D02*
X650716Y249970D01*
X650841Y249930D01*
X650951Y249870D01*
X651051Y249790D01*
X651131Y249690D01*
X651191Y249580D01*
X651231Y249455D01*
X651241Y249330D01*
Y247205D01*
X651271Y247175D01*
X651296Y247140D01*
X651326Y247105D01*
X651346Y247070D01*
X651371Y247035D01*
X651411Y246955D01*
X651456Y246835D01*
X651466Y246795D01*
X651476Y246750D01*
X651481Y246710D01*
X651491Y246665D01*
Y246495D01*
X651481Y246450D01*
X651476Y246410D01*
X651466Y246365D01*
X651456Y246325D01*
X651411Y246205D01*
X651371Y246125D01*
X651346Y246090D01*
X651326Y246055D01*
X651296Y246020D01*
X651271Y245985D01*
X651241Y245955D01*
Y243530D01*
X651231Y243405D01*
X651191Y243280D01*
X651131Y243170D01*
X651051Y243070D01*
X650951Y242990D01*
X650841Y242930D01*
X650716Y242890D01*
X650591Y242880D01*
X650466Y242890D01*
X650341Y242930D01*
X650231Y242990D01*
X650131Y243070D01*
X650051Y243170D01*
X649991Y243280D01*
X649951Y243405D01*
X649941Y243530D01*
Y245960D01*
X649911Y245990D01*
X649811Y246130D01*
X649791Y246170D01*
X649776Y246205D01*
X649756Y246245D01*
X649741Y246285D01*
X649731Y246325D01*
X649716Y246370D01*
X649711Y246410D01*
X649701Y246450D01*
X649696Y246495D01*
Y246535D01*
X649691Y246580D01*
X649696Y246625D01*
Y246665D01*
X649701Y246710D01*
X649711Y246750D01*
X649716Y246790D01*
X649731Y246835D01*
X649741Y246875D01*
X649756Y246915D01*
X649776Y246955D01*
X649791Y246990D01*
X649811Y247030D01*
X649911Y247170D01*
X649941Y247200D01*
Y249330D01*
X649951Y249455D01*
X649991Y249580D01*
X650051Y249690D01*
X650131Y249790D01*
X650231Y249870D01*
X650341Y249930D01*
X650466Y249970D01*
X650591Y249980D01*
G37*
G36*
G01X664764D02*
X664889Y249970D01*
X665014Y249930D01*
X665124Y249870D01*
X665224Y249790D01*
X665304Y249690D01*
X665364Y249580D01*
X665404Y249455D01*
X665414Y249330D01*
Y247205D01*
X665444Y247175D01*
X665469Y247140D01*
X665499Y247105D01*
X665519Y247070D01*
X665544Y247035D01*
X665584Y246955D01*
X665629Y246835D01*
X665639Y246795D01*
X665649Y246750D01*
X665654Y246710D01*
X665664Y246665D01*
Y246495D01*
X665654Y246450D01*
X665649Y246410D01*
X665639Y246365D01*
X665629Y246325D01*
X665584Y246205D01*
X665544Y246125D01*
X665519Y246090D01*
X665499Y246055D01*
X665469Y246020D01*
X665444Y245985D01*
X665414Y245955D01*
Y243530D01*
X665404Y243405D01*
X665364Y243280D01*
X665304Y243170D01*
X665224Y243070D01*
X665124Y242990D01*
X665014Y242930D01*
X664889Y242890D01*
X664764Y242880D01*
X664639Y242890D01*
X664514Y242930D01*
X664404Y242990D01*
X664304Y243070D01*
X664224Y243170D01*
X664164Y243280D01*
X664124Y243405D01*
X664114Y243530D01*
Y245960D01*
X664084Y245990D01*
X663984Y246130D01*
X663964Y246170D01*
X663949Y246205D01*
X663929Y246245D01*
X663914Y246285D01*
X663904Y246325D01*
X663889Y246370D01*
X663884Y246410D01*
X663874Y246450D01*
X663869Y246495D01*
Y246535D01*
X663864Y246580D01*
X663869Y246625D01*
Y246665D01*
X663874Y246710D01*
X663884Y246750D01*
X663889Y246790D01*
X663904Y246835D01*
X663914Y246875D01*
X663929Y246915D01*
X663949Y246955D01*
X663964Y246990D01*
X663984Y247030D01*
X664084Y247170D01*
X664114Y247200D01*
Y249330D01*
X664124Y249455D01*
X664164Y249580D01*
X664224Y249690D01*
X664304Y249790D01*
X664404Y249870D01*
X664514Y249930D01*
X664639Y249970D01*
X664764Y249980D01*
G37*
G36*
G01X669488D02*
X669613Y249970D01*
X669738Y249930D01*
X669848Y249870D01*
X669948Y249790D01*
X670028Y249690D01*
X670088Y249580D01*
X670128Y249455D01*
X670138Y249330D01*
Y247205D01*
X670168Y247175D01*
X670193Y247140D01*
X670223Y247105D01*
X670243Y247070D01*
X670268Y247035D01*
X670308Y246955D01*
X670353Y246835D01*
X670363Y246795D01*
X670373Y246750D01*
X670378Y246710D01*
X670388Y246665D01*
Y246495D01*
X670378Y246450D01*
X670373Y246410D01*
X670363Y246365D01*
X670353Y246325D01*
X670308Y246205D01*
X670268Y246125D01*
X670243Y246090D01*
X670223Y246055D01*
X670193Y246020D01*
X670168Y245985D01*
X670138Y245955D01*
Y243530D01*
X670128Y243405D01*
X670088Y243280D01*
X670028Y243170D01*
X669948Y243070D01*
X669848Y242990D01*
X669738Y242930D01*
X669613Y242890D01*
X669488Y242880D01*
X669363Y242890D01*
X669238Y242930D01*
X669128Y242990D01*
X669028Y243070D01*
X668948Y243170D01*
X668888Y243280D01*
X668848Y243405D01*
X668838Y243530D01*
Y245960D01*
X668808Y245990D01*
X668708Y246130D01*
X668688Y246170D01*
X668673Y246205D01*
X668653Y246245D01*
X668638Y246285D01*
X668628Y246325D01*
X668613Y246370D01*
X668608Y246410D01*
X668598Y246450D01*
X668593Y246495D01*
Y246535D01*
X668588Y246580D01*
X668593Y246625D01*
Y246665D01*
X668598Y246710D01*
X668608Y246750D01*
X668613Y246790D01*
X668628Y246835D01*
X668638Y246875D01*
X668653Y246915D01*
X668673Y246955D01*
X668688Y246990D01*
X668708Y247030D01*
X668808Y247170D01*
X668838Y247200D01*
Y249330D01*
X668848Y249455D01*
X668888Y249580D01*
X668948Y249690D01*
X669028Y249790D01*
X669128Y249870D01*
X669238Y249930D01*
X669363Y249970D01*
X669488Y249980D01*
G37*
G36*
G01X674213D02*
X674338Y249970D01*
X674463Y249930D01*
X674573Y249870D01*
X674673Y249790D01*
X674753Y249690D01*
X674813Y249580D01*
X674853Y249455D01*
X674863Y249330D01*
Y247205D01*
X674893Y247175D01*
X674918Y247140D01*
X674948Y247105D01*
X674968Y247070D01*
X674993Y247035D01*
X675033Y246955D01*
X675078Y246835D01*
X675088Y246795D01*
X675098Y246750D01*
X675103Y246710D01*
X675113Y246665D01*
Y246495D01*
X675103Y246450D01*
X675098Y246410D01*
X675088Y246365D01*
X675078Y246325D01*
X675033Y246205D01*
X674993Y246125D01*
X674968Y246090D01*
X674948Y246055D01*
X674918Y246020D01*
X674893Y245985D01*
X674863Y245955D01*
Y243530D01*
X674853Y243405D01*
X674813Y243280D01*
X674753Y243170D01*
X674673Y243070D01*
X674573Y242990D01*
X674463Y242930D01*
X674338Y242890D01*
X674213Y242880D01*
X674088Y242890D01*
X673963Y242930D01*
X673853Y242990D01*
X673753Y243070D01*
X673673Y243170D01*
X673613Y243280D01*
X673573Y243405D01*
X673563Y243530D01*
Y245960D01*
X673533Y245990D01*
X673433Y246130D01*
X673413Y246170D01*
X673398Y246205D01*
X673378Y246245D01*
X673363Y246285D01*
X673353Y246325D01*
X673338Y246370D01*
X673333Y246410D01*
X673323Y246450D01*
X673318Y246495D01*
Y246535D01*
X673313Y246580D01*
X673318Y246625D01*
Y246665D01*
X673323Y246710D01*
X673333Y246750D01*
X673338Y246790D01*
X673353Y246835D01*
X673363Y246875D01*
X673378Y246915D01*
X673398Y246955D01*
X673413Y246990D01*
X673433Y247030D01*
X673533Y247170D01*
X673563Y247200D01*
Y249330D01*
X673573Y249455D01*
X673613Y249580D01*
X673673Y249690D01*
X673753Y249790D01*
X673853Y249870D01*
X673963Y249930D01*
X674088Y249970D01*
X674213Y249980D01*
G37*
G36*
G01X678937D02*
X679062Y249970D01*
X679187Y249930D01*
X679297Y249870D01*
X679397Y249790D01*
X679477Y249690D01*
X679537Y249580D01*
X679577Y249455D01*
X679587Y249330D01*
Y247205D01*
X679617Y247175D01*
X679642Y247140D01*
X679672Y247105D01*
X679692Y247070D01*
X679717Y247035D01*
X679757Y246955D01*
X679802Y246835D01*
X679812Y246795D01*
X679822Y246750D01*
X679827Y246710D01*
X679837Y246665D01*
Y246495D01*
X679827Y246450D01*
X679822Y246410D01*
X679812Y246365D01*
X679802Y246325D01*
X679757Y246205D01*
X679717Y246125D01*
X679692Y246090D01*
X679672Y246055D01*
X679642Y246020D01*
X679617Y245985D01*
X679587Y245955D01*
Y243530D01*
X679577Y243405D01*
X679537Y243280D01*
X679477Y243170D01*
X679397Y243070D01*
X679297Y242990D01*
X679187Y242930D01*
X679062Y242890D01*
X678937Y242880D01*
X678812Y242890D01*
X678687Y242930D01*
X678577Y242990D01*
X678477Y243070D01*
X678397Y243170D01*
X678337Y243280D01*
X678297Y243405D01*
X678287Y243530D01*
Y245960D01*
X678257Y245990D01*
X678157Y246130D01*
X678137Y246170D01*
X678122Y246205D01*
X678102Y246245D01*
X678087Y246285D01*
X678077Y246325D01*
X678062Y246370D01*
X678057Y246410D01*
X678047Y246450D01*
X678042Y246495D01*
Y246535D01*
X678037Y246580D01*
X678042Y246625D01*
Y246665D01*
X678047Y246710D01*
X678057Y246750D01*
X678062Y246790D01*
X678077Y246835D01*
X678087Y246875D01*
X678102Y246915D01*
X678122Y246955D01*
X678137Y246990D01*
X678157Y247030D01*
X678257Y247170D01*
X678287Y247200D01*
Y249330D01*
X678297Y249455D01*
X678337Y249580D01*
X678397Y249690D01*
X678477Y249790D01*
X678577Y249870D01*
X678687Y249930D01*
X678812Y249970D01*
X678937Y249980D01*
G37*
G36*
G01X683662D02*
X683787Y249970D01*
X683912Y249930D01*
X684022Y249870D01*
X684122Y249790D01*
X684202Y249690D01*
X684262Y249580D01*
X684302Y249455D01*
X684312Y249330D01*
Y247205D01*
X684342Y247175D01*
X684367Y247140D01*
X684397Y247105D01*
X684417Y247070D01*
X684442Y247035D01*
X684482Y246955D01*
X684527Y246835D01*
X684537Y246795D01*
X684547Y246750D01*
X684552Y246710D01*
X684562Y246665D01*
Y246495D01*
X684552Y246450D01*
X684547Y246410D01*
X684537Y246365D01*
X684527Y246325D01*
X684482Y246205D01*
X684442Y246125D01*
X684417Y246090D01*
X684397Y246055D01*
X684367Y246020D01*
X684342Y245985D01*
X684312Y245955D01*
Y243530D01*
X684302Y243405D01*
X684262Y243280D01*
X684202Y243170D01*
X684122Y243070D01*
X684022Y242990D01*
X683912Y242930D01*
X683787Y242890D01*
X683662Y242880D01*
X683537Y242890D01*
X683412Y242930D01*
X683302Y242990D01*
X683202Y243070D01*
X683122Y243170D01*
X683062Y243280D01*
X683022Y243405D01*
X683012Y243530D01*
Y245960D01*
X682982Y245990D01*
X682882Y246130D01*
X682862Y246170D01*
X682847Y246205D01*
X682827Y246245D01*
X682812Y246285D01*
X682802Y246325D01*
X682787Y246370D01*
X682782Y246410D01*
X682772Y246450D01*
X682767Y246495D01*
Y246535D01*
X682762Y246580D01*
X682767Y246625D01*
Y246665D01*
X682772Y246710D01*
X682782Y246750D01*
X682787Y246790D01*
X682802Y246835D01*
X682812Y246875D01*
X682827Y246915D01*
X682847Y246955D01*
X682862Y246990D01*
X682882Y247030D01*
X682982Y247170D01*
X683012Y247200D01*
Y249330D01*
X683022Y249455D01*
X683062Y249580D01*
X683122Y249690D01*
X683202Y249790D01*
X683302Y249870D01*
X683412Y249930D01*
X683537Y249970D01*
X683662Y249980D01*
G37*
G36*
G01X688386D02*
X688511Y249970D01*
X688636Y249930D01*
X688746Y249870D01*
X688846Y249790D01*
X688926Y249690D01*
X688986Y249580D01*
X689026Y249455D01*
X689036Y249330D01*
Y247205D01*
X689066Y247175D01*
X689091Y247140D01*
X689121Y247105D01*
X689141Y247070D01*
X689166Y247035D01*
X689206Y246955D01*
X689251Y246835D01*
X689261Y246795D01*
X689271Y246750D01*
X689276Y246710D01*
X689286Y246665D01*
Y246495D01*
X689276Y246450D01*
X689271Y246410D01*
X689261Y246365D01*
X689251Y246325D01*
X689206Y246205D01*
X689166Y246125D01*
X689141Y246090D01*
X689121Y246055D01*
X689091Y246020D01*
X689066Y245985D01*
X689036Y245955D01*
Y243530D01*
X689026Y243405D01*
X688986Y243280D01*
X688926Y243170D01*
X688846Y243070D01*
X688746Y242990D01*
X688636Y242930D01*
X688511Y242890D01*
X688386Y242880D01*
X688261Y242890D01*
X688136Y242930D01*
X688026Y242990D01*
X687926Y243070D01*
X687846Y243170D01*
X687786Y243280D01*
X687746Y243405D01*
X687736Y243530D01*
Y245960D01*
X687706Y245990D01*
X687606Y246130D01*
X687586Y246170D01*
X687571Y246205D01*
X687551Y246245D01*
X687536Y246285D01*
X687526Y246325D01*
X687511Y246370D01*
X687506Y246410D01*
X687496Y246450D01*
X687491Y246495D01*
Y246535D01*
X687486Y246580D01*
X687491Y246625D01*
Y246665D01*
X687496Y246710D01*
X687506Y246750D01*
X687511Y246790D01*
X687526Y246835D01*
X687536Y246875D01*
X687551Y246915D01*
X687571Y246955D01*
X687586Y246990D01*
X687606Y247030D01*
X687706Y247170D01*
X687736Y247200D01*
Y249330D01*
X687746Y249455D01*
X687786Y249580D01*
X687846Y249690D01*
X687926Y249790D01*
X688026Y249870D01*
X688136Y249930D01*
X688261Y249970D01*
X688386Y249980D01*
G37*
G36*
G01X693110D02*
X693235Y249970D01*
X693360Y249930D01*
X693470Y249870D01*
X693570Y249790D01*
X693650Y249690D01*
X693710Y249580D01*
X693750Y249455D01*
X693760Y249330D01*
Y247205D01*
X693790Y247175D01*
X693815Y247140D01*
X693845Y247105D01*
X693865Y247070D01*
X693890Y247035D01*
X693930Y246955D01*
X693975Y246835D01*
X693985Y246795D01*
X693995Y246750D01*
X694000Y246710D01*
X694010Y246665D01*
Y246495D01*
X694000Y246450D01*
X693995Y246410D01*
X693985Y246365D01*
X693975Y246325D01*
X693930Y246205D01*
X693890Y246125D01*
X693865Y246090D01*
X693845Y246055D01*
X693815Y246020D01*
X693790Y245985D01*
X693760Y245955D01*
Y243530D01*
X693750Y243405D01*
X693710Y243280D01*
X693650Y243170D01*
X693570Y243070D01*
X693470Y242990D01*
X693360Y242930D01*
X693235Y242890D01*
X693110Y242880D01*
X692985Y242890D01*
X692860Y242930D01*
X692750Y242990D01*
X692650Y243070D01*
X692570Y243170D01*
X692510Y243280D01*
X692470Y243405D01*
X692460Y243530D01*
Y245960D01*
X692430Y245990D01*
X692330Y246130D01*
X692310Y246170D01*
X692295Y246205D01*
X692275Y246245D01*
X692260Y246285D01*
X692250Y246325D01*
X692235Y246370D01*
X692230Y246410D01*
X692220Y246450D01*
X692215Y246495D01*
Y246535D01*
X692210Y246580D01*
X692215Y246625D01*
Y246665D01*
X692220Y246710D01*
X692230Y246750D01*
X692235Y246790D01*
X692250Y246835D01*
X692260Y246875D01*
X692275Y246915D01*
X692295Y246955D01*
X692310Y246990D01*
X692330Y247030D01*
X692430Y247170D01*
X692460Y247200D01*
Y249330D01*
X692470Y249455D01*
X692510Y249580D01*
X692570Y249690D01*
X692650Y249790D01*
X692750Y249870D01*
X692860Y249930D01*
X692985Y249970D01*
X693110Y249980D01*
G37*
G36*
G01X697835D02*
X697960Y249970D01*
X698085Y249930D01*
X698195Y249870D01*
X698295Y249790D01*
X698375Y249690D01*
X698435Y249580D01*
X698475Y249455D01*
X698485Y249330D01*
Y247205D01*
X698515Y247175D01*
X698540Y247140D01*
X698570Y247105D01*
X698590Y247070D01*
X698615Y247035D01*
X698655Y246955D01*
X698700Y246835D01*
X698710Y246795D01*
X698720Y246750D01*
X698725Y246710D01*
X698735Y246665D01*
Y246495D01*
X698725Y246450D01*
X698720Y246410D01*
X698710Y246365D01*
X698700Y246325D01*
X698655Y246205D01*
X698615Y246125D01*
X698590Y246090D01*
X698570Y246055D01*
X698540Y246020D01*
X698515Y245985D01*
X698485Y245955D01*
Y243530D01*
X698475Y243405D01*
X698435Y243280D01*
X698375Y243170D01*
X698295Y243070D01*
X698195Y242990D01*
X698085Y242930D01*
X697960Y242890D01*
X697835Y242880D01*
X697710Y242890D01*
X697585Y242930D01*
X697475Y242990D01*
X697375Y243070D01*
X697295Y243170D01*
X697235Y243280D01*
X697195Y243405D01*
X697185Y243530D01*
Y245960D01*
X697155Y245990D01*
X697055Y246130D01*
X697035Y246170D01*
X697020Y246205D01*
X697000Y246245D01*
X696985Y246285D01*
X696975Y246325D01*
X696960Y246370D01*
X696955Y246410D01*
X696945Y246450D01*
X696940Y246495D01*
Y246535D01*
X696935Y246580D01*
X696940Y246625D01*
Y246665D01*
X696945Y246710D01*
X696955Y246750D01*
X696960Y246790D01*
X696975Y246835D01*
X696985Y246875D01*
X697000Y246915D01*
X697020Y246955D01*
X697035Y246990D01*
X697055Y247030D01*
X697155Y247170D01*
X697185Y247200D01*
Y249330D01*
X697195Y249455D01*
X697235Y249580D01*
X697295Y249690D01*
X697375Y249790D01*
X697475Y249870D01*
X697585Y249930D01*
X697710Y249970D01*
X697835Y249980D01*
G37*
G36*
G01X702559D02*
X702684Y249970D01*
X702809Y249930D01*
X702919Y249870D01*
X703019Y249790D01*
X703099Y249690D01*
X703159Y249580D01*
X703199Y249455D01*
X703209Y249330D01*
Y247205D01*
X703239Y247175D01*
X703264Y247140D01*
X703294Y247105D01*
X703314Y247070D01*
X703339Y247035D01*
X703379Y246955D01*
X703424Y246835D01*
X703434Y246795D01*
X703444Y246750D01*
X703449Y246710D01*
X703459Y246665D01*
Y246495D01*
X703449Y246450D01*
X703444Y246410D01*
X703434Y246365D01*
X703424Y246325D01*
X703379Y246205D01*
X703339Y246125D01*
X703314Y246090D01*
X703294Y246055D01*
X703264Y246020D01*
X703239Y245985D01*
X703209Y245955D01*
Y243530D01*
X703199Y243405D01*
X703159Y243280D01*
X703099Y243170D01*
X703019Y243070D01*
X702919Y242990D01*
X702809Y242930D01*
X702684Y242890D01*
X702559Y242880D01*
X702434Y242890D01*
X702309Y242930D01*
X702199Y242990D01*
X702099Y243070D01*
X702019Y243170D01*
X701959Y243280D01*
X701919Y243405D01*
X701909Y243530D01*
Y245960D01*
X701879Y245990D01*
X701779Y246130D01*
X701759Y246170D01*
X701744Y246205D01*
X701724Y246245D01*
X701709Y246285D01*
X701699Y246325D01*
X701684Y246370D01*
X701679Y246410D01*
X701669Y246450D01*
X701664Y246495D01*
Y246535D01*
X701659Y246580D01*
X701664Y246625D01*
Y246665D01*
X701669Y246710D01*
X701679Y246750D01*
X701684Y246790D01*
X701699Y246835D01*
X701709Y246875D01*
X701724Y246915D01*
X701744Y246955D01*
X701759Y246990D01*
X701779Y247030D01*
X701879Y247170D01*
X701909Y247200D01*
Y249330D01*
X701919Y249455D01*
X701959Y249580D01*
X702019Y249690D01*
X702099Y249790D01*
X702199Y249870D01*
X702309Y249930D01*
X702434Y249970D01*
X702559Y249980D01*
G37*
G36*
G01X707284D02*
X707409Y249970D01*
X707534Y249930D01*
X707644Y249870D01*
X707744Y249790D01*
X707824Y249690D01*
X707884Y249580D01*
X707924Y249455D01*
X707934Y249330D01*
Y247205D01*
X707964Y247175D01*
X707989Y247140D01*
X708019Y247105D01*
X708039Y247070D01*
X708064Y247035D01*
X708104Y246955D01*
X708149Y246835D01*
X708159Y246795D01*
X708169Y246750D01*
X708174Y246710D01*
X708184Y246665D01*
Y246495D01*
X708174Y246450D01*
X708169Y246410D01*
X708159Y246365D01*
X708149Y246325D01*
X708104Y246205D01*
X708064Y246125D01*
X708039Y246090D01*
X708019Y246055D01*
X707989Y246020D01*
X707964Y245985D01*
X707934Y245955D01*
Y243530D01*
X707924Y243405D01*
X707884Y243280D01*
X707824Y243170D01*
X707744Y243070D01*
X707644Y242990D01*
X707534Y242930D01*
X707409Y242890D01*
X707284Y242880D01*
X707159Y242890D01*
X707034Y242930D01*
X706924Y242990D01*
X706824Y243070D01*
X706744Y243170D01*
X706684Y243280D01*
X706644Y243405D01*
X706634Y243530D01*
Y245960D01*
X706604Y245990D01*
X706504Y246130D01*
X706484Y246170D01*
X706469Y246205D01*
X706449Y246245D01*
X706434Y246285D01*
X706424Y246325D01*
X706409Y246370D01*
X706404Y246410D01*
X706394Y246450D01*
X706389Y246495D01*
Y246535D01*
X706384Y246580D01*
X706389Y246625D01*
Y246665D01*
X706394Y246710D01*
X706404Y246750D01*
X706409Y246790D01*
X706424Y246835D01*
X706434Y246875D01*
X706449Y246915D01*
X706469Y246955D01*
X706484Y246990D01*
X706504Y247030D01*
X706604Y247170D01*
X706634Y247200D01*
Y249330D01*
X706644Y249455D01*
X706684Y249580D01*
X706744Y249690D01*
X706824Y249790D01*
X706924Y249870D01*
X707034Y249930D01*
X707159Y249970D01*
X707284Y249980D01*
G37*
G36*
G01X712008D02*
X712133Y249970D01*
X712258Y249930D01*
X712368Y249870D01*
X712468Y249790D01*
X712548Y249690D01*
X712608Y249580D01*
X712648Y249455D01*
X712658Y249330D01*
Y247205D01*
X712688Y247175D01*
X712713Y247140D01*
X712743Y247105D01*
X712763Y247070D01*
X712788Y247035D01*
X712828Y246955D01*
X712873Y246835D01*
X712883Y246795D01*
X712893Y246750D01*
X712898Y246710D01*
X712908Y246665D01*
Y246495D01*
X712898Y246450D01*
X712893Y246410D01*
X712883Y246365D01*
X712873Y246325D01*
X712828Y246205D01*
X712788Y246125D01*
X712763Y246090D01*
X712743Y246055D01*
X712713Y246020D01*
X712688Y245985D01*
X712658Y245955D01*
Y243530D01*
X712648Y243405D01*
X712608Y243280D01*
X712548Y243170D01*
X712468Y243070D01*
X712368Y242990D01*
X712258Y242930D01*
X712133Y242890D01*
X712008Y242880D01*
X711883Y242890D01*
X711758Y242930D01*
X711648Y242990D01*
X711548Y243070D01*
X711468Y243170D01*
X711408Y243280D01*
X711368Y243405D01*
X711358Y243530D01*
Y245960D01*
X711328Y245990D01*
X711228Y246130D01*
X711208Y246170D01*
X711193Y246205D01*
X711173Y246245D01*
X711158Y246285D01*
X711148Y246325D01*
X711133Y246370D01*
X711128Y246410D01*
X711118Y246450D01*
X711113Y246495D01*
Y246535D01*
X711108Y246580D01*
X711113Y246625D01*
Y246665D01*
X711118Y246710D01*
X711128Y246750D01*
X711133Y246790D01*
X711148Y246835D01*
X711158Y246875D01*
X711173Y246915D01*
X711193Y246955D01*
X711208Y246990D01*
X711228Y247030D01*
X711328Y247170D01*
X711358Y247200D01*
Y249330D01*
X711368Y249455D01*
X711408Y249580D01*
X711468Y249690D01*
X711548Y249790D01*
X711648Y249870D01*
X711758Y249930D01*
X711883Y249970D01*
X712008Y249980D01*
G37*
G36*
G01X716733D02*
X716858Y249970D01*
X716983Y249930D01*
X717093Y249870D01*
X717193Y249790D01*
X717273Y249690D01*
X717333Y249580D01*
X717373Y249455D01*
X717383Y249330D01*
Y247205D01*
X717413Y247175D01*
X717438Y247140D01*
X717468Y247105D01*
X717488Y247070D01*
X717513Y247035D01*
X717553Y246955D01*
X717598Y246835D01*
X717608Y246795D01*
X717618Y246750D01*
X717623Y246710D01*
X717633Y246665D01*
Y246495D01*
X717623Y246450D01*
X717618Y246410D01*
X717608Y246365D01*
X717598Y246325D01*
X717553Y246205D01*
X717513Y246125D01*
X717488Y246090D01*
X717468Y246055D01*
X717438Y246020D01*
X717413Y245985D01*
X717383Y245955D01*
Y243530D01*
X717373Y243405D01*
X717333Y243280D01*
X717273Y243170D01*
X717193Y243070D01*
X717093Y242990D01*
X716983Y242930D01*
X716858Y242890D01*
X716733Y242880D01*
X716608Y242890D01*
X716483Y242930D01*
X716373Y242990D01*
X716273Y243070D01*
X716193Y243170D01*
X716133Y243280D01*
X716093Y243405D01*
X716083Y243530D01*
Y245960D01*
X716053Y245990D01*
X715953Y246130D01*
X715933Y246170D01*
X715918Y246205D01*
X715898Y246245D01*
X715883Y246285D01*
X715873Y246325D01*
X715858Y246370D01*
X715853Y246410D01*
X715843Y246450D01*
X715838Y246495D01*
Y246535D01*
X715833Y246580D01*
X715838Y246625D01*
Y246665D01*
X715843Y246710D01*
X715853Y246750D01*
X715858Y246790D01*
X715873Y246835D01*
X715883Y246875D01*
X715898Y246915D01*
X715918Y246955D01*
X715933Y246990D01*
X715953Y247030D01*
X716053Y247170D01*
X716083Y247200D01*
Y249330D01*
X716093Y249455D01*
X716133Y249580D01*
X716193Y249690D01*
X716273Y249790D01*
X716373Y249870D01*
X716483Y249930D01*
X716608Y249970D01*
X716733Y249980D01*
G37*
G36*
G01X721457D02*
X721582Y249970D01*
X721707Y249930D01*
X721817Y249870D01*
X721917Y249790D01*
X721997Y249690D01*
X722057Y249580D01*
X722097Y249455D01*
X722107Y249330D01*
Y247205D01*
X722137Y247175D01*
X722162Y247140D01*
X722192Y247105D01*
X722212Y247070D01*
X722237Y247035D01*
X722277Y246955D01*
X722322Y246835D01*
X722332Y246795D01*
X722342Y246750D01*
X722347Y246710D01*
X722357Y246665D01*
Y246495D01*
X722347Y246450D01*
X722342Y246410D01*
X722332Y246365D01*
X722322Y246325D01*
X722277Y246205D01*
X722237Y246125D01*
X722212Y246090D01*
X722192Y246055D01*
X722162Y246020D01*
X722137Y245985D01*
X722107Y245955D01*
Y243530D01*
X722097Y243405D01*
X722057Y243280D01*
X721997Y243170D01*
X721917Y243070D01*
X721817Y242990D01*
X721707Y242930D01*
X721582Y242890D01*
X721457Y242880D01*
X721332Y242890D01*
X721207Y242930D01*
X721097Y242990D01*
X720997Y243070D01*
X720917Y243170D01*
X720857Y243280D01*
X720817Y243405D01*
X720807Y243530D01*
Y245960D01*
X720777Y245990D01*
X720677Y246130D01*
X720657Y246170D01*
X720642Y246205D01*
X720622Y246245D01*
X720607Y246285D01*
X720597Y246325D01*
X720582Y246370D01*
X720577Y246410D01*
X720567Y246450D01*
X720562Y246495D01*
Y246535D01*
X720557Y246580D01*
X720562Y246625D01*
Y246665D01*
X720567Y246710D01*
X720577Y246750D01*
X720582Y246790D01*
X720597Y246835D01*
X720607Y246875D01*
X720622Y246915D01*
X720642Y246955D01*
X720657Y246990D01*
X720677Y247030D01*
X720777Y247170D01*
X720807Y247200D01*
Y249330D01*
X720817Y249455D01*
X720857Y249580D01*
X720917Y249690D01*
X720997Y249790D01*
X721097Y249870D01*
X721207Y249930D01*
X721332Y249970D01*
X721457Y249980D01*
G37*
G36*
G01X726181D02*
X726306Y249970D01*
X726431Y249930D01*
X726541Y249870D01*
X726641Y249790D01*
X726721Y249690D01*
X726781Y249580D01*
X726821Y249455D01*
X726831Y249330D01*
Y247205D01*
X726861Y247175D01*
X726886Y247140D01*
X726916Y247105D01*
X726936Y247070D01*
X726961Y247035D01*
X727001Y246955D01*
X727046Y246835D01*
X727056Y246795D01*
X727066Y246750D01*
X727071Y246710D01*
X727081Y246665D01*
Y246495D01*
X727071Y246450D01*
X727066Y246410D01*
X727056Y246365D01*
X727046Y246325D01*
X727001Y246205D01*
X726961Y246125D01*
X726936Y246090D01*
X726916Y246055D01*
X726886Y246020D01*
X726861Y245985D01*
X726831Y245955D01*
Y243530D01*
X726821Y243405D01*
X726781Y243280D01*
X726721Y243170D01*
X726641Y243070D01*
X726541Y242990D01*
X726431Y242930D01*
X726306Y242890D01*
X726181Y242880D01*
X726056Y242890D01*
X725931Y242930D01*
X725821Y242990D01*
X725721Y243070D01*
X725641Y243170D01*
X725581Y243280D01*
X725541Y243405D01*
X725531Y243530D01*
Y245960D01*
X725501Y245990D01*
X725401Y246130D01*
X725381Y246170D01*
X725366Y246205D01*
X725346Y246245D01*
X725331Y246285D01*
X725321Y246325D01*
X725306Y246370D01*
X725301Y246410D01*
X725291Y246450D01*
X725286Y246495D01*
Y246535D01*
X725281Y246580D01*
X725286Y246625D01*
Y246665D01*
X725291Y246710D01*
X725301Y246750D01*
X725306Y246790D01*
X725321Y246835D01*
X725331Y246875D01*
X725346Y246915D01*
X725366Y246955D01*
X725381Y246990D01*
X725401Y247030D01*
X725501Y247170D01*
X725531Y247200D01*
Y249330D01*
X725541Y249455D01*
X725581Y249580D01*
X725641Y249690D01*
X725721Y249790D01*
X725821Y249870D01*
X725931Y249930D01*
X726056Y249970D01*
X726181Y249980D01*
G37*
G36*
G01X730906D02*
X731031Y249970D01*
X731156Y249930D01*
X731266Y249870D01*
X731366Y249790D01*
X731446Y249690D01*
X731506Y249580D01*
X731546Y249455D01*
X731556Y249330D01*
Y247205D01*
X731586Y247175D01*
X731611Y247140D01*
X731641Y247105D01*
X731661Y247070D01*
X731686Y247035D01*
X731726Y246955D01*
X731771Y246835D01*
X731781Y246795D01*
X731791Y246750D01*
X731796Y246710D01*
X731806Y246665D01*
Y246495D01*
X731796Y246450D01*
X731791Y246410D01*
X731781Y246365D01*
X731771Y246325D01*
X731726Y246205D01*
X731686Y246125D01*
X731661Y246090D01*
X731641Y246055D01*
X731611Y246020D01*
X731586Y245985D01*
X731556Y245955D01*
Y243530D01*
X731546Y243405D01*
X731506Y243280D01*
X731446Y243170D01*
X731366Y243070D01*
X731266Y242990D01*
X731156Y242930D01*
X731031Y242890D01*
X730906Y242880D01*
X730781Y242890D01*
X730656Y242930D01*
X730546Y242990D01*
X730446Y243070D01*
X730366Y243170D01*
X730306Y243280D01*
X730266Y243405D01*
X730256Y243530D01*
Y245960D01*
X730226Y245990D01*
X730126Y246130D01*
X730106Y246170D01*
X730091Y246205D01*
X730071Y246245D01*
X730056Y246285D01*
X730046Y246325D01*
X730031Y246370D01*
X730026Y246410D01*
X730016Y246450D01*
X730011Y246495D01*
Y246535D01*
X730006Y246580D01*
X730011Y246625D01*
Y246665D01*
X730016Y246710D01*
X730026Y246750D01*
X730031Y246790D01*
X730046Y246835D01*
X730056Y246875D01*
X730071Y246915D01*
X730091Y246955D01*
X730106Y246990D01*
X730126Y247030D01*
X730226Y247170D01*
X730256Y247200D01*
Y249330D01*
X730266Y249455D01*
X730306Y249580D01*
X730366Y249690D01*
X730446Y249790D01*
X730546Y249870D01*
X730656Y249930D01*
X730781Y249970D01*
X730906Y249980D01*
G37*
G36*
G01X735630D02*
X735755Y249970D01*
X735880Y249930D01*
X735990Y249870D01*
X736090Y249790D01*
X736170Y249690D01*
X736230Y249580D01*
X736270Y249455D01*
X736280Y249330D01*
Y247205D01*
X736310Y247175D01*
X736335Y247140D01*
X736365Y247105D01*
X736385Y247070D01*
X736410Y247035D01*
X736450Y246955D01*
X736495Y246835D01*
X736505Y246795D01*
X736515Y246750D01*
X736520Y246710D01*
X736530Y246665D01*
Y246495D01*
X736520Y246450D01*
X736515Y246410D01*
X736505Y246365D01*
X736495Y246325D01*
X736450Y246205D01*
X736410Y246125D01*
X736385Y246090D01*
X736365Y246055D01*
X736335Y246020D01*
X736310Y245985D01*
X736280Y245955D01*
Y243530D01*
X736270Y243405D01*
X736230Y243280D01*
X736170Y243170D01*
X736090Y243070D01*
X735990Y242990D01*
X735880Y242930D01*
X735755Y242890D01*
X735630Y242880D01*
X735505Y242890D01*
X735380Y242930D01*
X735270Y242990D01*
X735170Y243070D01*
X735090Y243170D01*
X735030Y243280D01*
X734990Y243405D01*
X734980Y243530D01*
Y245960D01*
X734950Y245990D01*
X734850Y246130D01*
X734830Y246170D01*
X734815Y246205D01*
X734795Y246245D01*
X734780Y246285D01*
X734770Y246325D01*
X734755Y246370D01*
X734750Y246410D01*
X734740Y246450D01*
X734735Y246495D01*
Y246535D01*
X734730Y246580D01*
X734735Y246625D01*
Y246665D01*
X734740Y246710D01*
X734750Y246750D01*
X734755Y246790D01*
X734770Y246835D01*
X734780Y246875D01*
X734795Y246915D01*
X734815Y246955D01*
X734830Y246990D01*
X734850Y247030D01*
X734950Y247170D01*
X734980Y247200D01*
Y249330D01*
X734990Y249455D01*
X735030Y249580D01*
X735090Y249690D01*
X735170Y249790D01*
X735270Y249870D01*
X735380Y249930D01*
X735505Y249970D01*
X735630Y249980D01*
G37*
G36*
G01X740355D02*
X740480Y249970D01*
X740605Y249930D01*
X740715Y249870D01*
X740815Y249790D01*
X740895Y249690D01*
X740955Y249580D01*
X740995Y249455D01*
X741005Y249330D01*
Y247205D01*
X741035Y247175D01*
X741060Y247140D01*
X741090Y247105D01*
X741110Y247070D01*
X741135Y247035D01*
X741175Y246955D01*
X741220Y246835D01*
X741230Y246795D01*
X741240Y246750D01*
X741245Y246710D01*
X741255Y246665D01*
Y246495D01*
X741245Y246450D01*
X741240Y246410D01*
X741230Y246365D01*
X741220Y246325D01*
X741175Y246205D01*
X741135Y246125D01*
X741110Y246090D01*
X741090Y246055D01*
X741060Y246020D01*
X741035Y245985D01*
X741005Y245955D01*
Y243530D01*
X740995Y243405D01*
X740955Y243280D01*
X740895Y243170D01*
X740815Y243070D01*
X740715Y242990D01*
X740605Y242930D01*
X740480Y242890D01*
X740355Y242880D01*
X740230Y242890D01*
X740105Y242930D01*
X739995Y242990D01*
X739895Y243070D01*
X739815Y243170D01*
X739755Y243280D01*
X739715Y243405D01*
X739705Y243530D01*
Y245960D01*
X739675Y245990D01*
X739575Y246130D01*
X739555Y246170D01*
X739540Y246205D01*
X739520Y246245D01*
X739505Y246285D01*
X739495Y246325D01*
X739480Y246370D01*
X739475Y246410D01*
X739465Y246450D01*
X739460Y246495D01*
Y246535D01*
X739455Y246580D01*
X739460Y246625D01*
Y246665D01*
X739465Y246710D01*
X739475Y246750D01*
X739480Y246790D01*
X739495Y246835D01*
X739505Y246875D01*
X739520Y246915D01*
X739540Y246955D01*
X739555Y246990D01*
X739575Y247030D01*
X739675Y247170D01*
X739705Y247200D01*
Y249330D01*
X739715Y249455D01*
X739755Y249580D01*
X739815Y249690D01*
X739895Y249790D01*
X739995Y249870D01*
X740105Y249930D01*
X740230Y249970D01*
X740355Y249980D01*
G37*
G36*
G01X745079D02*
X745204Y249970D01*
X745329Y249930D01*
X745439Y249870D01*
X745539Y249790D01*
X745619Y249690D01*
X745679Y249580D01*
X745719Y249455D01*
X745729Y249330D01*
Y247205D01*
X745759Y247175D01*
X745784Y247140D01*
X745814Y247105D01*
X745834Y247070D01*
X745859Y247035D01*
X745899Y246955D01*
X745944Y246835D01*
X745954Y246795D01*
X745964Y246750D01*
X745969Y246710D01*
X745979Y246665D01*
Y246495D01*
X745969Y246450D01*
X745964Y246410D01*
X745954Y246365D01*
X745944Y246325D01*
X745899Y246205D01*
X745859Y246125D01*
X745834Y246090D01*
X745814Y246055D01*
X745784Y246020D01*
X745759Y245985D01*
X745729Y245955D01*
Y243530D01*
X745719Y243405D01*
X745679Y243280D01*
X745619Y243170D01*
X745539Y243070D01*
X745439Y242990D01*
X745329Y242930D01*
X745204Y242890D01*
X745079Y242880D01*
X744954Y242890D01*
X744829Y242930D01*
X744719Y242990D01*
X744619Y243070D01*
X744539Y243170D01*
X744479Y243280D01*
X744439Y243405D01*
X744429Y243530D01*
Y245960D01*
X744399Y245990D01*
X744299Y246130D01*
X744279Y246170D01*
X744264Y246205D01*
X744244Y246245D01*
X744229Y246285D01*
X744219Y246325D01*
X744204Y246370D01*
X744199Y246410D01*
X744189Y246450D01*
X744184Y246495D01*
Y246535D01*
X744179Y246580D01*
X744184Y246625D01*
Y246665D01*
X744189Y246710D01*
X744199Y246750D01*
X744204Y246790D01*
X744219Y246835D01*
X744229Y246875D01*
X744244Y246915D01*
X744264Y246955D01*
X744279Y246990D01*
X744299Y247030D01*
X744399Y247170D01*
X744429Y247200D01*
Y249330D01*
X744439Y249455D01*
X744479Y249580D01*
X744539Y249690D01*
X744619Y249790D01*
X744719Y249870D01*
X744829Y249930D01*
X744954Y249970D01*
X745079Y249980D01*
G37*
G54D10*
X-19686Y15748D03*
Y573228D03*
X846455Y15748D03*
Y573228D03*
G54D121*
X683000Y104500D03*
Y132500D03*
G54D112*
X562000Y74931D03*
Y80069D03*
G54D130*
X735654Y128251D03*
Y129826D03*
Y131401D03*
Y132976D03*
Y134550D03*
Y136125D03*
Y137700D03*
Y139275D03*
X754554Y136125D03*
Y134550D03*
Y132976D03*
Y131401D03*
Y129826D03*
Y128251D03*
Y139275D03*
Y137700D03*
G54D131*
X745104Y133763D03*
G54D122*
X672000Y95500D03*
Y113500D03*
Y123500D03*
Y141500D03*
G36*
G01X501772Y249980D02*
X501897Y249970D01*
X502022Y249930D01*
X502132Y249870D01*
X502232Y249790D01*
X502312Y249690D01*
X502372Y249580D01*
X502412Y249455D01*
X502422Y249330D01*
Y248200D01*
X502452Y248170D01*
X502552Y248030D01*
X502572Y247990D01*
X502587Y247955D01*
X502607Y247915D01*
X502622Y247875D01*
X502632Y247835D01*
X502647Y247790D01*
X502652Y247750D01*
X502662Y247710D01*
X502667Y247665D01*
Y247625D01*
X502672Y247580D01*
X502667Y247535D01*
Y247495D01*
X502662Y247450D01*
X502652Y247410D01*
X502647Y247370D01*
X502632Y247325D01*
X502622Y247285D01*
X502607Y247245D01*
X502587Y247205D01*
X502572Y247170D01*
X502552Y247130D01*
X502452Y246990D01*
X502422Y246960D01*
Y243530D01*
X502412Y243405D01*
X502372Y243280D01*
X502312Y243170D01*
X502232Y243070D01*
X502132Y242990D01*
X502022Y242930D01*
X501897Y242890D01*
X501772Y242880D01*
X501647Y242890D01*
X501522Y242930D01*
X501412Y242990D01*
X501312Y243070D01*
X501232Y243170D01*
X501172Y243280D01*
X501132Y243405D01*
X501122Y243530D01*
Y246960D01*
X501092Y246990D01*
X500992Y247130D01*
X500972Y247170D01*
X500957Y247205D01*
X500937Y247245D01*
X500922Y247285D01*
X500912Y247325D01*
X500897Y247370D01*
X500892Y247410D01*
X500882Y247450D01*
X500877Y247495D01*
Y247535D01*
X500872Y247580D01*
X500877Y247625D01*
Y247665D01*
X500882Y247710D01*
X500892Y247750D01*
X500897Y247790D01*
X500912Y247835D01*
X500922Y247875D01*
X500937Y247915D01*
X500957Y247955D01*
X500972Y247990D01*
X500992Y248030D01*
X501092Y248170D01*
X501122Y248200D01*
Y249330D01*
X501132Y249455D01*
X501172Y249580D01*
X501232Y249690D01*
X501312Y249790D01*
X501412Y249870D01*
X501522Y249930D01*
X501647Y249970D01*
X501772Y249980D01*
G37*
G36*
G01X506496D02*
X506621Y249970D01*
X506746Y249930D01*
X506856Y249870D01*
X506956Y249790D01*
X507036Y249690D01*
X507096Y249580D01*
X507136Y249455D01*
X507146Y249330D01*
Y248200D01*
X507176Y248170D01*
X507276Y248030D01*
X507296Y247990D01*
X507311Y247955D01*
X507331Y247915D01*
X507346Y247875D01*
X507356Y247835D01*
X507371Y247790D01*
X507376Y247750D01*
X507386Y247710D01*
X507391Y247665D01*
Y247625D01*
X507396Y247580D01*
X507391Y247535D01*
Y247495D01*
X507386Y247450D01*
X507376Y247410D01*
X507371Y247370D01*
X507356Y247325D01*
X507346Y247285D01*
X507331Y247245D01*
X507311Y247205D01*
X507296Y247170D01*
X507276Y247130D01*
X507176Y246990D01*
X507146Y246960D01*
Y243530D01*
X507136Y243405D01*
X507096Y243280D01*
X507036Y243170D01*
X506956Y243070D01*
X506856Y242990D01*
X506746Y242930D01*
X506621Y242890D01*
X506496Y242880D01*
X506371Y242890D01*
X506246Y242930D01*
X506136Y242990D01*
X506036Y243070D01*
X505956Y243170D01*
X505896Y243280D01*
X505856Y243405D01*
X505846Y243530D01*
Y246960D01*
X505816Y246990D01*
X505716Y247130D01*
X505696Y247170D01*
X505681Y247205D01*
X505661Y247245D01*
X505646Y247285D01*
X505636Y247325D01*
X505621Y247370D01*
X505616Y247410D01*
X505606Y247450D01*
X505601Y247495D01*
Y247535D01*
X505596Y247580D01*
X505601Y247625D01*
Y247665D01*
X505606Y247710D01*
X505616Y247750D01*
X505621Y247790D01*
X505636Y247835D01*
X505646Y247875D01*
X505661Y247915D01*
X505681Y247955D01*
X505696Y247990D01*
X505716Y248030D01*
X505816Y248170D01*
X505846Y248200D01*
Y249330D01*
X505856Y249455D01*
X505896Y249580D01*
X505956Y249690D01*
X506036Y249790D01*
X506136Y249870D01*
X506246Y249930D01*
X506371Y249970D01*
X506496Y249980D01*
G37*
G36*
G01X511221D02*
X511346Y249970D01*
X511471Y249930D01*
X511581Y249870D01*
X511681Y249790D01*
X511761Y249690D01*
X511821Y249580D01*
X511861Y249455D01*
X511871Y249330D01*
Y248200D01*
X511901Y248170D01*
X512001Y248030D01*
X512021Y247990D01*
X512036Y247955D01*
X512056Y247915D01*
X512071Y247875D01*
X512081Y247835D01*
X512096Y247790D01*
X512101Y247750D01*
X512111Y247710D01*
X512116Y247665D01*
Y247625D01*
X512121Y247580D01*
X512116Y247535D01*
Y247495D01*
X512111Y247450D01*
X512101Y247410D01*
X512096Y247370D01*
X512081Y247325D01*
X512071Y247285D01*
X512056Y247245D01*
X512036Y247205D01*
X512021Y247170D01*
X512001Y247130D01*
X511901Y246990D01*
X511871Y246960D01*
Y243530D01*
X511861Y243405D01*
X511821Y243280D01*
X511761Y243170D01*
X511681Y243070D01*
X511581Y242990D01*
X511471Y242930D01*
X511346Y242890D01*
X511221Y242880D01*
X511096Y242890D01*
X510971Y242930D01*
X510861Y242990D01*
X510761Y243070D01*
X510681Y243170D01*
X510621Y243280D01*
X510581Y243405D01*
X510571Y243530D01*
Y246960D01*
X510541Y246990D01*
X510441Y247130D01*
X510421Y247170D01*
X510406Y247205D01*
X510386Y247245D01*
X510371Y247285D01*
X510361Y247325D01*
X510346Y247370D01*
X510341Y247410D01*
X510331Y247450D01*
X510326Y247495D01*
Y247535D01*
X510321Y247580D01*
X510326Y247625D01*
Y247665D01*
X510331Y247710D01*
X510341Y247750D01*
X510346Y247790D01*
X510361Y247835D01*
X510371Y247875D01*
X510386Y247915D01*
X510406Y247955D01*
X510421Y247990D01*
X510441Y248030D01*
X510541Y248170D01*
X510571Y248200D01*
Y249330D01*
X510581Y249455D01*
X510621Y249580D01*
X510681Y249690D01*
X510761Y249790D01*
X510861Y249870D01*
X510971Y249930D01*
X511096Y249970D01*
X511221Y249980D01*
G37*
G36*
G01X515945D02*
X516070Y249970D01*
X516195Y249930D01*
X516305Y249870D01*
X516405Y249790D01*
X516485Y249690D01*
X516545Y249580D01*
X516585Y249455D01*
X516595Y249330D01*
Y248200D01*
X516625Y248170D01*
X516725Y248030D01*
X516745Y247990D01*
X516760Y247955D01*
X516780Y247915D01*
X516795Y247875D01*
X516805Y247835D01*
X516820Y247790D01*
X516825Y247750D01*
X516835Y247710D01*
X516840Y247665D01*
Y247625D01*
X516845Y247580D01*
X516840Y247535D01*
Y247495D01*
X516835Y247450D01*
X516825Y247410D01*
X516820Y247370D01*
X516805Y247325D01*
X516795Y247285D01*
X516780Y247245D01*
X516760Y247205D01*
X516745Y247170D01*
X516725Y247130D01*
X516625Y246990D01*
X516595Y246960D01*
Y243530D01*
X516585Y243405D01*
X516545Y243280D01*
X516485Y243170D01*
X516405Y243070D01*
X516305Y242990D01*
X516195Y242930D01*
X516070Y242890D01*
X515945Y242880D01*
X515820Y242890D01*
X515695Y242930D01*
X515585Y242990D01*
X515485Y243070D01*
X515405Y243170D01*
X515345Y243280D01*
X515305Y243405D01*
X515295Y243530D01*
Y246960D01*
X515265Y246990D01*
X515165Y247130D01*
X515145Y247170D01*
X515130Y247205D01*
X515110Y247245D01*
X515095Y247285D01*
X515085Y247325D01*
X515070Y247370D01*
X515065Y247410D01*
X515055Y247450D01*
X515050Y247495D01*
Y247535D01*
X515045Y247580D01*
X515050Y247625D01*
Y247665D01*
X515055Y247710D01*
X515065Y247750D01*
X515070Y247790D01*
X515085Y247835D01*
X515095Y247875D01*
X515110Y247915D01*
X515130Y247955D01*
X515145Y247990D01*
X515165Y248030D01*
X515265Y248170D01*
X515295Y248200D01*
Y249330D01*
X515305Y249455D01*
X515345Y249580D01*
X515405Y249690D01*
X515485Y249790D01*
X515585Y249870D01*
X515695Y249930D01*
X515820Y249970D01*
X515945Y249980D01*
G37*
G36*
G01X520670D02*
X520795Y249970D01*
X520920Y249930D01*
X521030Y249870D01*
X521130Y249790D01*
X521210Y249690D01*
X521270Y249580D01*
X521310Y249455D01*
X521320Y249330D01*
Y248200D01*
X521350Y248170D01*
X521450Y248030D01*
X521470Y247990D01*
X521485Y247955D01*
X521505Y247915D01*
X521520Y247875D01*
X521530Y247835D01*
X521545Y247790D01*
X521550Y247750D01*
X521560Y247710D01*
X521565Y247665D01*
Y247625D01*
X521570Y247580D01*
X521565Y247535D01*
Y247495D01*
X521560Y247450D01*
X521550Y247410D01*
X521545Y247370D01*
X521530Y247325D01*
X521520Y247285D01*
X521505Y247245D01*
X521485Y247205D01*
X521470Y247170D01*
X521450Y247130D01*
X521350Y246990D01*
X521320Y246960D01*
Y243530D01*
X521310Y243405D01*
X521270Y243280D01*
X521210Y243170D01*
X521130Y243070D01*
X521030Y242990D01*
X520920Y242930D01*
X520795Y242890D01*
X520670Y242880D01*
X520545Y242890D01*
X520420Y242930D01*
X520310Y242990D01*
X520210Y243070D01*
X520130Y243170D01*
X520070Y243280D01*
X520030Y243405D01*
X520020Y243530D01*
Y246960D01*
X519990Y246990D01*
X519890Y247130D01*
X519870Y247170D01*
X519855Y247205D01*
X519835Y247245D01*
X519820Y247285D01*
X519810Y247325D01*
X519795Y247370D01*
X519790Y247410D01*
X519780Y247450D01*
X519775Y247495D01*
Y247535D01*
X519770Y247580D01*
X519775Y247625D01*
Y247665D01*
X519780Y247710D01*
X519790Y247750D01*
X519795Y247790D01*
X519810Y247835D01*
X519820Y247875D01*
X519835Y247915D01*
X519855Y247955D01*
X519870Y247990D01*
X519890Y248030D01*
X519990Y248170D01*
X520020Y248200D01*
Y249330D01*
X520030Y249455D01*
X520070Y249580D01*
X520130Y249690D01*
X520210Y249790D01*
X520310Y249870D01*
X520420Y249930D01*
X520545Y249970D01*
X520670Y249980D01*
G37*
G36*
G01X525394D02*
X525519Y249970D01*
X525644Y249930D01*
X525754Y249870D01*
X525854Y249790D01*
X525934Y249690D01*
X525994Y249580D01*
X526034Y249455D01*
X526044Y249330D01*
Y248200D01*
X526074Y248170D01*
X526174Y248030D01*
X526194Y247990D01*
X526209Y247955D01*
X526229Y247915D01*
X526244Y247875D01*
X526254Y247835D01*
X526269Y247790D01*
X526274Y247750D01*
X526284Y247710D01*
X526289Y247665D01*
Y247625D01*
X526294Y247580D01*
X526289Y247535D01*
Y247495D01*
X526284Y247450D01*
X526274Y247410D01*
X526269Y247370D01*
X526254Y247325D01*
X526244Y247285D01*
X526229Y247245D01*
X526209Y247205D01*
X526194Y247170D01*
X526174Y247130D01*
X526074Y246990D01*
X526044Y246960D01*
Y243530D01*
X526034Y243405D01*
X525994Y243280D01*
X525934Y243170D01*
X525854Y243070D01*
X525754Y242990D01*
X525644Y242930D01*
X525519Y242890D01*
X525394Y242880D01*
X525269Y242890D01*
X525144Y242930D01*
X525034Y242990D01*
X524934Y243070D01*
X524854Y243170D01*
X524794Y243280D01*
X524754Y243405D01*
X524744Y243530D01*
Y246960D01*
X524714Y246990D01*
X524614Y247130D01*
X524594Y247170D01*
X524579Y247205D01*
X524559Y247245D01*
X524544Y247285D01*
X524534Y247325D01*
X524519Y247370D01*
X524514Y247410D01*
X524504Y247450D01*
X524499Y247495D01*
Y247535D01*
X524494Y247580D01*
X524499Y247625D01*
Y247665D01*
X524504Y247710D01*
X524514Y247750D01*
X524519Y247790D01*
X524534Y247835D01*
X524544Y247875D01*
X524559Y247915D01*
X524579Y247955D01*
X524594Y247990D01*
X524614Y248030D01*
X524714Y248170D01*
X524744Y248200D01*
Y249330D01*
X524754Y249455D01*
X524794Y249580D01*
X524854Y249690D01*
X524934Y249790D01*
X525034Y249870D01*
X525144Y249930D01*
X525269Y249970D01*
X525394Y249980D01*
G37*
G36*
G01X530118D02*
X530243Y249970D01*
X530368Y249930D01*
X530478Y249870D01*
X530578Y249790D01*
X530658Y249690D01*
X530718Y249580D01*
X530758Y249455D01*
X530768Y249330D01*
Y248200D01*
X530798Y248170D01*
X530898Y248030D01*
X530918Y247990D01*
X530933Y247955D01*
X530953Y247915D01*
X530968Y247875D01*
X530978Y247835D01*
X530993Y247790D01*
X530998Y247750D01*
X531008Y247710D01*
X531013Y247665D01*
Y247625D01*
X531018Y247580D01*
X531013Y247535D01*
Y247495D01*
X531008Y247450D01*
X530998Y247410D01*
X530993Y247370D01*
X530978Y247325D01*
X530968Y247285D01*
X530953Y247245D01*
X530933Y247205D01*
X530918Y247170D01*
X530898Y247130D01*
X530798Y246990D01*
X530768Y246960D01*
Y243530D01*
X530758Y243405D01*
X530718Y243280D01*
X530658Y243170D01*
X530578Y243070D01*
X530478Y242990D01*
X530368Y242930D01*
X530243Y242890D01*
X530118Y242880D01*
X529993Y242890D01*
X529868Y242930D01*
X529758Y242990D01*
X529658Y243070D01*
X529578Y243170D01*
X529518Y243280D01*
X529478Y243405D01*
X529468Y243530D01*
Y246960D01*
X529438Y246990D01*
X529338Y247130D01*
X529318Y247170D01*
X529303Y247205D01*
X529283Y247245D01*
X529268Y247285D01*
X529258Y247325D01*
X529243Y247370D01*
X529238Y247410D01*
X529228Y247450D01*
X529223Y247495D01*
Y247535D01*
X529218Y247580D01*
X529223Y247625D01*
Y247665D01*
X529228Y247710D01*
X529238Y247750D01*
X529243Y247790D01*
X529258Y247835D01*
X529268Y247875D01*
X529283Y247915D01*
X529303Y247955D01*
X529318Y247990D01*
X529338Y248030D01*
X529438Y248170D01*
X529468Y248200D01*
Y249330D01*
X529478Y249455D01*
X529518Y249580D01*
X529578Y249690D01*
X529658Y249790D01*
X529758Y249870D01*
X529868Y249930D01*
X529993Y249970D01*
X530118Y249980D01*
G37*
G36*
G01X534843D02*
X534968Y249970D01*
X535093Y249930D01*
X535203Y249870D01*
X535303Y249790D01*
X535383Y249690D01*
X535443Y249580D01*
X535483Y249455D01*
X535493Y249330D01*
Y248200D01*
X535523Y248170D01*
X535623Y248030D01*
X535643Y247990D01*
X535658Y247955D01*
X535678Y247915D01*
X535693Y247875D01*
X535703Y247835D01*
X535718Y247790D01*
X535723Y247750D01*
X535733Y247710D01*
X535738Y247665D01*
Y247625D01*
X535743Y247580D01*
X535738Y247535D01*
Y247495D01*
X535733Y247450D01*
X535723Y247410D01*
X535718Y247370D01*
X535703Y247325D01*
X535693Y247285D01*
X535678Y247245D01*
X535658Y247205D01*
X535643Y247170D01*
X535623Y247130D01*
X535523Y246990D01*
X535493Y246960D01*
Y243530D01*
X535483Y243405D01*
X535443Y243280D01*
X535383Y243170D01*
X535303Y243070D01*
X535203Y242990D01*
X535093Y242930D01*
X534968Y242890D01*
X534843Y242880D01*
X534718Y242890D01*
X534593Y242930D01*
X534483Y242990D01*
X534383Y243070D01*
X534303Y243170D01*
X534243Y243280D01*
X534203Y243405D01*
X534193Y243530D01*
Y246960D01*
X534163Y246990D01*
X534063Y247130D01*
X534043Y247170D01*
X534028Y247205D01*
X534008Y247245D01*
X533993Y247285D01*
X533983Y247325D01*
X533968Y247370D01*
X533963Y247410D01*
X533953Y247450D01*
X533948Y247495D01*
Y247535D01*
X533943Y247580D01*
X533948Y247625D01*
Y247665D01*
X533953Y247710D01*
X533963Y247750D01*
X533968Y247790D01*
X533983Y247835D01*
X533993Y247875D01*
X534008Y247915D01*
X534028Y247955D01*
X534043Y247990D01*
X534063Y248030D01*
X534163Y248170D01*
X534193Y248200D01*
Y249330D01*
X534203Y249455D01*
X534243Y249580D01*
X534303Y249690D01*
X534383Y249790D01*
X534483Y249870D01*
X534593Y249930D01*
X534718Y249970D01*
X534843Y249980D01*
G37*
G36*
G01X539567D02*
X539692Y249970D01*
X539817Y249930D01*
X539927Y249870D01*
X540027Y249790D01*
X540107Y249690D01*
X540167Y249580D01*
X540207Y249455D01*
X540217Y249330D01*
Y248200D01*
X540247Y248170D01*
X540347Y248030D01*
X540367Y247990D01*
X540382Y247955D01*
X540402Y247915D01*
X540417Y247875D01*
X540427Y247835D01*
X540442Y247790D01*
X540447Y247750D01*
X540457Y247710D01*
X540462Y247665D01*
Y247625D01*
X540467Y247580D01*
X540462Y247535D01*
Y247495D01*
X540457Y247450D01*
X540447Y247410D01*
X540442Y247370D01*
X540427Y247325D01*
X540417Y247285D01*
X540402Y247245D01*
X540382Y247205D01*
X540367Y247170D01*
X540347Y247130D01*
X540247Y246990D01*
X540217Y246960D01*
Y243530D01*
X540207Y243405D01*
X540167Y243280D01*
X540107Y243170D01*
X540027Y243070D01*
X539927Y242990D01*
X539817Y242930D01*
X539692Y242890D01*
X539567Y242880D01*
X539442Y242890D01*
X539317Y242930D01*
X539207Y242990D01*
X539107Y243070D01*
X539027Y243170D01*
X538967Y243280D01*
X538927Y243405D01*
X538917Y243530D01*
Y246960D01*
X538887Y246990D01*
X538787Y247130D01*
X538767Y247170D01*
X538752Y247205D01*
X538732Y247245D01*
X538717Y247285D01*
X538707Y247325D01*
X538692Y247370D01*
X538687Y247410D01*
X538677Y247450D01*
X538672Y247495D01*
Y247535D01*
X538667Y247580D01*
X538672Y247625D01*
Y247665D01*
X538677Y247710D01*
X538687Y247750D01*
X538692Y247790D01*
X538707Y247835D01*
X538717Y247875D01*
X538732Y247915D01*
X538752Y247955D01*
X538767Y247990D01*
X538787Y248030D01*
X538887Y248170D01*
X538917Y248200D01*
Y249330D01*
X538927Y249455D01*
X538967Y249580D01*
X539027Y249690D01*
X539107Y249790D01*
X539207Y249870D01*
X539317Y249930D01*
X539442Y249970D01*
X539567Y249980D01*
G37*
G36*
G01X544292D02*
X544417Y249970D01*
X544542Y249930D01*
X544652Y249870D01*
X544752Y249790D01*
X544832Y249690D01*
X544892Y249580D01*
X544932Y249455D01*
X544942Y249330D01*
Y248200D01*
X544972Y248170D01*
X545072Y248030D01*
X545092Y247990D01*
X545107Y247955D01*
X545127Y247915D01*
X545142Y247875D01*
X545152Y247835D01*
X545167Y247790D01*
X545172Y247750D01*
X545182Y247710D01*
X545187Y247665D01*
Y247625D01*
X545192Y247580D01*
X545187Y247535D01*
Y247495D01*
X545182Y247450D01*
X545172Y247410D01*
X545167Y247370D01*
X545152Y247325D01*
X545142Y247285D01*
X545127Y247245D01*
X545107Y247205D01*
X545092Y247170D01*
X545072Y247130D01*
X544972Y246990D01*
X544942Y246960D01*
Y243530D01*
X544932Y243405D01*
X544892Y243280D01*
X544832Y243170D01*
X544752Y243070D01*
X544652Y242990D01*
X544542Y242930D01*
X544417Y242890D01*
X544292Y242880D01*
X544167Y242890D01*
X544042Y242930D01*
X543932Y242990D01*
X543832Y243070D01*
X543752Y243170D01*
X543692Y243280D01*
X543652Y243405D01*
X543642Y243530D01*
Y246960D01*
X543612Y246990D01*
X543512Y247130D01*
X543492Y247170D01*
X543477Y247205D01*
X543457Y247245D01*
X543442Y247285D01*
X543432Y247325D01*
X543417Y247370D01*
X543412Y247410D01*
X543402Y247450D01*
X543397Y247495D01*
Y247535D01*
X543392Y247580D01*
X543397Y247625D01*
Y247665D01*
X543402Y247710D01*
X543412Y247750D01*
X543417Y247790D01*
X543432Y247835D01*
X543442Y247875D01*
X543457Y247915D01*
X543477Y247955D01*
X543492Y247990D01*
X543512Y248030D01*
X543612Y248170D01*
X543642Y248200D01*
Y249330D01*
X543652Y249455D01*
X543692Y249580D01*
X543752Y249690D01*
X543832Y249790D01*
X543932Y249870D01*
X544042Y249930D01*
X544167Y249970D01*
X544292Y249980D01*
G37*
G36*
G01X549016D02*
X549141Y249970D01*
X549266Y249930D01*
X549376Y249870D01*
X549476Y249790D01*
X549556Y249690D01*
X549616Y249580D01*
X549656Y249455D01*
X549666Y249330D01*
Y248200D01*
X549696Y248170D01*
X549796Y248030D01*
X549816Y247990D01*
X549831Y247955D01*
X549851Y247915D01*
X549866Y247875D01*
X549876Y247835D01*
X549891Y247790D01*
X549896Y247750D01*
X549906Y247710D01*
X549911Y247665D01*
Y247625D01*
X549916Y247580D01*
X549911Y247535D01*
Y247495D01*
X549906Y247450D01*
X549896Y247410D01*
X549891Y247370D01*
X549876Y247325D01*
X549866Y247285D01*
X549851Y247245D01*
X549831Y247205D01*
X549816Y247170D01*
X549796Y247130D01*
X549696Y246990D01*
X549666Y246960D01*
Y243530D01*
X549656Y243405D01*
X549616Y243280D01*
X549556Y243170D01*
X549476Y243070D01*
X549376Y242990D01*
X549266Y242930D01*
X549141Y242890D01*
X549016Y242880D01*
X548891Y242890D01*
X548766Y242930D01*
X548656Y242990D01*
X548556Y243070D01*
X548476Y243170D01*
X548416Y243280D01*
X548376Y243405D01*
X548366Y243530D01*
Y246960D01*
X548336Y246990D01*
X548236Y247130D01*
X548216Y247170D01*
X548201Y247205D01*
X548181Y247245D01*
X548166Y247285D01*
X548156Y247325D01*
X548141Y247370D01*
X548136Y247410D01*
X548126Y247450D01*
X548121Y247495D01*
Y247535D01*
X548116Y247580D01*
X548121Y247625D01*
Y247665D01*
X548126Y247710D01*
X548136Y247750D01*
X548141Y247790D01*
X548156Y247835D01*
X548166Y247875D01*
X548181Y247915D01*
X548201Y247955D01*
X548216Y247990D01*
X548236Y248030D01*
X548336Y248170D01*
X548366Y248200D01*
Y249330D01*
X548376Y249455D01*
X548416Y249580D01*
X548476Y249690D01*
X548556Y249790D01*
X548656Y249870D01*
X548766Y249930D01*
X548891Y249970D01*
X549016Y249980D01*
G37*
G36*
G01X553740D02*
X553865Y249970D01*
X553990Y249930D01*
X554100Y249870D01*
X554200Y249790D01*
X554280Y249690D01*
X554340Y249580D01*
X554380Y249455D01*
X554390Y249330D01*
Y248200D01*
X554420Y248170D01*
X554520Y248030D01*
X554540Y247990D01*
X554555Y247955D01*
X554575Y247915D01*
X554590Y247875D01*
X554600Y247835D01*
X554615Y247790D01*
X554620Y247750D01*
X554630Y247710D01*
X554635Y247665D01*
Y247625D01*
X554640Y247580D01*
X554635Y247535D01*
Y247495D01*
X554630Y247450D01*
X554620Y247410D01*
X554615Y247370D01*
X554600Y247325D01*
X554590Y247285D01*
X554575Y247245D01*
X554555Y247205D01*
X554540Y247170D01*
X554520Y247130D01*
X554420Y246990D01*
X554390Y246960D01*
Y243530D01*
X554380Y243405D01*
X554340Y243280D01*
X554280Y243170D01*
X554200Y243070D01*
X554100Y242990D01*
X553990Y242930D01*
X553865Y242890D01*
X553740Y242880D01*
X553615Y242890D01*
X553490Y242930D01*
X553380Y242990D01*
X553280Y243070D01*
X553200Y243170D01*
X553140Y243280D01*
X553100Y243405D01*
X553090Y243530D01*
Y246960D01*
X553060Y246990D01*
X552960Y247130D01*
X552940Y247170D01*
X552925Y247205D01*
X552905Y247245D01*
X552890Y247285D01*
X552880Y247325D01*
X552865Y247370D01*
X552860Y247410D01*
X552850Y247450D01*
X552845Y247495D01*
Y247535D01*
X552840Y247580D01*
X552845Y247625D01*
Y247665D01*
X552850Y247710D01*
X552860Y247750D01*
X552865Y247790D01*
X552880Y247835D01*
X552890Y247875D01*
X552905Y247915D01*
X552925Y247955D01*
X552940Y247990D01*
X552960Y248030D01*
X553060Y248170D01*
X553090Y248200D01*
Y249330D01*
X553100Y249455D01*
X553140Y249580D01*
X553200Y249690D01*
X553280Y249790D01*
X553380Y249870D01*
X553490Y249930D01*
X553615Y249970D01*
X553740Y249980D01*
G37*
G36*
G01X558465D02*
X558590Y249970D01*
X558715Y249930D01*
X558825Y249870D01*
X558925Y249790D01*
X559005Y249690D01*
X559065Y249580D01*
X559105Y249455D01*
X559115Y249330D01*
Y248200D01*
X559145Y248170D01*
X559245Y248030D01*
X559265Y247990D01*
X559280Y247955D01*
X559300Y247915D01*
X559315Y247875D01*
X559325Y247835D01*
X559340Y247790D01*
X559345Y247750D01*
X559355Y247710D01*
X559360Y247665D01*
Y247625D01*
X559365Y247580D01*
X559360Y247535D01*
Y247495D01*
X559355Y247450D01*
X559345Y247410D01*
X559340Y247370D01*
X559325Y247325D01*
X559315Y247285D01*
X559300Y247245D01*
X559280Y247205D01*
X559265Y247170D01*
X559245Y247130D01*
X559145Y246990D01*
X559115Y246960D01*
Y243530D01*
X559105Y243405D01*
X559065Y243280D01*
X559005Y243170D01*
X558925Y243070D01*
X558825Y242990D01*
X558715Y242930D01*
X558590Y242890D01*
X558465Y242880D01*
X558340Y242890D01*
X558215Y242930D01*
X558105Y242990D01*
X558005Y243070D01*
X557925Y243170D01*
X557865Y243280D01*
X557825Y243405D01*
X557815Y243530D01*
Y246960D01*
X557785Y246990D01*
X557685Y247130D01*
X557665Y247170D01*
X557650Y247205D01*
X557630Y247245D01*
X557615Y247285D01*
X557605Y247325D01*
X557590Y247370D01*
X557585Y247410D01*
X557575Y247450D01*
X557570Y247495D01*
Y247535D01*
X557565Y247580D01*
X557570Y247625D01*
Y247665D01*
X557575Y247710D01*
X557585Y247750D01*
X557590Y247790D01*
X557605Y247835D01*
X557615Y247875D01*
X557630Y247915D01*
X557650Y247955D01*
X557665Y247990D01*
X557685Y248030D01*
X557785Y248170D01*
X557815Y248200D01*
Y249330D01*
X557825Y249455D01*
X557865Y249580D01*
X557925Y249690D01*
X558005Y249790D01*
X558105Y249870D01*
X558215Y249930D01*
X558340Y249970D01*
X558465Y249980D01*
G37*
G36*
G01X563189D02*
X563314Y249970D01*
X563439Y249930D01*
X563549Y249870D01*
X563649Y249790D01*
X563729Y249690D01*
X563789Y249580D01*
X563829Y249455D01*
X563839Y249330D01*
Y248200D01*
X563869Y248170D01*
X563969Y248030D01*
X563989Y247990D01*
X564004Y247955D01*
X564024Y247915D01*
X564039Y247875D01*
X564049Y247835D01*
X564064Y247790D01*
X564069Y247750D01*
X564079Y247710D01*
X564084Y247665D01*
Y247625D01*
X564089Y247580D01*
X564084Y247535D01*
Y247495D01*
X564079Y247450D01*
X564069Y247410D01*
X564064Y247370D01*
X564049Y247325D01*
X564039Y247285D01*
X564024Y247245D01*
X564004Y247205D01*
X563989Y247170D01*
X563969Y247130D01*
X563869Y246990D01*
X563839Y246960D01*
Y243530D01*
X563829Y243405D01*
X563789Y243280D01*
X563729Y243170D01*
X563649Y243070D01*
X563549Y242990D01*
X563439Y242930D01*
X563314Y242890D01*
X563189Y242880D01*
X563064Y242890D01*
X562939Y242930D01*
X562829Y242990D01*
X562729Y243070D01*
X562649Y243170D01*
X562589Y243280D01*
X562549Y243405D01*
X562539Y243530D01*
Y246960D01*
X562509Y246990D01*
X562409Y247130D01*
X562389Y247170D01*
X562374Y247205D01*
X562354Y247245D01*
X562339Y247285D01*
X562329Y247325D01*
X562314Y247370D01*
X562309Y247410D01*
X562299Y247450D01*
X562294Y247495D01*
Y247535D01*
X562289Y247580D01*
X562294Y247625D01*
Y247665D01*
X562299Y247710D01*
X562309Y247750D01*
X562314Y247790D01*
X562329Y247835D01*
X562339Y247875D01*
X562354Y247915D01*
X562374Y247955D01*
X562389Y247990D01*
X562409Y248030D01*
X562509Y248170D01*
X562539Y248200D01*
Y249330D01*
X562549Y249455D01*
X562589Y249580D01*
X562649Y249690D01*
X562729Y249790D01*
X562829Y249870D01*
X562939Y249930D01*
X563064Y249970D01*
X563189Y249980D01*
G37*
G36*
G01X567914D02*
X568039Y249970D01*
X568164Y249930D01*
X568274Y249870D01*
X568374Y249790D01*
X568454Y249690D01*
X568514Y249580D01*
X568554Y249455D01*
X568564Y249330D01*
Y248200D01*
X568594Y248170D01*
X568694Y248030D01*
X568714Y247990D01*
X568729Y247955D01*
X568749Y247915D01*
X568764Y247875D01*
X568774Y247835D01*
X568789Y247790D01*
X568794Y247750D01*
X568804Y247710D01*
X568809Y247665D01*
Y247625D01*
X568814Y247580D01*
X568809Y247535D01*
Y247495D01*
X568804Y247450D01*
X568794Y247410D01*
X568789Y247370D01*
X568774Y247325D01*
X568764Y247285D01*
X568749Y247245D01*
X568729Y247205D01*
X568714Y247170D01*
X568694Y247130D01*
X568594Y246990D01*
X568564Y246960D01*
Y243530D01*
X568554Y243405D01*
X568514Y243280D01*
X568454Y243170D01*
X568374Y243070D01*
X568274Y242990D01*
X568164Y242930D01*
X568039Y242890D01*
X567914Y242880D01*
X567789Y242890D01*
X567664Y242930D01*
X567554Y242990D01*
X567454Y243070D01*
X567374Y243170D01*
X567314Y243280D01*
X567274Y243405D01*
X567264Y243530D01*
Y246960D01*
X567234Y246990D01*
X567134Y247130D01*
X567114Y247170D01*
X567099Y247205D01*
X567079Y247245D01*
X567064Y247285D01*
X567054Y247325D01*
X567039Y247370D01*
X567034Y247410D01*
X567024Y247450D01*
X567019Y247495D01*
Y247535D01*
X567014Y247580D01*
X567019Y247625D01*
Y247665D01*
X567024Y247710D01*
X567034Y247750D01*
X567039Y247790D01*
X567054Y247835D01*
X567064Y247875D01*
X567079Y247915D01*
X567099Y247955D01*
X567114Y247990D01*
X567134Y248030D01*
X567234Y248170D01*
X567264Y248200D01*
Y249330D01*
X567274Y249455D01*
X567314Y249580D01*
X567374Y249690D01*
X567454Y249790D01*
X567554Y249870D01*
X567664Y249930D01*
X567789Y249970D01*
X567914Y249980D01*
G37*
G36*
G01X572638D02*
X572763Y249970D01*
X572888Y249930D01*
X572998Y249870D01*
X573098Y249790D01*
X573178Y249690D01*
X573238Y249580D01*
X573278Y249455D01*
X573288Y249330D01*
Y248200D01*
X573318Y248170D01*
X573418Y248030D01*
X573438Y247990D01*
X573453Y247955D01*
X573473Y247915D01*
X573488Y247875D01*
X573498Y247835D01*
X573513Y247790D01*
X573518Y247750D01*
X573528Y247710D01*
X573533Y247665D01*
Y247625D01*
X573538Y247580D01*
X573533Y247535D01*
Y247495D01*
X573528Y247450D01*
X573518Y247410D01*
X573513Y247370D01*
X573498Y247325D01*
X573488Y247285D01*
X573473Y247245D01*
X573453Y247205D01*
X573438Y247170D01*
X573418Y247130D01*
X573318Y246990D01*
X573288Y246960D01*
Y243530D01*
X573278Y243405D01*
X573238Y243280D01*
X573178Y243170D01*
X573098Y243070D01*
X572998Y242990D01*
X572888Y242930D01*
X572763Y242890D01*
X572638Y242880D01*
X572513Y242890D01*
X572388Y242930D01*
X572278Y242990D01*
X572178Y243070D01*
X572098Y243170D01*
X572038Y243280D01*
X571998Y243405D01*
X571988Y243530D01*
Y246960D01*
X571958Y246990D01*
X571858Y247130D01*
X571838Y247170D01*
X571823Y247205D01*
X571803Y247245D01*
X571788Y247285D01*
X571778Y247325D01*
X571763Y247370D01*
X571758Y247410D01*
X571748Y247450D01*
X571743Y247495D01*
Y247535D01*
X571738Y247580D01*
X571743Y247625D01*
Y247665D01*
X571748Y247710D01*
X571758Y247750D01*
X571763Y247790D01*
X571778Y247835D01*
X571788Y247875D01*
X571803Y247915D01*
X571823Y247955D01*
X571838Y247990D01*
X571858Y248030D01*
X571958Y248170D01*
X571988Y248200D01*
Y249330D01*
X571998Y249455D01*
X572038Y249580D01*
X572098Y249690D01*
X572178Y249790D01*
X572278Y249870D01*
X572388Y249930D01*
X572513Y249970D01*
X572638Y249980D01*
G37*
G36*
G01X577362D02*
X577487Y249970D01*
X577612Y249930D01*
X577722Y249870D01*
X577822Y249790D01*
X577902Y249690D01*
X577962Y249580D01*
X578002Y249455D01*
X578012Y249330D01*
Y248200D01*
X578042Y248170D01*
X578142Y248030D01*
X578162Y247990D01*
X578177Y247955D01*
X578197Y247915D01*
X578212Y247875D01*
X578222Y247835D01*
X578237Y247790D01*
X578242Y247750D01*
X578252Y247710D01*
X578257Y247665D01*
Y247625D01*
X578262Y247580D01*
X578257Y247535D01*
Y247495D01*
X578252Y247450D01*
X578242Y247410D01*
X578237Y247370D01*
X578222Y247325D01*
X578212Y247285D01*
X578197Y247245D01*
X578177Y247205D01*
X578162Y247170D01*
X578142Y247130D01*
X578042Y246990D01*
X578012Y246960D01*
Y243530D01*
X578002Y243405D01*
X577962Y243280D01*
X577902Y243170D01*
X577822Y243070D01*
X577722Y242990D01*
X577612Y242930D01*
X577487Y242890D01*
X577362Y242880D01*
X577237Y242890D01*
X577112Y242930D01*
X577002Y242990D01*
X576902Y243070D01*
X576822Y243170D01*
X576762Y243280D01*
X576722Y243405D01*
X576712Y243530D01*
Y246960D01*
X576682Y246990D01*
X576582Y247130D01*
X576562Y247170D01*
X576547Y247205D01*
X576527Y247245D01*
X576512Y247285D01*
X576502Y247325D01*
X576487Y247370D01*
X576482Y247410D01*
X576472Y247450D01*
X576467Y247495D01*
Y247535D01*
X576462Y247580D01*
X576467Y247625D01*
Y247665D01*
X576472Y247710D01*
X576482Y247750D01*
X576487Y247790D01*
X576502Y247835D01*
X576512Y247875D01*
X576527Y247915D01*
X576547Y247955D01*
X576562Y247990D01*
X576582Y248030D01*
X576682Y248170D01*
X576712Y248200D01*
Y249330D01*
X576722Y249455D01*
X576762Y249580D01*
X576822Y249690D01*
X576902Y249790D01*
X577002Y249870D01*
X577112Y249930D01*
X577237Y249970D01*
X577362Y249980D01*
G37*
G36*
G01X582087D02*
X582212Y249970D01*
X582337Y249930D01*
X582447Y249870D01*
X582547Y249790D01*
X582627Y249690D01*
X582687Y249580D01*
X582727Y249455D01*
X582737Y249330D01*
Y248200D01*
X582767Y248170D01*
X582867Y248030D01*
X582887Y247990D01*
X582902Y247955D01*
X582922Y247915D01*
X582937Y247875D01*
X582947Y247835D01*
X582962Y247790D01*
X582967Y247750D01*
X582977Y247710D01*
X582982Y247665D01*
Y247625D01*
X582987Y247580D01*
X582982Y247535D01*
Y247495D01*
X582977Y247450D01*
X582967Y247410D01*
X582962Y247370D01*
X582947Y247325D01*
X582937Y247285D01*
X582922Y247245D01*
X582902Y247205D01*
X582887Y247170D01*
X582867Y247130D01*
X582767Y246990D01*
X582737Y246960D01*
Y243530D01*
X582727Y243405D01*
X582687Y243280D01*
X582627Y243170D01*
X582547Y243070D01*
X582447Y242990D01*
X582337Y242930D01*
X582212Y242890D01*
X582087Y242880D01*
X581962Y242890D01*
X581837Y242930D01*
X581727Y242990D01*
X581627Y243070D01*
X581547Y243170D01*
X581487Y243280D01*
X581447Y243405D01*
X581437Y243530D01*
Y246960D01*
X581407Y246990D01*
X581307Y247130D01*
X581287Y247170D01*
X581272Y247205D01*
X581252Y247245D01*
X581237Y247285D01*
X581227Y247325D01*
X581212Y247370D01*
X581207Y247410D01*
X581197Y247450D01*
X581192Y247495D01*
Y247535D01*
X581187Y247580D01*
X581192Y247625D01*
Y247665D01*
X581197Y247710D01*
X581207Y247750D01*
X581212Y247790D01*
X581227Y247835D01*
X581237Y247875D01*
X581252Y247915D01*
X581272Y247955D01*
X581287Y247990D01*
X581307Y248030D01*
X581407Y248170D01*
X581437Y248200D01*
Y249330D01*
X581447Y249455D01*
X581487Y249580D01*
X581547Y249690D01*
X581627Y249790D01*
X581727Y249870D01*
X581837Y249930D01*
X581962Y249970D01*
X582087Y249980D01*
G37*
G36*
G01X586811D02*
X586936Y249970D01*
X587061Y249930D01*
X587171Y249870D01*
X587271Y249790D01*
X587351Y249690D01*
X587411Y249580D01*
X587451Y249455D01*
X587461Y249330D01*
Y248200D01*
X587491Y248170D01*
X587591Y248030D01*
X587611Y247990D01*
X587626Y247955D01*
X587646Y247915D01*
X587661Y247875D01*
X587671Y247835D01*
X587686Y247790D01*
X587691Y247750D01*
X587701Y247710D01*
X587706Y247665D01*
Y247625D01*
X587711Y247580D01*
X587706Y247535D01*
Y247495D01*
X587701Y247450D01*
X587691Y247410D01*
X587686Y247370D01*
X587671Y247325D01*
X587661Y247285D01*
X587646Y247245D01*
X587626Y247205D01*
X587611Y247170D01*
X587591Y247130D01*
X587491Y246990D01*
X587461Y246960D01*
Y243530D01*
X587451Y243405D01*
X587411Y243280D01*
X587351Y243170D01*
X587271Y243070D01*
X587171Y242990D01*
X587061Y242930D01*
X586936Y242890D01*
X586811Y242880D01*
X586686Y242890D01*
X586561Y242930D01*
X586451Y242990D01*
X586351Y243070D01*
X586271Y243170D01*
X586211Y243280D01*
X586171Y243405D01*
X586161Y243530D01*
Y246960D01*
X586131Y246990D01*
X586031Y247130D01*
X586011Y247170D01*
X585996Y247205D01*
X585976Y247245D01*
X585961Y247285D01*
X585951Y247325D01*
X585936Y247370D01*
X585931Y247410D01*
X585921Y247450D01*
X585916Y247495D01*
Y247535D01*
X585911Y247580D01*
X585916Y247625D01*
Y247665D01*
X585921Y247710D01*
X585931Y247750D01*
X585936Y247790D01*
X585951Y247835D01*
X585961Y247875D01*
X585976Y247915D01*
X585996Y247955D01*
X586011Y247990D01*
X586031Y248030D01*
X586131Y248170D01*
X586161Y248200D01*
Y249330D01*
X586171Y249455D01*
X586211Y249580D01*
X586271Y249690D01*
X586351Y249790D01*
X586451Y249870D01*
X586561Y249930D01*
X586686Y249970D01*
X586811Y249980D01*
G37*
G36*
G01X591536D02*
X591661Y249970D01*
X591786Y249930D01*
X591896Y249870D01*
X591996Y249790D01*
X592076Y249690D01*
X592136Y249580D01*
X592176Y249455D01*
X592186Y249330D01*
Y248200D01*
X592216Y248170D01*
X592316Y248030D01*
X592336Y247990D01*
X592351Y247955D01*
X592371Y247915D01*
X592386Y247875D01*
X592396Y247835D01*
X592411Y247790D01*
X592416Y247750D01*
X592426Y247710D01*
X592431Y247665D01*
Y247625D01*
X592436Y247580D01*
X592431Y247535D01*
Y247495D01*
X592426Y247450D01*
X592416Y247410D01*
X592411Y247370D01*
X592396Y247325D01*
X592386Y247285D01*
X592371Y247245D01*
X592351Y247205D01*
X592336Y247170D01*
X592316Y247130D01*
X592216Y246990D01*
X592186Y246960D01*
Y243530D01*
X592176Y243405D01*
X592136Y243280D01*
X592076Y243170D01*
X591996Y243070D01*
X591896Y242990D01*
X591786Y242930D01*
X591661Y242890D01*
X591536Y242880D01*
X591411Y242890D01*
X591286Y242930D01*
X591176Y242990D01*
X591076Y243070D01*
X590996Y243170D01*
X590936Y243280D01*
X590896Y243405D01*
X590886Y243530D01*
Y246960D01*
X590856Y246990D01*
X590756Y247130D01*
X590736Y247170D01*
X590721Y247205D01*
X590701Y247245D01*
X590686Y247285D01*
X590676Y247325D01*
X590661Y247370D01*
X590656Y247410D01*
X590646Y247450D01*
X590641Y247495D01*
Y247535D01*
X590636Y247580D01*
X590641Y247625D01*
Y247665D01*
X590646Y247710D01*
X590656Y247750D01*
X590661Y247790D01*
X590676Y247835D01*
X590686Y247875D01*
X590701Y247915D01*
X590721Y247955D01*
X590736Y247990D01*
X590756Y248030D01*
X590856Y248170D01*
X590886Y248200D01*
Y249330D01*
X590896Y249455D01*
X590936Y249580D01*
X590996Y249690D01*
X591076Y249790D01*
X591176Y249870D01*
X591286Y249930D01*
X591411Y249970D01*
X591536Y249980D01*
G37*
G36*
G01X596260D02*
X596385Y249970D01*
X596510Y249930D01*
X596620Y249870D01*
X596720Y249790D01*
X596800Y249690D01*
X596860Y249580D01*
X596900Y249455D01*
X596910Y249330D01*
Y248200D01*
X596940Y248170D01*
X597040Y248030D01*
X597060Y247990D01*
X597075Y247955D01*
X597095Y247915D01*
X597110Y247875D01*
X597120Y247835D01*
X597135Y247790D01*
X597140Y247750D01*
X597150Y247710D01*
X597155Y247665D01*
Y247625D01*
X597160Y247580D01*
X597155Y247535D01*
Y247495D01*
X597150Y247450D01*
X597140Y247410D01*
X597135Y247370D01*
X597120Y247325D01*
X597110Y247285D01*
X597095Y247245D01*
X597075Y247205D01*
X597060Y247170D01*
X597040Y247130D01*
X596940Y246990D01*
X596910Y246960D01*
Y243530D01*
X596900Y243405D01*
X596860Y243280D01*
X596800Y243170D01*
X596720Y243070D01*
X596620Y242990D01*
X596510Y242930D01*
X596385Y242890D01*
X596260Y242880D01*
X596135Y242890D01*
X596010Y242930D01*
X595900Y242990D01*
X595800Y243070D01*
X595720Y243170D01*
X595660Y243280D01*
X595620Y243405D01*
X595610Y243530D01*
Y246960D01*
X595580Y246990D01*
X595480Y247130D01*
X595460Y247170D01*
X595445Y247205D01*
X595425Y247245D01*
X595410Y247285D01*
X595400Y247325D01*
X595385Y247370D01*
X595380Y247410D01*
X595370Y247450D01*
X595365Y247495D01*
Y247535D01*
X595360Y247580D01*
X595365Y247625D01*
Y247665D01*
X595370Y247710D01*
X595380Y247750D01*
X595385Y247790D01*
X595400Y247835D01*
X595410Y247875D01*
X595425Y247915D01*
X595445Y247955D01*
X595460Y247990D01*
X595480Y248030D01*
X595580Y248170D01*
X595610Y248200D01*
Y249330D01*
X595620Y249455D01*
X595660Y249580D01*
X595720Y249690D01*
X595800Y249790D01*
X595900Y249870D01*
X596010Y249930D01*
X596135Y249970D01*
X596260Y249980D01*
G37*
G36*
G01X600985D02*
X601110Y249970D01*
X601235Y249930D01*
X601345Y249870D01*
X601445Y249790D01*
X601525Y249690D01*
X601585Y249580D01*
X601625Y249455D01*
X601635Y249330D01*
Y248200D01*
X601665Y248170D01*
X601765Y248030D01*
X601785Y247990D01*
X601800Y247955D01*
X601820Y247915D01*
X601835Y247875D01*
X601845Y247835D01*
X601860Y247790D01*
X601865Y247750D01*
X601875Y247710D01*
X601880Y247665D01*
Y247625D01*
X601885Y247580D01*
X601880Y247535D01*
Y247495D01*
X601875Y247450D01*
X601865Y247410D01*
X601860Y247370D01*
X601845Y247325D01*
X601835Y247285D01*
X601820Y247245D01*
X601800Y247205D01*
X601785Y247170D01*
X601765Y247130D01*
X601665Y246990D01*
X601635Y246960D01*
Y243530D01*
X601625Y243405D01*
X601585Y243280D01*
X601525Y243170D01*
X601445Y243070D01*
X601345Y242990D01*
X601235Y242930D01*
X601110Y242890D01*
X600985Y242880D01*
X600860Y242890D01*
X600735Y242930D01*
X600625Y242990D01*
X600525Y243070D01*
X600445Y243170D01*
X600385Y243280D01*
X600345Y243405D01*
X600335Y243530D01*
Y246960D01*
X600305Y246990D01*
X600205Y247130D01*
X600185Y247170D01*
X600170Y247205D01*
X600150Y247245D01*
X600135Y247285D01*
X600125Y247325D01*
X600110Y247370D01*
X600105Y247410D01*
X600095Y247450D01*
X600090Y247495D01*
Y247535D01*
X600085Y247580D01*
X600090Y247625D01*
Y247665D01*
X600095Y247710D01*
X600105Y247750D01*
X600110Y247790D01*
X600125Y247835D01*
X600135Y247875D01*
X600150Y247915D01*
X600170Y247955D01*
X600185Y247990D01*
X600205Y248030D01*
X600305Y248170D01*
X600335Y248200D01*
Y249330D01*
X600345Y249455D01*
X600385Y249580D01*
X600445Y249690D01*
X600525Y249790D01*
X600625Y249870D01*
X600735Y249930D01*
X600860Y249970D01*
X600985Y249980D01*
G37*
G36*
G01X605709D02*
X605834Y249970D01*
X605959Y249930D01*
X606069Y249870D01*
X606169Y249790D01*
X606249Y249690D01*
X606309Y249580D01*
X606349Y249455D01*
X606359Y249330D01*
Y248200D01*
X606389Y248170D01*
X606489Y248030D01*
X606509Y247990D01*
X606524Y247955D01*
X606544Y247915D01*
X606559Y247875D01*
X606569Y247835D01*
X606584Y247790D01*
X606589Y247750D01*
X606599Y247710D01*
X606604Y247665D01*
Y247625D01*
X606609Y247580D01*
X606604Y247535D01*
Y247495D01*
X606599Y247450D01*
X606589Y247410D01*
X606584Y247370D01*
X606569Y247325D01*
X606559Y247285D01*
X606544Y247245D01*
X606524Y247205D01*
X606509Y247170D01*
X606489Y247130D01*
X606389Y246990D01*
X606359Y246960D01*
Y243530D01*
X606349Y243405D01*
X606309Y243280D01*
X606249Y243170D01*
X606169Y243070D01*
X606069Y242990D01*
X605959Y242930D01*
X605834Y242890D01*
X605709Y242880D01*
X605584Y242890D01*
X605459Y242930D01*
X605349Y242990D01*
X605249Y243070D01*
X605169Y243170D01*
X605109Y243280D01*
X605069Y243405D01*
X605059Y243530D01*
Y246960D01*
X605029Y246990D01*
X604929Y247130D01*
X604909Y247170D01*
X604894Y247205D01*
X604874Y247245D01*
X604859Y247285D01*
X604849Y247325D01*
X604834Y247370D01*
X604829Y247410D01*
X604819Y247450D01*
X604814Y247495D01*
Y247535D01*
X604809Y247580D01*
X604814Y247625D01*
Y247665D01*
X604819Y247710D01*
X604829Y247750D01*
X604834Y247790D01*
X604849Y247835D01*
X604859Y247875D01*
X604874Y247915D01*
X604894Y247955D01*
X604909Y247990D01*
X604929Y248030D01*
X605029Y248170D01*
X605059Y248200D01*
Y249330D01*
X605069Y249455D01*
X605109Y249580D01*
X605169Y249690D01*
X605249Y249790D01*
X605349Y249870D01*
X605459Y249930D01*
X605584Y249970D01*
X605709Y249980D01*
G37*
G36*
G01X610433D02*
X610558Y249970D01*
X610683Y249930D01*
X610793Y249870D01*
X610893Y249790D01*
X610973Y249690D01*
X611033Y249580D01*
X611073Y249455D01*
X611083Y249330D01*
Y248200D01*
X611113Y248170D01*
X611213Y248030D01*
X611233Y247990D01*
X611248Y247955D01*
X611268Y247915D01*
X611283Y247875D01*
X611293Y247835D01*
X611308Y247790D01*
X611313Y247750D01*
X611323Y247710D01*
X611328Y247665D01*
Y247625D01*
X611333Y247580D01*
X611328Y247535D01*
Y247495D01*
X611323Y247450D01*
X611313Y247410D01*
X611308Y247370D01*
X611293Y247325D01*
X611283Y247285D01*
X611268Y247245D01*
X611248Y247205D01*
X611233Y247170D01*
X611213Y247130D01*
X611113Y246990D01*
X611083Y246960D01*
Y243530D01*
X611073Y243405D01*
X611033Y243280D01*
X610973Y243170D01*
X610893Y243070D01*
X610793Y242990D01*
X610683Y242930D01*
X610558Y242890D01*
X610433Y242880D01*
X610308Y242890D01*
X610183Y242930D01*
X610073Y242990D01*
X609973Y243070D01*
X609893Y243170D01*
X609833Y243280D01*
X609793Y243405D01*
X609783Y243530D01*
Y246960D01*
X609753Y246990D01*
X609653Y247130D01*
X609633Y247170D01*
X609618Y247205D01*
X609598Y247245D01*
X609583Y247285D01*
X609573Y247325D01*
X609558Y247370D01*
X609553Y247410D01*
X609543Y247450D01*
X609538Y247495D01*
Y247535D01*
X609533Y247580D01*
X609538Y247625D01*
Y247665D01*
X609543Y247710D01*
X609553Y247750D01*
X609558Y247790D01*
X609573Y247835D01*
X609583Y247875D01*
X609598Y247915D01*
X609618Y247955D01*
X609633Y247990D01*
X609653Y248030D01*
X609753Y248170D01*
X609783Y248200D01*
Y249330D01*
X609793Y249455D01*
X609833Y249580D01*
X609893Y249690D01*
X609973Y249790D01*
X610073Y249870D01*
X610183Y249930D01*
X610308Y249970D01*
X610433Y249980D01*
G37*
G36*
G01X615158D02*
X615283Y249970D01*
X615408Y249930D01*
X615518Y249870D01*
X615618Y249790D01*
X615698Y249690D01*
X615758Y249580D01*
X615798Y249455D01*
X615808Y249330D01*
Y248200D01*
X615838Y248170D01*
X615938Y248030D01*
X615958Y247990D01*
X615973Y247955D01*
X615993Y247915D01*
X616008Y247875D01*
X616018Y247835D01*
X616033Y247790D01*
X616038Y247750D01*
X616048Y247710D01*
X616053Y247665D01*
Y247625D01*
X616058Y247580D01*
X616053Y247535D01*
Y247495D01*
X616048Y247450D01*
X616038Y247410D01*
X616033Y247370D01*
X616018Y247325D01*
X616008Y247285D01*
X615993Y247245D01*
X615973Y247205D01*
X615958Y247170D01*
X615938Y247130D01*
X615838Y246990D01*
X615808Y246960D01*
Y243530D01*
X615798Y243405D01*
X615758Y243280D01*
X615698Y243170D01*
X615618Y243070D01*
X615518Y242990D01*
X615408Y242930D01*
X615283Y242890D01*
X615158Y242880D01*
X615033Y242890D01*
X614908Y242930D01*
X614798Y242990D01*
X614698Y243070D01*
X614618Y243170D01*
X614558Y243280D01*
X614518Y243405D01*
X614508Y243530D01*
Y246960D01*
X614478Y246990D01*
X614378Y247130D01*
X614358Y247170D01*
X614343Y247205D01*
X614323Y247245D01*
X614308Y247285D01*
X614298Y247325D01*
X614283Y247370D01*
X614278Y247410D01*
X614268Y247450D01*
X614263Y247495D01*
Y247535D01*
X614258Y247580D01*
X614263Y247625D01*
Y247665D01*
X614268Y247710D01*
X614278Y247750D01*
X614283Y247790D01*
X614298Y247835D01*
X614308Y247875D01*
X614323Y247915D01*
X614343Y247955D01*
X614358Y247990D01*
X614378Y248030D01*
X614478Y248170D01*
X614508Y248200D01*
Y249330D01*
X614518Y249455D01*
X614558Y249580D01*
X614618Y249690D01*
X614698Y249790D01*
X614798Y249870D01*
X614908Y249930D01*
X615033Y249970D01*
X615158Y249980D01*
G37*
G36*
G01X619882D02*
X620007Y249970D01*
X620132Y249930D01*
X620242Y249870D01*
X620342Y249790D01*
X620422Y249690D01*
X620482Y249580D01*
X620522Y249455D01*
X620532Y249330D01*
Y248200D01*
X620562Y248170D01*
X620662Y248030D01*
X620682Y247990D01*
X620697Y247955D01*
X620717Y247915D01*
X620732Y247875D01*
X620742Y247835D01*
X620757Y247790D01*
X620762Y247750D01*
X620772Y247710D01*
X620777Y247665D01*
Y247625D01*
X620782Y247580D01*
X620777Y247535D01*
Y247495D01*
X620772Y247450D01*
X620762Y247410D01*
X620757Y247370D01*
X620742Y247325D01*
X620732Y247285D01*
X620717Y247245D01*
X620697Y247205D01*
X620682Y247170D01*
X620662Y247130D01*
X620562Y246990D01*
X620532Y246960D01*
Y243530D01*
X620522Y243405D01*
X620482Y243280D01*
X620422Y243170D01*
X620342Y243070D01*
X620242Y242990D01*
X620132Y242930D01*
X620007Y242890D01*
X619882Y242880D01*
X619757Y242890D01*
X619632Y242930D01*
X619522Y242990D01*
X619422Y243070D01*
X619342Y243170D01*
X619282Y243280D01*
X619242Y243405D01*
X619232Y243530D01*
Y246960D01*
X619202Y246990D01*
X619102Y247130D01*
X619082Y247170D01*
X619067Y247205D01*
X619047Y247245D01*
X619032Y247285D01*
X619022Y247325D01*
X619007Y247370D01*
X619002Y247410D01*
X618992Y247450D01*
X618987Y247495D01*
Y247535D01*
X618982Y247580D01*
X618987Y247625D01*
Y247665D01*
X618992Y247710D01*
X619002Y247750D01*
X619007Y247790D01*
X619022Y247835D01*
X619032Y247875D01*
X619047Y247915D01*
X619067Y247955D01*
X619082Y247990D01*
X619102Y248030D01*
X619202Y248170D01*
X619232Y248200D01*
Y249330D01*
X619242Y249455D01*
X619282Y249580D01*
X619342Y249690D01*
X619422Y249790D01*
X619522Y249870D01*
X619632Y249930D01*
X619757Y249970D01*
X619882Y249980D01*
G37*
G36*
G01X624607D02*
X624732Y249970D01*
X624857Y249930D01*
X624967Y249870D01*
X625067Y249790D01*
X625147Y249690D01*
X625207Y249580D01*
X625247Y249455D01*
X625257Y249330D01*
Y248200D01*
X625287Y248170D01*
X625387Y248030D01*
X625407Y247990D01*
X625422Y247955D01*
X625442Y247915D01*
X625457Y247875D01*
X625467Y247835D01*
X625482Y247790D01*
X625487Y247750D01*
X625497Y247710D01*
X625502Y247665D01*
Y247625D01*
X625507Y247580D01*
X625502Y247535D01*
Y247495D01*
X625497Y247450D01*
X625487Y247410D01*
X625482Y247370D01*
X625467Y247325D01*
X625457Y247285D01*
X625442Y247245D01*
X625422Y247205D01*
X625407Y247170D01*
X625387Y247130D01*
X625287Y246990D01*
X625257Y246960D01*
Y243530D01*
X625247Y243405D01*
X625207Y243280D01*
X625147Y243170D01*
X625067Y243070D01*
X624967Y242990D01*
X624857Y242930D01*
X624732Y242890D01*
X624607Y242880D01*
X624482Y242890D01*
X624357Y242930D01*
X624247Y242990D01*
X624147Y243070D01*
X624067Y243170D01*
X624007Y243280D01*
X623967Y243405D01*
X623957Y243530D01*
Y246960D01*
X623927Y246990D01*
X623827Y247130D01*
X623807Y247170D01*
X623792Y247205D01*
X623772Y247245D01*
X623757Y247285D01*
X623747Y247325D01*
X623732Y247370D01*
X623727Y247410D01*
X623717Y247450D01*
X623712Y247495D01*
Y247535D01*
X623707Y247580D01*
X623712Y247625D01*
Y247665D01*
X623717Y247710D01*
X623727Y247750D01*
X623732Y247790D01*
X623747Y247835D01*
X623757Y247875D01*
X623772Y247915D01*
X623792Y247955D01*
X623807Y247990D01*
X623827Y248030D01*
X623927Y248170D01*
X623957Y248200D01*
Y249330D01*
X623967Y249455D01*
X624007Y249580D01*
X624067Y249690D01*
X624147Y249790D01*
X624247Y249870D01*
X624357Y249930D01*
X624482Y249970D01*
X624607Y249980D01*
G37*
G36*
G01X629331D02*
X629456Y249970D01*
X629581Y249930D01*
X629691Y249870D01*
X629791Y249790D01*
X629871Y249690D01*
X629931Y249580D01*
X629971Y249455D01*
X629981Y249330D01*
Y248200D01*
X630011Y248170D01*
X630111Y248030D01*
X630131Y247990D01*
X630146Y247955D01*
X630166Y247915D01*
X630181Y247875D01*
X630191Y247835D01*
X630206Y247790D01*
X630211Y247750D01*
X630221Y247710D01*
X630226Y247665D01*
Y247625D01*
X630231Y247580D01*
X630226Y247535D01*
Y247495D01*
X630221Y247450D01*
X630211Y247410D01*
X630206Y247370D01*
X630191Y247325D01*
X630181Y247285D01*
X630166Y247245D01*
X630146Y247205D01*
X630131Y247170D01*
X630111Y247130D01*
X630011Y246990D01*
X629981Y246960D01*
Y243530D01*
X629971Y243405D01*
X629931Y243280D01*
X629871Y243170D01*
X629791Y243070D01*
X629691Y242990D01*
X629581Y242930D01*
X629456Y242890D01*
X629331Y242880D01*
X629206Y242890D01*
X629081Y242930D01*
X628971Y242990D01*
X628871Y243070D01*
X628791Y243170D01*
X628731Y243280D01*
X628691Y243405D01*
X628681Y243530D01*
Y246960D01*
X628651Y246990D01*
X628551Y247130D01*
X628531Y247170D01*
X628516Y247205D01*
X628496Y247245D01*
X628481Y247285D01*
X628471Y247325D01*
X628456Y247370D01*
X628451Y247410D01*
X628441Y247450D01*
X628436Y247495D01*
Y247535D01*
X628431Y247580D01*
X628436Y247625D01*
Y247665D01*
X628441Y247710D01*
X628451Y247750D01*
X628456Y247790D01*
X628471Y247835D01*
X628481Y247875D01*
X628496Y247915D01*
X628516Y247955D01*
X628531Y247990D01*
X628551Y248030D01*
X628651Y248170D01*
X628681Y248200D01*
Y249330D01*
X628691Y249455D01*
X628731Y249580D01*
X628791Y249690D01*
X628871Y249790D01*
X628971Y249870D01*
X629081Y249930D01*
X629206Y249970D01*
X629331Y249980D01*
G37*
G36*
G01X634055D02*
X634180Y249970D01*
X634305Y249930D01*
X634415Y249870D01*
X634515Y249790D01*
X634595Y249690D01*
X634655Y249580D01*
X634695Y249455D01*
X634705Y249330D01*
Y248200D01*
X634735Y248170D01*
X634835Y248030D01*
X634855Y247990D01*
X634870Y247955D01*
X634890Y247915D01*
X634905Y247875D01*
X634915Y247835D01*
X634930Y247790D01*
X634935Y247750D01*
X634945Y247710D01*
X634950Y247665D01*
Y247625D01*
X634955Y247580D01*
X634950Y247535D01*
Y247495D01*
X634945Y247450D01*
X634935Y247410D01*
X634930Y247370D01*
X634915Y247325D01*
X634905Y247285D01*
X634890Y247245D01*
X634870Y247205D01*
X634855Y247170D01*
X634835Y247130D01*
X634735Y246990D01*
X634705Y246960D01*
Y243530D01*
X634695Y243405D01*
X634655Y243280D01*
X634595Y243170D01*
X634515Y243070D01*
X634415Y242990D01*
X634305Y242930D01*
X634180Y242890D01*
X634055Y242880D01*
X633930Y242890D01*
X633805Y242930D01*
X633695Y242990D01*
X633595Y243070D01*
X633515Y243170D01*
X633455Y243280D01*
X633415Y243405D01*
X633405Y243530D01*
Y246960D01*
X633375Y246990D01*
X633275Y247130D01*
X633255Y247170D01*
X633240Y247205D01*
X633220Y247245D01*
X633205Y247285D01*
X633195Y247325D01*
X633180Y247370D01*
X633175Y247410D01*
X633165Y247450D01*
X633160Y247495D01*
Y247535D01*
X633155Y247580D01*
X633160Y247625D01*
Y247665D01*
X633165Y247710D01*
X633175Y247750D01*
X633180Y247790D01*
X633195Y247835D01*
X633205Y247875D01*
X633220Y247915D01*
X633240Y247955D01*
X633255Y247990D01*
X633275Y248030D01*
X633375Y248170D01*
X633405Y248200D01*
Y249330D01*
X633415Y249455D01*
X633455Y249580D01*
X633515Y249690D01*
X633595Y249790D01*
X633695Y249870D01*
X633805Y249930D01*
X633930Y249970D01*
X634055Y249980D01*
G37*
G36*
G01X638780D02*
X638905Y249970D01*
X639030Y249930D01*
X639140Y249870D01*
X639240Y249790D01*
X639320Y249690D01*
X639380Y249580D01*
X639420Y249455D01*
X639430Y249330D01*
Y248200D01*
X639460Y248170D01*
X639560Y248030D01*
X639580Y247990D01*
X639595Y247955D01*
X639615Y247915D01*
X639630Y247875D01*
X639640Y247835D01*
X639655Y247790D01*
X639660Y247750D01*
X639670Y247710D01*
X639675Y247665D01*
Y247625D01*
X639680Y247580D01*
X639675Y247535D01*
Y247495D01*
X639670Y247450D01*
X639660Y247410D01*
X639655Y247370D01*
X639640Y247325D01*
X639630Y247285D01*
X639615Y247245D01*
X639595Y247205D01*
X639580Y247170D01*
X639560Y247130D01*
X639460Y246990D01*
X639430Y246960D01*
Y243530D01*
X639420Y243405D01*
X639380Y243280D01*
X639320Y243170D01*
X639240Y243070D01*
X639140Y242990D01*
X639030Y242930D01*
X638905Y242890D01*
X638780Y242880D01*
X638655Y242890D01*
X638530Y242930D01*
X638420Y242990D01*
X638320Y243070D01*
X638240Y243170D01*
X638180Y243280D01*
X638140Y243405D01*
X638130Y243530D01*
Y246960D01*
X638100Y246990D01*
X638000Y247130D01*
X637980Y247170D01*
X637965Y247205D01*
X637945Y247245D01*
X637930Y247285D01*
X637920Y247325D01*
X637905Y247370D01*
X637900Y247410D01*
X637890Y247450D01*
X637885Y247495D01*
Y247535D01*
X637880Y247580D01*
X637885Y247625D01*
Y247665D01*
X637890Y247710D01*
X637900Y247750D01*
X637905Y247790D01*
X637920Y247835D01*
X637930Y247875D01*
X637945Y247915D01*
X637965Y247955D01*
X637980Y247990D01*
X638000Y248030D01*
X638100Y248170D01*
X638130Y248200D01*
Y249330D01*
X638140Y249455D01*
X638180Y249580D01*
X638240Y249690D01*
X638320Y249790D01*
X638420Y249870D01*
X638530Y249930D01*
X638655Y249970D01*
X638780Y249980D01*
G37*
G36*
G01X643504D02*
X643629Y249970D01*
X643754Y249930D01*
X643864Y249870D01*
X643964Y249790D01*
X644044Y249690D01*
X644104Y249580D01*
X644144Y249455D01*
X644154Y249330D01*
Y248200D01*
X644184Y248170D01*
X644284Y248030D01*
X644304Y247990D01*
X644319Y247955D01*
X644339Y247915D01*
X644354Y247875D01*
X644364Y247835D01*
X644379Y247790D01*
X644384Y247750D01*
X644394Y247710D01*
X644399Y247665D01*
Y247625D01*
X644404Y247580D01*
X644399Y247535D01*
Y247495D01*
X644394Y247450D01*
X644384Y247410D01*
X644379Y247370D01*
X644364Y247325D01*
X644354Y247285D01*
X644339Y247245D01*
X644319Y247205D01*
X644304Y247170D01*
X644284Y247130D01*
X644184Y246990D01*
X644154Y246960D01*
Y243530D01*
X644144Y243405D01*
X644104Y243280D01*
X644044Y243170D01*
X643964Y243070D01*
X643864Y242990D01*
X643754Y242930D01*
X643629Y242890D01*
X643504Y242880D01*
X643379Y242890D01*
X643254Y242930D01*
X643144Y242990D01*
X643044Y243070D01*
X642964Y243170D01*
X642904Y243280D01*
X642864Y243405D01*
X642854Y243530D01*
Y246960D01*
X642824Y246990D01*
X642724Y247130D01*
X642704Y247170D01*
X642689Y247205D01*
X642669Y247245D01*
X642654Y247285D01*
X642644Y247325D01*
X642629Y247370D01*
X642624Y247410D01*
X642614Y247450D01*
X642609Y247495D01*
Y247535D01*
X642604Y247580D01*
X642609Y247625D01*
Y247665D01*
X642614Y247710D01*
X642624Y247750D01*
X642629Y247790D01*
X642644Y247835D01*
X642654Y247875D01*
X642669Y247915D01*
X642689Y247955D01*
X642704Y247990D01*
X642724Y248030D01*
X642824Y248170D01*
X642854Y248200D01*
Y249330D01*
X642864Y249455D01*
X642904Y249580D01*
X642964Y249690D01*
X643044Y249790D01*
X643144Y249870D01*
X643254Y249930D01*
X643379Y249970D01*
X643504Y249980D01*
G37*
G36*
G01X648229D02*
X648354Y249970D01*
X648479Y249930D01*
X648589Y249870D01*
X648689Y249790D01*
X648769Y249690D01*
X648829Y249580D01*
X648869Y249455D01*
X648879Y249330D01*
Y248200D01*
X648909Y248170D01*
X649009Y248030D01*
X649029Y247990D01*
X649044Y247955D01*
X649064Y247915D01*
X649079Y247875D01*
X649089Y247835D01*
X649104Y247790D01*
X649109Y247750D01*
X649119Y247710D01*
X649124Y247665D01*
Y247625D01*
X649129Y247580D01*
X649124Y247535D01*
Y247495D01*
X649119Y247450D01*
X649109Y247410D01*
X649104Y247370D01*
X649089Y247325D01*
X649079Y247285D01*
X649064Y247245D01*
X649044Y247205D01*
X649029Y247170D01*
X649009Y247130D01*
X648909Y246990D01*
X648879Y246960D01*
Y243530D01*
X648869Y243405D01*
X648829Y243280D01*
X648769Y243170D01*
X648689Y243070D01*
X648589Y242990D01*
X648479Y242930D01*
X648354Y242890D01*
X648229Y242880D01*
X648104Y242890D01*
X647979Y242930D01*
X647869Y242990D01*
X647769Y243070D01*
X647689Y243170D01*
X647629Y243280D01*
X647589Y243405D01*
X647579Y243530D01*
Y246960D01*
X647549Y246990D01*
X647449Y247130D01*
X647429Y247170D01*
X647414Y247205D01*
X647394Y247245D01*
X647379Y247285D01*
X647369Y247325D01*
X647354Y247370D01*
X647349Y247410D01*
X647339Y247450D01*
X647334Y247495D01*
Y247535D01*
X647329Y247580D01*
X647334Y247625D01*
Y247665D01*
X647339Y247710D01*
X647349Y247750D01*
X647354Y247790D01*
X647369Y247835D01*
X647379Y247875D01*
X647394Y247915D01*
X647414Y247955D01*
X647429Y247990D01*
X647449Y248030D01*
X647549Y248170D01*
X647579Y248200D01*
Y249330D01*
X647589Y249455D01*
X647629Y249580D01*
X647689Y249690D01*
X647769Y249790D01*
X647869Y249870D01*
X647979Y249930D01*
X648104Y249970D01*
X648229Y249980D01*
G37*
G36*
G01X652953D02*
X653078Y249970D01*
X653203Y249930D01*
X653313Y249870D01*
X653413Y249790D01*
X653493Y249690D01*
X653553Y249580D01*
X653593Y249455D01*
X653603Y249330D01*
Y248200D01*
X653633Y248170D01*
X653733Y248030D01*
X653753Y247990D01*
X653768Y247955D01*
X653788Y247915D01*
X653803Y247875D01*
X653813Y247835D01*
X653828Y247790D01*
X653833Y247750D01*
X653843Y247710D01*
X653848Y247665D01*
Y247625D01*
X653853Y247580D01*
X653848Y247535D01*
Y247495D01*
X653843Y247450D01*
X653833Y247410D01*
X653828Y247370D01*
X653813Y247325D01*
X653803Y247285D01*
X653788Y247245D01*
X653768Y247205D01*
X653753Y247170D01*
X653733Y247130D01*
X653633Y246990D01*
X653603Y246960D01*
Y243530D01*
X653593Y243405D01*
X653553Y243280D01*
X653493Y243170D01*
X653413Y243070D01*
X653313Y242990D01*
X653203Y242930D01*
X653078Y242890D01*
X652953Y242880D01*
X652828Y242890D01*
X652703Y242930D01*
X652593Y242990D01*
X652493Y243070D01*
X652413Y243170D01*
X652353Y243280D01*
X652313Y243405D01*
X652303Y243530D01*
Y246960D01*
X652273Y246990D01*
X652173Y247130D01*
X652153Y247170D01*
X652138Y247205D01*
X652118Y247245D01*
X652103Y247285D01*
X652093Y247325D01*
X652078Y247370D01*
X652073Y247410D01*
X652063Y247450D01*
X652058Y247495D01*
Y247535D01*
X652053Y247580D01*
X652058Y247625D01*
Y247665D01*
X652063Y247710D01*
X652073Y247750D01*
X652078Y247790D01*
X652093Y247835D01*
X652103Y247875D01*
X652118Y247915D01*
X652138Y247955D01*
X652153Y247990D01*
X652173Y248030D01*
X652273Y248170D01*
X652303Y248200D01*
Y249330D01*
X652313Y249455D01*
X652353Y249580D01*
X652413Y249690D01*
X652493Y249790D01*
X652593Y249870D01*
X652703Y249930D01*
X652828Y249970D01*
X652953Y249980D01*
G37*
G36*
G01X667126D02*
X667251Y249970D01*
X667376Y249930D01*
X667486Y249870D01*
X667586Y249790D01*
X667666Y249690D01*
X667726Y249580D01*
X667766Y249455D01*
X667776Y249330D01*
Y248200D01*
X667806Y248170D01*
X667906Y248030D01*
X667926Y247990D01*
X667941Y247955D01*
X667961Y247915D01*
X667976Y247875D01*
X667986Y247835D01*
X668001Y247790D01*
X668006Y247750D01*
X668016Y247710D01*
X668021Y247665D01*
Y247625D01*
X668026Y247580D01*
X668021Y247535D01*
Y247495D01*
X668016Y247450D01*
X668006Y247410D01*
X668001Y247370D01*
X667986Y247325D01*
X667976Y247285D01*
X667961Y247245D01*
X667941Y247205D01*
X667926Y247170D01*
X667906Y247130D01*
X667806Y246990D01*
X667776Y246960D01*
Y243530D01*
X667766Y243405D01*
X667726Y243280D01*
X667666Y243170D01*
X667586Y243070D01*
X667486Y242990D01*
X667376Y242930D01*
X667251Y242890D01*
X667126Y242880D01*
X667001Y242890D01*
X666876Y242930D01*
X666766Y242990D01*
X666666Y243070D01*
X666586Y243170D01*
X666526Y243280D01*
X666486Y243405D01*
X666476Y243530D01*
Y246960D01*
X666446Y246990D01*
X666346Y247130D01*
X666326Y247170D01*
X666311Y247205D01*
X666291Y247245D01*
X666276Y247285D01*
X666266Y247325D01*
X666251Y247370D01*
X666246Y247410D01*
X666236Y247450D01*
X666231Y247495D01*
Y247535D01*
X666226Y247580D01*
X666231Y247625D01*
Y247665D01*
X666236Y247710D01*
X666246Y247750D01*
X666251Y247790D01*
X666266Y247835D01*
X666276Y247875D01*
X666291Y247915D01*
X666311Y247955D01*
X666326Y247990D01*
X666346Y248030D01*
X666446Y248170D01*
X666476Y248200D01*
Y249330D01*
X666486Y249455D01*
X666526Y249580D01*
X666586Y249690D01*
X666666Y249790D01*
X666766Y249870D01*
X666876Y249930D01*
X667001Y249970D01*
X667126Y249980D01*
G37*
G36*
G01X671851D02*
X671976Y249970D01*
X672101Y249930D01*
X672211Y249870D01*
X672311Y249790D01*
X672391Y249690D01*
X672451Y249580D01*
X672491Y249455D01*
X672501Y249330D01*
Y248200D01*
X672531Y248170D01*
X672631Y248030D01*
X672651Y247990D01*
X672666Y247955D01*
X672686Y247915D01*
X672701Y247875D01*
X672711Y247835D01*
X672726Y247790D01*
X672731Y247750D01*
X672741Y247710D01*
X672746Y247665D01*
Y247625D01*
X672751Y247580D01*
X672746Y247535D01*
Y247495D01*
X672741Y247450D01*
X672731Y247410D01*
X672726Y247370D01*
X672711Y247325D01*
X672701Y247285D01*
X672686Y247245D01*
X672666Y247205D01*
X672651Y247170D01*
X672631Y247130D01*
X672531Y246990D01*
X672501Y246960D01*
Y243530D01*
X672491Y243405D01*
X672451Y243280D01*
X672391Y243170D01*
X672311Y243070D01*
X672211Y242990D01*
X672101Y242930D01*
X671976Y242890D01*
X671851Y242880D01*
X671726Y242890D01*
X671601Y242930D01*
X671491Y242990D01*
X671391Y243070D01*
X671311Y243170D01*
X671251Y243280D01*
X671211Y243405D01*
X671201Y243530D01*
Y246960D01*
X671171Y246990D01*
X671071Y247130D01*
X671051Y247170D01*
X671036Y247205D01*
X671016Y247245D01*
X671001Y247285D01*
X670991Y247325D01*
X670976Y247370D01*
X670971Y247410D01*
X670961Y247450D01*
X670956Y247495D01*
Y247535D01*
X670951Y247580D01*
X670956Y247625D01*
Y247665D01*
X670961Y247710D01*
X670971Y247750D01*
X670976Y247790D01*
X670991Y247835D01*
X671001Y247875D01*
X671016Y247915D01*
X671036Y247955D01*
X671051Y247990D01*
X671071Y248030D01*
X671171Y248170D01*
X671201Y248200D01*
Y249330D01*
X671211Y249455D01*
X671251Y249580D01*
X671311Y249690D01*
X671391Y249790D01*
X671491Y249870D01*
X671601Y249930D01*
X671726Y249970D01*
X671851Y249980D01*
G37*
G36*
G01X676575D02*
X676700Y249970D01*
X676825Y249930D01*
X676935Y249870D01*
X677035Y249790D01*
X677115Y249690D01*
X677175Y249580D01*
X677215Y249455D01*
X677225Y249330D01*
Y248200D01*
X677255Y248170D01*
X677355Y248030D01*
X677375Y247990D01*
X677390Y247955D01*
X677410Y247915D01*
X677425Y247875D01*
X677435Y247835D01*
X677450Y247790D01*
X677455Y247750D01*
X677465Y247710D01*
X677470Y247665D01*
Y247625D01*
X677475Y247580D01*
X677470Y247535D01*
Y247495D01*
X677465Y247450D01*
X677455Y247410D01*
X677450Y247370D01*
X677435Y247325D01*
X677425Y247285D01*
X677410Y247245D01*
X677390Y247205D01*
X677375Y247170D01*
X677355Y247130D01*
X677255Y246990D01*
X677225Y246960D01*
Y243530D01*
X677215Y243405D01*
X677175Y243280D01*
X677115Y243170D01*
X677035Y243070D01*
X676935Y242990D01*
X676825Y242930D01*
X676700Y242890D01*
X676575Y242880D01*
X676450Y242890D01*
X676325Y242930D01*
X676215Y242990D01*
X676115Y243070D01*
X676035Y243170D01*
X675975Y243280D01*
X675935Y243405D01*
X675925Y243530D01*
Y246960D01*
X675895Y246990D01*
X675795Y247130D01*
X675775Y247170D01*
X675760Y247205D01*
X675740Y247245D01*
X675725Y247285D01*
X675715Y247325D01*
X675700Y247370D01*
X675695Y247410D01*
X675685Y247450D01*
X675680Y247495D01*
Y247535D01*
X675675Y247580D01*
X675680Y247625D01*
Y247665D01*
X675685Y247710D01*
X675695Y247750D01*
X675700Y247790D01*
X675715Y247835D01*
X675725Y247875D01*
X675740Y247915D01*
X675760Y247955D01*
X675775Y247990D01*
X675795Y248030D01*
X675895Y248170D01*
X675925Y248200D01*
Y249330D01*
X675935Y249455D01*
X675975Y249580D01*
X676035Y249690D01*
X676115Y249790D01*
X676215Y249870D01*
X676325Y249930D01*
X676450Y249970D01*
X676575Y249980D01*
G37*
G36*
G01X681299D02*
X681424Y249970D01*
X681549Y249930D01*
X681659Y249870D01*
X681759Y249790D01*
X681839Y249690D01*
X681899Y249580D01*
X681939Y249455D01*
X681949Y249330D01*
Y248200D01*
X681979Y248170D01*
X682079Y248030D01*
X682099Y247990D01*
X682114Y247955D01*
X682134Y247915D01*
X682149Y247875D01*
X682159Y247835D01*
X682174Y247790D01*
X682179Y247750D01*
X682189Y247710D01*
X682194Y247665D01*
Y247625D01*
X682199Y247580D01*
X682194Y247535D01*
Y247495D01*
X682189Y247450D01*
X682179Y247410D01*
X682174Y247370D01*
X682159Y247325D01*
X682149Y247285D01*
X682134Y247245D01*
X682114Y247205D01*
X682099Y247170D01*
X682079Y247130D01*
X681979Y246990D01*
X681949Y246960D01*
Y243530D01*
X681939Y243405D01*
X681899Y243280D01*
X681839Y243170D01*
X681759Y243070D01*
X681659Y242990D01*
X681549Y242930D01*
X681424Y242890D01*
X681299Y242880D01*
X681174Y242890D01*
X681049Y242930D01*
X680939Y242990D01*
X680839Y243070D01*
X680759Y243170D01*
X680699Y243280D01*
X680659Y243405D01*
X680649Y243530D01*
Y246960D01*
X680619Y246990D01*
X680519Y247130D01*
X680499Y247170D01*
X680484Y247205D01*
X680464Y247245D01*
X680449Y247285D01*
X680439Y247325D01*
X680424Y247370D01*
X680419Y247410D01*
X680409Y247450D01*
X680404Y247495D01*
Y247535D01*
X680399Y247580D01*
X680404Y247625D01*
Y247665D01*
X680409Y247710D01*
X680419Y247750D01*
X680424Y247790D01*
X680439Y247835D01*
X680449Y247875D01*
X680464Y247915D01*
X680484Y247955D01*
X680499Y247990D01*
X680519Y248030D01*
X680619Y248170D01*
X680649Y248200D01*
Y249330D01*
X680659Y249455D01*
X680699Y249580D01*
X680759Y249690D01*
X680839Y249790D01*
X680939Y249870D01*
X681049Y249930D01*
X681174Y249970D01*
X681299Y249980D01*
G37*
G36*
G01X686024D02*
X686149Y249970D01*
X686274Y249930D01*
X686384Y249870D01*
X686484Y249790D01*
X686564Y249690D01*
X686624Y249580D01*
X686664Y249455D01*
X686674Y249330D01*
Y248200D01*
X686704Y248170D01*
X686804Y248030D01*
X686824Y247990D01*
X686839Y247955D01*
X686859Y247915D01*
X686874Y247875D01*
X686884Y247835D01*
X686899Y247790D01*
X686904Y247750D01*
X686914Y247710D01*
X686919Y247665D01*
Y247625D01*
X686924Y247580D01*
X686919Y247535D01*
Y247495D01*
X686914Y247450D01*
X686904Y247410D01*
X686899Y247370D01*
X686884Y247325D01*
X686874Y247285D01*
X686859Y247245D01*
X686839Y247205D01*
X686824Y247170D01*
X686804Y247130D01*
X686704Y246990D01*
X686674Y246960D01*
Y243530D01*
X686664Y243405D01*
X686624Y243280D01*
X686564Y243170D01*
X686484Y243070D01*
X686384Y242990D01*
X686274Y242930D01*
X686149Y242890D01*
X686024Y242880D01*
X685899Y242890D01*
X685774Y242930D01*
X685664Y242990D01*
X685564Y243070D01*
X685484Y243170D01*
X685424Y243280D01*
X685384Y243405D01*
X685374Y243530D01*
Y246960D01*
X685344Y246990D01*
X685244Y247130D01*
X685224Y247170D01*
X685209Y247205D01*
X685189Y247245D01*
X685174Y247285D01*
X685164Y247325D01*
X685149Y247370D01*
X685144Y247410D01*
X685134Y247450D01*
X685129Y247495D01*
Y247535D01*
X685124Y247580D01*
X685129Y247625D01*
Y247665D01*
X685134Y247710D01*
X685144Y247750D01*
X685149Y247790D01*
X685164Y247835D01*
X685174Y247875D01*
X685189Y247915D01*
X685209Y247955D01*
X685224Y247990D01*
X685244Y248030D01*
X685344Y248170D01*
X685374Y248200D01*
Y249330D01*
X685384Y249455D01*
X685424Y249580D01*
X685484Y249690D01*
X685564Y249790D01*
X685664Y249870D01*
X685774Y249930D01*
X685899Y249970D01*
X686024Y249980D01*
G37*
G36*
G01X690748D02*
X690873Y249970D01*
X690998Y249930D01*
X691108Y249870D01*
X691208Y249790D01*
X691288Y249690D01*
X691348Y249580D01*
X691388Y249455D01*
X691398Y249330D01*
Y248200D01*
X691428Y248170D01*
X691528Y248030D01*
X691548Y247990D01*
X691563Y247955D01*
X691583Y247915D01*
X691598Y247875D01*
X691608Y247835D01*
X691623Y247790D01*
X691628Y247750D01*
X691638Y247710D01*
X691643Y247665D01*
Y247625D01*
X691648Y247580D01*
X691643Y247535D01*
Y247495D01*
X691638Y247450D01*
X691628Y247410D01*
X691623Y247370D01*
X691608Y247325D01*
X691598Y247285D01*
X691583Y247245D01*
X691563Y247205D01*
X691548Y247170D01*
X691528Y247130D01*
X691428Y246990D01*
X691398Y246960D01*
Y243530D01*
X691388Y243405D01*
X691348Y243280D01*
X691288Y243170D01*
X691208Y243070D01*
X691108Y242990D01*
X690998Y242930D01*
X690873Y242890D01*
X690748Y242880D01*
X690623Y242890D01*
X690498Y242930D01*
X690388Y242990D01*
X690288Y243070D01*
X690208Y243170D01*
X690148Y243280D01*
X690108Y243405D01*
X690098Y243530D01*
Y246960D01*
X690068Y246990D01*
X689968Y247130D01*
X689948Y247170D01*
X689933Y247205D01*
X689913Y247245D01*
X689898Y247285D01*
X689888Y247325D01*
X689873Y247370D01*
X689868Y247410D01*
X689858Y247450D01*
X689853Y247495D01*
Y247535D01*
X689848Y247580D01*
X689853Y247625D01*
Y247665D01*
X689858Y247710D01*
X689868Y247750D01*
X689873Y247790D01*
X689888Y247835D01*
X689898Y247875D01*
X689913Y247915D01*
X689933Y247955D01*
X689948Y247990D01*
X689968Y248030D01*
X690068Y248170D01*
X690098Y248200D01*
Y249330D01*
X690108Y249455D01*
X690148Y249580D01*
X690208Y249690D01*
X690288Y249790D01*
X690388Y249870D01*
X690498Y249930D01*
X690623Y249970D01*
X690748Y249980D01*
G37*
G36*
G01X695473D02*
X695598Y249970D01*
X695723Y249930D01*
X695833Y249870D01*
X695933Y249790D01*
X696013Y249690D01*
X696073Y249580D01*
X696113Y249455D01*
X696123Y249330D01*
Y248200D01*
X696153Y248170D01*
X696253Y248030D01*
X696273Y247990D01*
X696288Y247955D01*
X696308Y247915D01*
X696323Y247875D01*
X696333Y247835D01*
X696348Y247790D01*
X696353Y247750D01*
X696363Y247710D01*
X696368Y247665D01*
Y247625D01*
X696373Y247580D01*
X696368Y247535D01*
Y247495D01*
X696363Y247450D01*
X696353Y247410D01*
X696348Y247370D01*
X696333Y247325D01*
X696323Y247285D01*
X696308Y247245D01*
X696288Y247205D01*
X696273Y247170D01*
X696253Y247130D01*
X696153Y246990D01*
X696123Y246960D01*
Y243530D01*
X696113Y243405D01*
X696073Y243280D01*
X696013Y243170D01*
X695933Y243070D01*
X695833Y242990D01*
X695723Y242930D01*
X695598Y242890D01*
X695473Y242880D01*
X695348Y242890D01*
X695223Y242930D01*
X695113Y242990D01*
X695013Y243070D01*
X694933Y243170D01*
X694873Y243280D01*
X694833Y243405D01*
X694823Y243530D01*
Y246960D01*
X694793Y246990D01*
X694693Y247130D01*
X694673Y247170D01*
X694658Y247205D01*
X694638Y247245D01*
X694623Y247285D01*
X694613Y247325D01*
X694598Y247370D01*
X694593Y247410D01*
X694583Y247450D01*
X694578Y247495D01*
Y247535D01*
X694573Y247580D01*
X694578Y247625D01*
Y247665D01*
X694583Y247710D01*
X694593Y247750D01*
X694598Y247790D01*
X694613Y247835D01*
X694623Y247875D01*
X694638Y247915D01*
X694658Y247955D01*
X694673Y247990D01*
X694693Y248030D01*
X694793Y248170D01*
X694823Y248200D01*
Y249330D01*
X694833Y249455D01*
X694873Y249580D01*
X694933Y249690D01*
X695013Y249790D01*
X695113Y249870D01*
X695223Y249930D01*
X695348Y249970D01*
X695473Y249980D01*
G37*
G36*
G01X700197D02*
X700322Y249970D01*
X700447Y249930D01*
X700557Y249870D01*
X700657Y249790D01*
X700737Y249690D01*
X700797Y249580D01*
X700837Y249455D01*
X700847Y249330D01*
Y248200D01*
X700877Y248170D01*
X700977Y248030D01*
X700997Y247990D01*
X701012Y247955D01*
X701032Y247915D01*
X701047Y247875D01*
X701057Y247835D01*
X701072Y247790D01*
X701077Y247750D01*
X701087Y247710D01*
X701092Y247665D01*
Y247625D01*
X701097Y247580D01*
X701092Y247535D01*
Y247495D01*
X701087Y247450D01*
X701077Y247410D01*
X701072Y247370D01*
X701057Y247325D01*
X701047Y247285D01*
X701032Y247245D01*
X701012Y247205D01*
X700997Y247170D01*
X700977Y247130D01*
X700877Y246990D01*
X700847Y246960D01*
Y243530D01*
X700837Y243405D01*
X700797Y243280D01*
X700737Y243170D01*
X700657Y243070D01*
X700557Y242990D01*
X700447Y242930D01*
X700322Y242890D01*
X700197Y242880D01*
X700072Y242890D01*
X699947Y242930D01*
X699837Y242990D01*
X699737Y243070D01*
X699657Y243170D01*
X699597Y243280D01*
X699557Y243405D01*
X699547Y243530D01*
Y246960D01*
X699517Y246990D01*
X699417Y247130D01*
X699397Y247170D01*
X699382Y247205D01*
X699362Y247245D01*
X699347Y247285D01*
X699337Y247325D01*
X699322Y247370D01*
X699317Y247410D01*
X699307Y247450D01*
X699302Y247495D01*
Y247535D01*
X699297Y247580D01*
X699302Y247625D01*
Y247665D01*
X699307Y247710D01*
X699317Y247750D01*
X699322Y247790D01*
X699337Y247835D01*
X699347Y247875D01*
X699362Y247915D01*
X699382Y247955D01*
X699397Y247990D01*
X699417Y248030D01*
X699517Y248170D01*
X699547Y248200D01*
Y249330D01*
X699557Y249455D01*
X699597Y249580D01*
X699657Y249690D01*
X699737Y249790D01*
X699837Y249870D01*
X699947Y249930D01*
X700072Y249970D01*
X700197Y249980D01*
G37*
G36*
G01X704922D02*
X705047Y249970D01*
X705172Y249930D01*
X705282Y249870D01*
X705382Y249790D01*
X705462Y249690D01*
X705522Y249580D01*
X705562Y249455D01*
X705572Y249330D01*
Y248200D01*
X705602Y248170D01*
X705702Y248030D01*
X705722Y247990D01*
X705737Y247955D01*
X705757Y247915D01*
X705772Y247875D01*
X705782Y247835D01*
X705797Y247790D01*
X705802Y247750D01*
X705812Y247710D01*
X705817Y247665D01*
Y247625D01*
X705822Y247580D01*
X705817Y247535D01*
Y247495D01*
X705812Y247450D01*
X705802Y247410D01*
X705797Y247370D01*
X705782Y247325D01*
X705772Y247285D01*
X705757Y247245D01*
X705737Y247205D01*
X705722Y247170D01*
X705702Y247130D01*
X705602Y246990D01*
X705572Y246960D01*
Y243530D01*
X705562Y243405D01*
X705522Y243280D01*
X705462Y243170D01*
X705382Y243070D01*
X705282Y242990D01*
X705172Y242930D01*
X705047Y242890D01*
X704922Y242880D01*
X704797Y242890D01*
X704672Y242930D01*
X704562Y242990D01*
X704462Y243070D01*
X704382Y243170D01*
X704322Y243280D01*
X704282Y243405D01*
X704272Y243530D01*
Y246960D01*
X704242Y246990D01*
X704142Y247130D01*
X704122Y247170D01*
X704107Y247205D01*
X704087Y247245D01*
X704072Y247285D01*
X704062Y247325D01*
X704047Y247370D01*
X704042Y247410D01*
X704032Y247450D01*
X704027Y247495D01*
Y247535D01*
X704022Y247580D01*
X704027Y247625D01*
Y247665D01*
X704032Y247710D01*
X704042Y247750D01*
X704047Y247790D01*
X704062Y247835D01*
X704072Y247875D01*
X704087Y247915D01*
X704107Y247955D01*
X704122Y247990D01*
X704142Y248030D01*
X704242Y248170D01*
X704272Y248200D01*
Y249330D01*
X704282Y249455D01*
X704322Y249580D01*
X704382Y249690D01*
X704462Y249790D01*
X704562Y249870D01*
X704672Y249930D01*
X704797Y249970D01*
X704922Y249980D01*
G37*
G36*
G01X709646D02*
X709771Y249970D01*
X709896Y249930D01*
X710006Y249870D01*
X710106Y249790D01*
X710186Y249690D01*
X710246Y249580D01*
X710286Y249455D01*
X710296Y249330D01*
Y248200D01*
X710326Y248170D01*
X710426Y248030D01*
X710446Y247990D01*
X710461Y247955D01*
X710481Y247915D01*
X710496Y247875D01*
X710506Y247835D01*
X710521Y247790D01*
X710526Y247750D01*
X710536Y247710D01*
X710541Y247665D01*
Y247625D01*
X710546Y247580D01*
X710541Y247535D01*
Y247495D01*
X710536Y247450D01*
X710526Y247410D01*
X710521Y247370D01*
X710506Y247325D01*
X710496Y247285D01*
X710481Y247245D01*
X710461Y247205D01*
X710446Y247170D01*
X710426Y247130D01*
X710326Y246990D01*
X710296Y246960D01*
Y243530D01*
X710286Y243405D01*
X710246Y243280D01*
X710186Y243170D01*
X710106Y243070D01*
X710006Y242990D01*
X709896Y242930D01*
X709771Y242890D01*
X709646Y242880D01*
X709521Y242890D01*
X709396Y242930D01*
X709286Y242990D01*
X709186Y243070D01*
X709106Y243170D01*
X709046Y243280D01*
X709006Y243405D01*
X708996Y243530D01*
Y246960D01*
X708966Y246990D01*
X708866Y247130D01*
X708846Y247170D01*
X708831Y247205D01*
X708811Y247245D01*
X708796Y247285D01*
X708786Y247325D01*
X708771Y247370D01*
X708766Y247410D01*
X708756Y247450D01*
X708751Y247495D01*
Y247535D01*
X708746Y247580D01*
X708751Y247625D01*
Y247665D01*
X708756Y247710D01*
X708766Y247750D01*
X708771Y247790D01*
X708786Y247835D01*
X708796Y247875D01*
X708811Y247915D01*
X708831Y247955D01*
X708846Y247990D01*
X708866Y248030D01*
X708966Y248170D01*
X708996Y248200D01*
Y249330D01*
X709006Y249455D01*
X709046Y249580D01*
X709106Y249690D01*
X709186Y249790D01*
X709286Y249870D01*
X709396Y249930D01*
X709521Y249970D01*
X709646Y249980D01*
G37*
G36*
G01X714370D02*
X714495Y249970D01*
X714620Y249930D01*
X714730Y249870D01*
X714830Y249790D01*
X714910Y249690D01*
X714970Y249580D01*
X715010Y249455D01*
X715020Y249330D01*
Y248200D01*
X715050Y248170D01*
X715150Y248030D01*
X715170Y247990D01*
X715185Y247955D01*
X715205Y247915D01*
X715220Y247875D01*
X715230Y247835D01*
X715245Y247790D01*
X715250Y247750D01*
X715260Y247710D01*
X715265Y247665D01*
Y247625D01*
X715270Y247580D01*
X715265Y247535D01*
Y247495D01*
X715260Y247450D01*
X715250Y247410D01*
X715245Y247370D01*
X715230Y247325D01*
X715220Y247285D01*
X715205Y247245D01*
X715185Y247205D01*
X715170Y247170D01*
X715150Y247130D01*
X715050Y246990D01*
X715020Y246960D01*
Y243530D01*
X715010Y243405D01*
X714970Y243280D01*
X714910Y243170D01*
X714830Y243070D01*
X714730Y242990D01*
X714620Y242930D01*
X714495Y242890D01*
X714370Y242880D01*
X714245Y242890D01*
X714120Y242930D01*
X714010Y242990D01*
X713910Y243070D01*
X713830Y243170D01*
X713770Y243280D01*
X713730Y243405D01*
X713720Y243530D01*
Y246960D01*
X713690Y246990D01*
X713590Y247130D01*
X713570Y247170D01*
X713555Y247205D01*
X713535Y247245D01*
X713520Y247285D01*
X713510Y247325D01*
X713495Y247370D01*
X713490Y247410D01*
X713480Y247450D01*
X713475Y247495D01*
Y247535D01*
X713470Y247580D01*
X713475Y247625D01*
Y247665D01*
X713480Y247710D01*
X713490Y247750D01*
X713495Y247790D01*
X713510Y247835D01*
X713520Y247875D01*
X713535Y247915D01*
X713555Y247955D01*
X713570Y247990D01*
X713590Y248030D01*
X713690Y248170D01*
X713720Y248200D01*
Y249330D01*
X713730Y249455D01*
X713770Y249580D01*
X713830Y249690D01*
X713910Y249790D01*
X714010Y249870D01*
X714120Y249930D01*
X714245Y249970D01*
X714370Y249980D01*
G37*
G36*
G01X719095D02*
X719220Y249970D01*
X719345Y249930D01*
X719455Y249870D01*
X719555Y249790D01*
X719635Y249690D01*
X719695Y249580D01*
X719735Y249455D01*
X719745Y249330D01*
Y248200D01*
X719775Y248170D01*
X719875Y248030D01*
X719895Y247990D01*
X719910Y247955D01*
X719930Y247915D01*
X719945Y247875D01*
X719955Y247835D01*
X719970Y247790D01*
X719975Y247750D01*
X719985Y247710D01*
X719990Y247665D01*
Y247625D01*
X719995Y247580D01*
X719990Y247535D01*
Y247495D01*
X719985Y247450D01*
X719975Y247410D01*
X719970Y247370D01*
X719955Y247325D01*
X719945Y247285D01*
X719930Y247245D01*
X719910Y247205D01*
X719895Y247170D01*
X719875Y247130D01*
X719775Y246990D01*
X719745Y246960D01*
Y243530D01*
X719735Y243405D01*
X719695Y243280D01*
X719635Y243170D01*
X719555Y243070D01*
X719455Y242990D01*
X719345Y242930D01*
X719220Y242890D01*
X719095Y242880D01*
X718970Y242890D01*
X718845Y242930D01*
X718735Y242990D01*
X718635Y243070D01*
X718555Y243170D01*
X718495Y243280D01*
X718455Y243405D01*
X718445Y243530D01*
Y246960D01*
X718415Y246990D01*
X718315Y247130D01*
X718295Y247170D01*
X718280Y247205D01*
X718260Y247245D01*
X718245Y247285D01*
X718235Y247325D01*
X718220Y247370D01*
X718215Y247410D01*
X718205Y247450D01*
X718200Y247495D01*
Y247535D01*
X718195Y247580D01*
X718200Y247625D01*
Y247665D01*
X718205Y247710D01*
X718215Y247750D01*
X718220Y247790D01*
X718235Y247835D01*
X718245Y247875D01*
X718260Y247915D01*
X718280Y247955D01*
X718295Y247990D01*
X718315Y248030D01*
X718415Y248170D01*
X718445Y248200D01*
Y249330D01*
X718455Y249455D01*
X718495Y249580D01*
X718555Y249690D01*
X718635Y249790D01*
X718735Y249870D01*
X718845Y249930D01*
X718970Y249970D01*
X719095Y249980D01*
G37*
G36*
G01X723819D02*
X723944Y249970D01*
X724069Y249930D01*
X724179Y249870D01*
X724279Y249790D01*
X724359Y249690D01*
X724419Y249580D01*
X724459Y249455D01*
X724469Y249330D01*
Y248200D01*
X724499Y248170D01*
X724599Y248030D01*
X724619Y247990D01*
X724634Y247955D01*
X724654Y247915D01*
X724669Y247875D01*
X724679Y247835D01*
X724694Y247790D01*
X724699Y247750D01*
X724709Y247710D01*
X724714Y247665D01*
Y247625D01*
X724719Y247580D01*
X724714Y247535D01*
Y247495D01*
X724709Y247450D01*
X724699Y247410D01*
X724694Y247370D01*
X724679Y247325D01*
X724669Y247285D01*
X724654Y247245D01*
X724634Y247205D01*
X724619Y247170D01*
X724599Y247130D01*
X724499Y246990D01*
X724469Y246960D01*
Y243530D01*
X724459Y243405D01*
X724419Y243280D01*
X724359Y243170D01*
X724279Y243070D01*
X724179Y242990D01*
X724069Y242930D01*
X723944Y242890D01*
X723819Y242880D01*
X723694Y242890D01*
X723569Y242930D01*
X723459Y242990D01*
X723359Y243070D01*
X723279Y243170D01*
X723219Y243280D01*
X723179Y243405D01*
X723169Y243530D01*
Y246960D01*
X723139Y246990D01*
X723039Y247130D01*
X723019Y247170D01*
X723004Y247205D01*
X722984Y247245D01*
X722969Y247285D01*
X722959Y247325D01*
X722944Y247370D01*
X722939Y247410D01*
X722929Y247450D01*
X722924Y247495D01*
Y247535D01*
X722919Y247580D01*
X722924Y247625D01*
Y247665D01*
X722929Y247710D01*
X722939Y247750D01*
X722944Y247790D01*
X722959Y247835D01*
X722969Y247875D01*
X722984Y247915D01*
X723004Y247955D01*
X723019Y247990D01*
X723039Y248030D01*
X723139Y248170D01*
X723169Y248200D01*
Y249330D01*
X723179Y249455D01*
X723219Y249580D01*
X723279Y249690D01*
X723359Y249790D01*
X723459Y249870D01*
X723569Y249930D01*
X723694Y249970D01*
X723819Y249980D01*
G37*
G36*
G01X728544D02*
X728669Y249970D01*
X728794Y249930D01*
X728904Y249870D01*
X729004Y249790D01*
X729084Y249690D01*
X729144Y249580D01*
X729184Y249455D01*
X729194Y249330D01*
Y248200D01*
X729224Y248170D01*
X729324Y248030D01*
X729344Y247990D01*
X729359Y247955D01*
X729379Y247915D01*
X729394Y247875D01*
X729404Y247835D01*
X729419Y247790D01*
X729424Y247750D01*
X729434Y247710D01*
X729439Y247665D01*
Y247625D01*
X729444Y247580D01*
X729439Y247535D01*
Y247495D01*
X729434Y247450D01*
X729424Y247410D01*
X729419Y247370D01*
X729404Y247325D01*
X729394Y247285D01*
X729379Y247245D01*
X729359Y247205D01*
X729344Y247170D01*
X729324Y247130D01*
X729224Y246990D01*
X729194Y246960D01*
Y243530D01*
X729184Y243405D01*
X729144Y243280D01*
X729084Y243170D01*
X729004Y243070D01*
X728904Y242990D01*
X728794Y242930D01*
X728669Y242890D01*
X728544Y242880D01*
X728419Y242890D01*
X728294Y242930D01*
X728184Y242990D01*
X728084Y243070D01*
X728004Y243170D01*
X727944Y243280D01*
X727904Y243405D01*
X727894Y243530D01*
Y246960D01*
X727864Y246990D01*
X727764Y247130D01*
X727744Y247170D01*
X727729Y247205D01*
X727709Y247245D01*
X727694Y247285D01*
X727684Y247325D01*
X727669Y247370D01*
X727664Y247410D01*
X727654Y247450D01*
X727649Y247495D01*
Y247535D01*
X727644Y247580D01*
X727649Y247625D01*
Y247665D01*
X727654Y247710D01*
X727664Y247750D01*
X727669Y247790D01*
X727684Y247835D01*
X727694Y247875D01*
X727709Y247915D01*
X727729Y247955D01*
X727744Y247990D01*
X727764Y248030D01*
X727864Y248170D01*
X727894Y248200D01*
Y249330D01*
X727904Y249455D01*
X727944Y249580D01*
X728004Y249690D01*
X728084Y249790D01*
X728184Y249870D01*
X728294Y249930D01*
X728419Y249970D01*
X728544Y249980D01*
G37*
G36*
G01X733268D02*
X733393Y249970D01*
X733518Y249930D01*
X733628Y249870D01*
X733728Y249790D01*
X733808Y249690D01*
X733868Y249580D01*
X733908Y249455D01*
X733918Y249330D01*
Y248200D01*
X733948Y248170D01*
X734048Y248030D01*
X734068Y247990D01*
X734083Y247955D01*
X734103Y247915D01*
X734118Y247875D01*
X734128Y247835D01*
X734143Y247790D01*
X734148Y247750D01*
X734158Y247710D01*
X734163Y247665D01*
Y247625D01*
X734168Y247580D01*
X734163Y247535D01*
Y247495D01*
X734158Y247450D01*
X734148Y247410D01*
X734143Y247370D01*
X734128Y247325D01*
X734118Y247285D01*
X734103Y247245D01*
X734083Y247205D01*
X734068Y247170D01*
X734048Y247130D01*
X733948Y246990D01*
X733918Y246960D01*
Y243530D01*
X733908Y243405D01*
X733868Y243280D01*
X733808Y243170D01*
X733728Y243070D01*
X733628Y242990D01*
X733518Y242930D01*
X733393Y242890D01*
X733268Y242880D01*
X733143Y242890D01*
X733018Y242930D01*
X732908Y242990D01*
X732808Y243070D01*
X732728Y243170D01*
X732668Y243280D01*
X732628Y243405D01*
X732618Y243530D01*
Y246960D01*
X732588Y246990D01*
X732488Y247130D01*
X732468Y247170D01*
X732453Y247205D01*
X732433Y247245D01*
X732418Y247285D01*
X732408Y247325D01*
X732393Y247370D01*
X732388Y247410D01*
X732378Y247450D01*
X732373Y247495D01*
Y247535D01*
X732368Y247580D01*
X732373Y247625D01*
Y247665D01*
X732378Y247710D01*
X732388Y247750D01*
X732393Y247790D01*
X732408Y247835D01*
X732418Y247875D01*
X732433Y247915D01*
X732453Y247955D01*
X732468Y247990D01*
X732488Y248030D01*
X732588Y248170D01*
X732618Y248200D01*
Y249330D01*
X732628Y249455D01*
X732668Y249580D01*
X732728Y249690D01*
X732808Y249790D01*
X732908Y249870D01*
X733018Y249930D01*
X733143Y249970D01*
X733268Y249980D01*
G37*
G36*
G01X737992D02*
X738117Y249970D01*
X738242Y249930D01*
X738352Y249870D01*
X738452Y249790D01*
X738532Y249690D01*
X738592Y249580D01*
X738632Y249455D01*
X738642Y249330D01*
Y248200D01*
X738672Y248170D01*
X738772Y248030D01*
X738792Y247990D01*
X738807Y247955D01*
X738827Y247915D01*
X738842Y247875D01*
X738852Y247835D01*
X738867Y247790D01*
X738872Y247750D01*
X738882Y247710D01*
X738887Y247665D01*
Y247625D01*
X738892Y247580D01*
X738887Y247535D01*
Y247495D01*
X738882Y247450D01*
X738872Y247410D01*
X738867Y247370D01*
X738852Y247325D01*
X738842Y247285D01*
X738827Y247245D01*
X738807Y247205D01*
X738792Y247170D01*
X738772Y247130D01*
X738672Y246990D01*
X738642Y246960D01*
Y243530D01*
X738632Y243405D01*
X738592Y243280D01*
X738532Y243170D01*
X738452Y243070D01*
X738352Y242990D01*
X738242Y242930D01*
X738117Y242890D01*
X737992Y242880D01*
X737867Y242890D01*
X737742Y242930D01*
X737632Y242990D01*
X737532Y243070D01*
X737452Y243170D01*
X737392Y243280D01*
X737352Y243405D01*
X737342Y243530D01*
Y246960D01*
X737312Y246990D01*
X737212Y247130D01*
X737192Y247170D01*
X737177Y247205D01*
X737157Y247245D01*
X737142Y247285D01*
X737132Y247325D01*
X737117Y247370D01*
X737112Y247410D01*
X737102Y247450D01*
X737097Y247495D01*
Y247535D01*
X737092Y247580D01*
X737097Y247625D01*
Y247665D01*
X737102Y247710D01*
X737112Y247750D01*
X737117Y247790D01*
X737132Y247835D01*
X737142Y247875D01*
X737157Y247915D01*
X737177Y247955D01*
X737192Y247990D01*
X737212Y248030D01*
X737312Y248170D01*
X737342Y248200D01*
Y249330D01*
X737352Y249455D01*
X737392Y249580D01*
X737452Y249690D01*
X737532Y249790D01*
X737632Y249870D01*
X737742Y249930D01*
X737867Y249970D01*
X737992Y249980D01*
G37*
G36*
G01X742717D02*
X742842Y249970D01*
X742967Y249930D01*
X743077Y249870D01*
X743177Y249790D01*
X743257Y249690D01*
X743317Y249580D01*
X743357Y249455D01*
X743367Y249330D01*
Y248200D01*
X743397Y248170D01*
X743497Y248030D01*
X743517Y247990D01*
X743532Y247955D01*
X743552Y247915D01*
X743567Y247875D01*
X743577Y247835D01*
X743592Y247790D01*
X743597Y247750D01*
X743607Y247710D01*
X743612Y247665D01*
Y247625D01*
X743617Y247580D01*
X743612Y247535D01*
Y247495D01*
X743607Y247450D01*
X743597Y247410D01*
X743592Y247370D01*
X743577Y247325D01*
X743567Y247285D01*
X743552Y247245D01*
X743532Y247205D01*
X743517Y247170D01*
X743497Y247130D01*
X743397Y246990D01*
X743367Y246960D01*
Y243530D01*
X743357Y243405D01*
X743317Y243280D01*
X743257Y243170D01*
X743177Y243070D01*
X743077Y242990D01*
X742967Y242930D01*
X742842Y242890D01*
X742717Y242880D01*
X742592Y242890D01*
X742467Y242930D01*
X742357Y242990D01*
X742257Y243070D01*
X742177Y243170D01*
X742117Y243280D01*
X742077Y243405D01*
X742067Y243530D01*
Y246960D01*
X742037Y246990D01*
X741937Y247130D01*
X741917Y247170D01*
X741902Y247205D01*
X741882Y247245D01*
X741867Y247285D01*
X741857Y247325D01*
X741842Y247370D01*
X741837Y247410D01*
X741827Y247450D01*
X741822Y247495D01*
Y247535D01*
X741817Y247580D01*
X741822Y247625D01*
Y247665D01*
X741827Y247710D01*
X741837Y247750D01*
X741842Y247790D01*
X741857Y247835D01*
X741867Y247875D01*
X741882Y247915D01*
X741902Y247955D01*
X741917Y247990D01*
X741937Y248030D01*
X742037Y248170D01*
X742067Y248200D01*
Y249330D01*
X742077Y249455D01*
X742117Y249580D01*
X742177Y249690D01*
X742257Y249790D01*
X742357Y249870D01*
X742467Y249930D01*
X742592Y249970D01*
X742717Y249980D01*
G37*
G36*
G01X747441D02*
X747566Y249970D01*
X747691Y249930D01*
X747801Y249870D01*
X747901Y249790D01*
X747981Y249690D01*
X748041Y249580D01*
X748081Y249455D01*
X748091Y249330D01*
Y248200D01*
X748121Y248170D01*
X748221Y248030D01*
X748241Y247990D01*
X748256Y247955D01*
X748276Y247915D01*
X748291Y247875D01*
X748301Y247835D01*
X748316Y247790D01*
X748321Y247750D01*
X748331Y247710D01*
X748336Y247665D01*
Y247625D01*
X748341Y247580D01*
X748336Y247535D01*
Y247495D01*
X748331Y247450D01*
X748321Y247410D01*
X748316Y247370D01*
X748301Y247325D01*
X748291Y247285D01*
X748276Y247245D01*
X748256Y247205D01*
X748241Y247170D01*
X748221Y247130D01*
X748121Y246990D01*
X748091Y246960D01*
Y243530D01*
X748081Y243405D01*
X748041Y243280D01*
X747981Y243170D01*
X747901Y243070D01*
X747801Y242990D01*
X747691Y242930D01*
X747566Y242890D01*
X747441Y242880D01*
X747316Y242890D01*
X747191Y242930D01*
X747081Y242990D01*
X746981Y243070D01*
X746901Y243170D01*
X746841Y243280D01*
X746801Y243405D01*
X746791Y243530D01*
Y246960D01*
X746761Y246990D01*
X746661Y247130D01*
X746641Y247170D01*
X746626Y247205D01*
X746606Y247245D01*
X746591Y247285D01*
X746581Y247325D01*
X746566Y247370D01*
X746561Y247410D01*
X746551Y247450D01*
X746546Y247495D01*
Y247535D01*
X746541Y247580D01*
X746546Y247625D01*
Y247665D01*
X746551Y247710D01*
X746561Y247750D01*
X746566Y247790D01*
X746581Y247835D01*
X746591Y247875D01*
X746606Y247915D01*
X746626Y247955D01*
X746641Y247990D01*
X746661Y248030D01*
X746761Y248170D01*
X746791Y248200D01*
Y249330D01*
X746801Y249455D01*
X746841Y249580D01*
X746901Y249690D01*
X746981Y249790D01*
X747081Y249870D01*
X747191Y249930D01*
X747316Y249970D01*
X747441Y249980D01*
G37*
G54D113*
X577000Y197705D03*
Y195735D03*
Y193765D03*
Y191795D03*
Y189830D03*
Y199670D03*
X590400Y189830D03*
Y191795D03*
Y193765D03*
Y195735D03*
Y197705D03*
Y199670D03*
G54D140*
X792700Y165671D03*
Y196329D03*
G54D11*
X-11600Y33200D03*
X18400Y76200D03*
X24000Y280000D03*
X325500Y229000D03*
X394100Y57700D03*
X468000Y171500D03*
X799500Y10500D03*
X833100Y564800D03*
X842500Y35000D03*
G54D20*
X20000Y116100D03*
Y110900D03*
Y129600D03*
Y124400D03*
X72500Y90900D03*
Y96100D03*
X72400Y198000D03*
X77400D03*
X72400Y203200D03*
X77400D03*
X108550Y146600D03*
Y141400D03*
X177000Y134900D03*
Y140100D03*
X204000Y197400D03*
X198200Y197401D03*
X204000Y202600D03*
X198200Y202601D03*
X198500Y258600D03*
Y253400D03*
X255000Y225600D03*
Y220400D03*
X287500Y160100D03*
Y154900D03*
X507000Y224600D03*
Y219400D03*
X522500Y224600D03*
Y219400D03*
X605300Y235600D03*
Y230400D03*
X740000Y238600D03*
Y233400D03*
X749800Y105700D03*
Y110900D03*
G54D30*
X44250Y126000D03*
X208750Y210500D03*
G54D123*
X675839Y162260D03*
Y166000D03*
Y169740D03*
X685161Y166000D03*
Y162260D03*
Y169740D03*
G54D114*
X580745Y187050D03*
X586655D03*
X580745Y202450D03*
X586655D03*
G54D21*
X24000Y127700D03*
Y124300D03*
X27200Y127700D03*
Y124300D03*
X30200Y127700D03*
Y124300D03*
X24900Y197300D03*
Y200700D03*
X37500Y127700D03*
Y124300D03*
X57000Y127200D03*
Y123800D03*
X52500Y238200D03*
Y234800D03*
X49500Y238200D03*
Y234800D03*
X61300Y253300D03*
Y249900D03*
X79000Y132600D03*
Y129200D03*
X68000Y198300D03*
Y201700D03*
X77700Y256500D03*
Y253100D03*
X64400Y253300D03*
Y249900D03*
X89500Y258300D03*
Y254900D03*
X80200Y266200D03*
Y262800D03*
X118000Y54200D03*
Y50800D03*
X123700Y150900D03*
Y154300D03*
X129500Y81200D03*
Y77800D03*
X130600Y131800D03*
Y128400D03*
X126800Y144300D03*
Y140900D03*
X127000Y150800D03*
Y154200D03*
X150000Y167200D03*
Y163800D03*
X184500Y65000D03*
Y61600D03*
X187500Y65000D03*
Y61600D03*
X185500Y87800D03*
Y91200D03*
X190500Y65000D03*
Y61600D03*
X193500Y65000D03*
Y61600D03*
X194600Y88800D03*
X197600D03*
X194600Y92200D03*
X197600D03*
X197300Y135800D03*
X191300D03*
X194300D03*
X197300Y139200D03*
X191300D03*
X194300D03*
X221500Y212300D03*
Y215700D03*
X238000Y166700D03*
Y163300D03*
X246000Y193200D03*
Y189800D03*
X255500Y96700D03*
Y93300D03*
X270000Y84700D03*
Y81300D03*
X267000Y84700D03*
Y81300D03*
X276700Y182700D03*
Y186100D03*
X293000Y195700D03*
Y192300D03*
X289500Y218700D03*
Y215300D03*
X322000Y257800D03*
X311500D03*
X322000Y261200D03*
X311500D03*
X441600Y254800D03*
Y251400D03*
X449000Y281700D03*
Y278300D03*
X446000Y281700D03*
Y278300D03*
X462500Y255200D03*
Y251800D03*
X461000Y270700D03*
Y267300D03*
X465500Y143763D03*
Y140363D03*
Y255200D03*
Y251800D03*
X509200Y103200D03*
Y99800D03*
X523000Y74800D03*
Y78200D03*
X531500Y237200D03*
Y233800D03*
X555300Y214100D03*
Y217500D03*
X566500Y84700D03*
Y81300D03*
X595500Y202200D03*
Y198800D03*
X613000Y115700D03*
Y112300D03*
X616000Y115700D03*
Y112300D03*
X622500Y88700D03*
Y85300D03*
X623000Y115700D03*
Y112300D03*
X634000Y136300D03*
Y139700D03*
X628900Y178400D03*
Y175000D03*
X646500Y182200D03*
Y178800D03*
X667500Y164800D03*
Y168200D03*
X668000Y211500D03*
Y208100D03*
X694500Y226700D03*
Y223300D03*
X691500Y226700D03*
Y223300D03*
X682500Y226700D03*
Y223300D03*
X711000Y66700D03*
Y63300D03*
X714000Y71200D03*
Y67800D03*
X725200Y119900D03*
Y116500D03*
X718700Y126600D03*
Y123200D03*
X718000Y143700D03*
Y140300D03*
X723000Y183200D03*
Y179800D03*
X726000Y183200D03*
Y179800D03*
X725000Y213700D03*
Y210300D03*
X722000Y213700D03*
Y210300D03*
X718500Y220700D03*
Y217300D03*
X722000Y220700D03*
Y217300D03*
X728000Y104300D03*
X739500Y104600D03*
X728000Y107700D03*
X739500Y108000D03*
X728000Y158700D03*
Y155300D03*
X735500Y182700D03*
Y179300D03*
X740500Y197800D03*
Y201200D03*
X744000Y165200D03*
Y161800D03*
X754500Y158700D03*
Y155300D03*
X782500Y41800D03*
Y45200D03*
X779500Y148700D03*
Y145300D03*
X807500Y86200D03*
Y82800D03*
G36*
G01X500591Y282316D02*
X500716Y282306D01*
X500841Y282266D01*
X500951Y282206D01*
X501051Y282126D01*
X501131Y282026D01*
X501191Y281916D01*
X501231Y281791D01*
X501241Y281666D01*
Y279236D01*
X501271Y279206D01*
X501371Y279066D01*
X501391Y279026D01*
X501406Y278991D01*
X501426Y278951D01*
X501441Y278911D01*
X501451Y278871D01*
X501466Y278826D01*
X501471Y278786D01*
X501481Y278746D01*
X501486Y278701D01*
Y278661D01*
X501491Y278616D01*
X501486Y278571D01*
Y278531D01*
X501481Y278486D01*
X501471Y278446D01*
X501466Y278406D01*
X501451Y278361D01*
X501441Y278321D01*
X501426Y278281D01*
X501406Y278241D01*
X501391Y278206D01*
X501371Y278166D01*
X501271Y278026D01*
X501241Y277996D01*
Y275866D01*
X501231Y275741D01*
X501191Y275616D01*
X501131Y275506D01*
X501051Y275406D01*
X500951Y275326D01*
X500841Y275266D01*
X500716Y275226D01*
X500591Y275216D01*
X500466Y275226D01*
X500341Y275266D01*
X500231Y275326D01*
X500131Y275406D01*
X500051Y275506D01*
X499991Y275616D01*
X499951Y275741D01*
X499941Y275866D01*
Y277991D01*
X499911Y278021D01*
X499886Y278056D01*
X499856Y278091D01*
X499836Y278126D01*
X499811Y278161D01*
X499771Y278241D01*
X499726Y278361D01*
X499716Y278401D01*
X499706Y278446D01*
X499701Y278486D01*
X499691Y278531D01*
Y278701D01*
X499701Y278746D01*
X499706Y278786D01*
X499716Y278831D01*
X499726Y278871D01*
X499771Y278991D01*
X499811Y279071D01*
X499836Y279106D01*
X499856Y279141D01*
X499886Y279176D01*
X499911Y279211D01*
X499941Y279241D01*
Y281666D01*
X499951Y281791D01*
X499991Y281916D01*
X500051Y282026D01*
X500131Y282126D01*
X500231Y282206D01*
X500341Y282266D01*
X500466Y282306D01*
X500591Y282316D01*
G37*
G36*
G01X505315D02*
X505440Y282306D01*
X505565Y282266D01*
X505675Y282206D01*
X505775Y282126D01*
X505855Y282026D01*
X505915Y281916D01*
X505955Y281791D01*
X505965Y281666D01*
Y279236D01*
X505995Y279206D01*
X506095Y279066D01*
X506115Y279026D01*
X506130Y278991D01*
X506150Y278951D01*
X506165Y278911D01*
X506175Y278871D01*
X506190Y278826D01*
X506195Y278786D01*
X506205Y278746D01*
X506210Y278701D01*
Y278661D01*
X506215Y278616D01*
X506210Y278571D01*
Y278531D01*
X506205Y278486D01*
X506195Y278446D01*
X506190Y278406D01*
X506175Y278361D01*
X506165Y278321D01*
X506150Y278281D01*
X506130Y278241D01*
X506115Y278206D01*
X506095Y278166D01*
X505995Y278026D01*
X505965Y277996D01*
Y275866D01*
X505955Y275741D01*
X505915Y275616D01*
X505855Y275506D01*
X505775Y275406D01*
X505675Y275326D01*
X505565Y275266D01*
X505440Y275226D01*
X505315Y275216D01*
X505190Y275226D01*
X505065Y275266D01*
X504955Y275326D01*
X504855Y275406D01*
X504775Y275506D01*
X504715Y275616D01*
X504675Y275741D01*
X504665Y275866D01*
Y277991D01*
X504635Y278021D01*
X504610Y278056D01*
X504580Y278091D01*
X504560Y278126D01*
X504535Y278161D01*
X504495Y278241D01*
X504450Y278361D01*
X504440Y278401D01*
X504430Y278446D01*
X504425Y278486D01*
X504415Y278531D01*
Y278701D01*
X504425Y278746D01*
X504430Y278786D01*
X504440Y278831D01*
X504450Y278871D01*
X504495Y278991D01*
X504535Y279071D01*
X504560Y279106D01*
X504580Y279141D01*
X504610Y279176D01*
X504635Y279211D01*
X504665Y279241D01*
Y281666D01*
X504675Y281791D01*
X504715Y281916D01*
X504775Y282026D01*
X504855Y282126D01*
X504955Y282206D01*
X505065Y282266D01*
X505190Y282306D01*
X505315Y282316D01*
G37*
G36*
G01X510040D02*
X510165Y282306D01*
X510290Y282266D01*
X510400Y282206D01*
X510500Y282126D01*
X510580Y282026D01*
X510640Y281916D01*
X510680Y281791D01*
X510690Y281666D01*
Y279236D01*
X510720Y279206D01*
X510820Y279066D01*
X510840Y279026D01*
X510855Y278991D01*
X510875Y278951D01*
X510890Y278911D01*
X510900Y278871D01*
X510915Y278826D01*
X510920Y278786D01*
X510930Y278746D01*
X510935Y278701D01*
Y278661D01*
X510940Y278616D01*
X510935Y278571D01*
Y278531D01*
X510930Y278486D01*
X510920Y278446D01*
X510915Y278406D01*
X510900Y278361D01*
X510890Y278321D01*
X510875Y278281D01*
X510855Y278241D01*
X510840Y278206D01*
X510820Y278166D01*
X510720Y278026D01*
X510690Y277996D01*
Y275866D01*
X510680Y275741D01*
X510640Y275616D01*
X510580Y275506D01*
X510500Y275406D01*
X510400Y275326D01*
X510290Y275266D01*
X510165Y275226D01*
X510040Y275216D01*
X509915Y275226D01*
X509790Y275266D01*
X509680Y275326D01*
X509580Y275406D01*
X509500Y275506D01*
X509440Y275616D01*
X509400Y275741D01*
X509390Y275866D01*
Y277991D01*
X509360Y278021D01*
X509335Y278056D01*
X509305Y278091D01*
X509285Y278126D01*
X509260Y278161D01*
X509220Y278241D01*
X509175Y278361D01*
X509165Y278401D01*
X509155Y278446D01*
X509150Y278486D01*
X509140Y278531D01*
Y278701D01*
X509150Y278746D01*
X509155Y278786D01*
X509165Y278831D01*
X509175Y278871D01*
X509220Y278991D01*
X509260Y279071D01*
X509285Y279106D01*
X509305Y279141D01*
X509335Y279176D01*
X509360Y279211D01*
X509390Y279241D01*
Y281666D01*
X509400Y281791D01*
X509440Y281916D01*
X509500Y282026D01*
X509580Y282126D01*
X509680Y282206D01*
X509790Y282266D01*
X509915Y282306D01*
X510040Y282316D01*
G37*
G36*
G01X514764D02*
X514889Y282306D01*
X515014Y282266D01*
X515124Y282206D01*
X515224Y282126D01*
X515304Y282026D01*
X515364Y281916D01*
X515404Y281791D01*
X515414Y281666D01*
Y279236D01*
X515444Y279206D01*
X515544Y279066D01*
X515564Y279026D01*
X515579Y278991D01*
X515599Y278951D01*
X515614Y278911D01*
X515624Y278871D01*
X515639Y278826D01*
X515644Y278786D01*
X515654Y278746D01*
X515659Y278701D01*
Y278661D01*
X515664Y278616D01*
X515659Y278571D01*
Y278531D01*
X515654Y278486D01*
X515644Y278446D01*
X515639Y278406D01*
X515624Y278361D01*
X515614Y278321D01*
X515599Y278281D01*
X515579Y278241D01*
X515564Y278206D01*
X515544Y278166D01*
X515444Y278026D01*
X515414Y277996D01*
Y275866D01*
X515404Y275741D01*
X515364Y275616D01*
X515304Y275506D01*
X515224Y275406D01*
X515124Y275326D01*
X515014Y275266D01*
X514889Y275226D01*
X514764Y275216D01*
X514639Y275226D01*
X514514Y275266D01*
X514404Y275326D01*
X514304Y275406D01*
X514224Y275506D01*
X514164Y275616D01*
X514124Y275741D01*
X514114Y275866D01*
Y277991D01*
X514084Y278021D01*
X514059Y278056D01*
X514029Y278091D01*
X514009Y278126D01*
X513984Y278161D01*
X513944Y278241D01*
X513899Y278361D01*
X513889Y278401D01*
X513879Y278446D01*
X513874Y278486D01*
X513864Y278531D01*
Y278701D01*
X513874Y278746D01*
X513879Y278786D01*
X513889Y278831D01*
X513899Y278871D01*
X513944Y278991D01*
X513984Y279071D01*
X514009Y279106D01*
X514029Y279141D01*
X514059Y279176D01*
X514084Y279211D01*
X514114Y279241D01*
Y281666D01*
X514124Y281791D01*
X514164Y281916D01*
X514224Y282026D01*
X514304Y282126D01*
X514404Y282206D01*
X514514Y282266D01*
X514639Y282306D01*
X514764Y282316D01*
G37*
G36*
G01X519488D02*
X519613Y282306D01*
X519738Y282266D01*
X519848Y282206D01*
X519948Y282126D01*
X520028Y282026D01*
X520088Y281916D01*
X520128Y281791D01*
X520138Y281666D01*
Y279236D01*
X520168Y279206D01*
X520268Y279066D01*
X520288Y279026D01*
X520303Y278991D01*
X520323Y278951D01*
X520338Y278911D01*
X520348Y278871D01*
X520363Y278826D01*
X520368Y278786D01*
X520378Y278746D01*
X520383Y278701D01*
Y278661D01*
X520388Y278616D01*
X520383Y278571D01*
Y278531D01*
X520378Y278486D01*
X520368Y278446D01*
X520363Y278406D01*
X520348Y278361D01*
X520338Y278321D01*
X520323Y278281D01*
X520303Y278241D01*
X520288Y278206D01*
X520268Y278166D01*
X520168Y278026D01*
X520138Y277996D01*
Y275866D01*
X520128Y275741D01*
X520088Y275616D01*
X520028Y275506D01*
X519948Y275406D01*
X519848Y275326D01*
X519738Y275266D01*
X519613Y275226D01*
X519488Y275216D01*
X519363Y275226D01*
X519238Y275266D01*
X519128Y275326D01*
X519028Y275406D01*
X518948Y275506D01*
X518888Y275616D01*
X518848Y275741D01*
X518838Y275866D01*
Y277991D01*
X518808Y278021D01*
X518783Y278056D01*
X518753Y278091D01*
X518733Y278126D01*
X518708Y278161D01*
X518668Y278241D01*
X518623Y278361D01*
X518613Y278401D01*
X518603Y278446D01*
X518598Y278486D01*
X518588Y278531D01*
Y278701D01*
X518598Y278746D01*
X518603Y278786D01*
X518613Y278831D01*
X518623Y278871D01*
X518668Y278991D01*
X518708Y279071D01*
X518733Y279106D01*
X518753Y279141D01*
X518783Y279176D01*
X518808Y279211D01*
X518838Y279241D01*
Y281666D01*
X518848Y281791D01*
X518888Y281916D01*
X518948Y282026D01*
X519028Y282126D01*
X519128Y282206D01*
X519238Y282266D01*
X519363Y282306D01*
X519488Y282316D01*
G37*
G36*
G01X524213D02*
X524338Y282306D01*
X524463Y282266D01*
X524573Y282206D01*
X524673Y282126D01*
X524753Y282026D01*
X524813Y281916D01*
X524853Y281791D01*
X524863Y281666D01*
Y279236D01*
X524893Y279206D01*
X524993Y279066D01*
X525013Y279026D01*
X525028Y278991D01*
X525048Y278951D01*
X525063Y278911D01*
X525073Y278871D01*
X525088Y278826D01*
X525093Y278786D01*
X525103Y278746D01*
X525108Y278701D01*
Y278661D01*
X525113Y278616D01*
X525108Y278571D01*
Y278531D01*
X525103Y278486D01*
X525093Y278446D01*
X525088Y278406D01*
X525073Y278361D01*
X525063Y278321D01*
X525048Y278281D01*
X525028Y278241D01*
X525013Y278206D01*
X524993Y278166D01*
X524893Y278026D01*
X524863Y277996D01*
Y275866D01*
X524853Y275741D01*
X524813Y275616D01*
X524753Y275506D01*
X524673Y275406D01*
X524573Y275326D01*
X524463Y275266D01*
X524338Y275226D01*
X524213Y275216D01*
X524088Y275226D01*
X523963Y275266D01*
X523853Y275326D01*
X523753Y275406D01*
X523673Y275506D01*
X523613Y275616D01*
X523573Y275741D01*
X523563Y275866D01*
Y277991D01*
X523533Y278021D01*
X523508Y278056D01*
X523478Y278091D01*
X523458Y278126D01*
X523433Y278161D01*
X523393Y278241D01*
X523348Y278361D01*
X523338Y278401D01*
X523328Y278446D01*
X523323Y278486D01*
X523313Y278531D01*
Y278701D01*
X523323Y278746D01*
X523328Y278786D01*
X523338Y278831D01*
X523348Y278871D01*
X523393Y278991D01*
X523433Y279071D01*
X523458Y279106D01*
X523478Y279141D01*
X523508Y279176D01*
X523533Y279211D01*
X523563Y279241D01*
Y281666D01*
X523573Y281791D01*
X523613Y281916D01*
X523673Y282026D01*
X523753Y282126D01*
X523853Y282206D01*
X523963Y282266D01*
X524088Y282306D01*
X524213Y282316D01*
G37*
G36*
G01X528937D02*
X529062Y282306D01*
X529187Y282266D01*
X529297Y282206D01*
X529397Y282126D01*
X529477Y282026D01*
X529537Y281916D01*
X529577Y281791D01*
X529587Y281666D01*
Y279236D01*
X529617Y279206D01*
X529717Y279066D01*
X529737Y279026D01*
X529752Y278991D01*
X529772Y278951D01*
X529787Y278911D01*
X529797Y278871D01*
X529812Y278826D01*
X529817Y278786D01*
X529827Y278746D01*
X529832Y278701D01*
Y278661D01*
X529837Y278616D01*
X529832Y278571D01*
Y278531D01*
X529827Y278486D01*
X529817Y278446D01*
X529812Y278406D01*
X529797Y278361D01*
X529787Y278321D01*
X529772Y278281D01*
X529752Y278241D01*
X529737Y278206D01*
X529717Y278166D01*
X529617Y278026D01*
X529587Y277996D01*
Y275866D01*
X529577Y275741D01*
X529537Y275616D01*
X529477Y275506D01*
X529397Y275406D01*
X529297Y275326D01*
X529187Y275266D01*
X529062Y275226D01*
X528937Y275216D01*
X528812Y275226D01*
X528687Y275266D01*
X528577Y275326D01*
X528477Y275406D01*
X528397Y275506D01*
X528337Y275616D01*
X528297Y275741D01*
X528287Y275866D01*
Y277991D01*
X528257Y278021D01*
X528232Y278056D01*
X528202Y278091D01*
X528182Y278126D01*
X528157Y278161D01*
X528117Y278241D01*
X528072Y278361D01*
X528062Y278401D01*
X528052Y278446D01*
X528047Y278486D01*
X528037Y278531D01*
Y278701D01*
X528047Y278746D01*
X528052Y278786D01*
X528062Y278831D01*
X528072Y278871D01*
X528117Y278991D01*
X528157Y279071D01*
X528182Y279106D01*
X528202Y279141D01*
X528232Y279176D01*
X528257Y279211D01*
X528287Y279241D01*
Y281666D01*
X528297Y281791D01*
X528337Y281916D01*
X528397Y282026D01*
X528477Y282126D01*
X528577Y282206D01*
X528687Y282266D01*
X528812Y282306D01*
X528937Y282316D01*
G37*
G36*
G01X533662D02*
X533787Y282306D01*
X533912Y282266D01*
X534022Y282206D01*
X534122Y282126D01*
X534202Y282026D01*
X534262Y281916D01*
X534302Y281791D01*
X534312Y281666D01*
Y279236D01*
X534342Y279206D01*
X534442Y279066D01*
X534462Y279026D01*
X534477Y278991D01*
X534497Y278951D01*
X534512Y278911D01*
X534522Y278871D01*
X534537Y278826D01*
X534542Y278786D01*
X534552Y278746D01*
X534557Y278701D01*
Y278661D01*
X534562Y278616D01*
X534557Y278571D01*
Y278531D01*
X534552Y278486D01*
X534542Y278446D01*
X534537Y278406D01*
X534522Y278361D01*
X534512Y278321D01*
X534497Y278281D01*
X534477Y278241D01*
X534462Y278206D01*
X534442Y278166D01*
X534342Y278026D01*
X534312Y277996D01*
Y275866D01*
X534302Y275741D01*
X534262Y275616D01*
X534202Y275506D01*
X534122Y275406D01*
X534022Y275326D01*
X533912Y275266D01*
X533787Y275226D01*
X533662Y275216D01*
X533537Y275226D01*
X533412Y275266D01*
X533302Y275326D01*
X533202Y275406D01*
X533122Y275506D01*
X533062Y275616D01*
X533022Y275741D01*
X533012Y275866D01*
Y277991D01*
X532982Y278021D01*
X532957Y278056D01*
X532927Y278091D01*
X532907Y278126D01*
X532882Y278161D01*
X532842Y278241D01*
X532797Y278361D01*
X532787Y278401D01*
X532777Y278446D01*
X532772Y278486D01*
X532762Y278531D01*
Y278701D01*
X532772Y278746D01*
X532777Y278786D01*
X532787Y278831D01*
X532797Y278871D01*
X532842Y278991D01*
X532882Y279071D01*
X532907Y279106D01*
X532927Y279141D01*
X532957Y279176D01*
X532982Y279211D01*
X533012Y279241D01*
Y281666D01*
X533022Y281791D01*
X533062Y281916D01*
X533122Y282026D01*
X533202Y282126D01*
X533302Y282206D01*
X533412Y282266D01*
X533537Y282306D01*
X533662Y282316D01*
G37*
G36*
G01X538386D02*
X538511Y282306D01*
X538636Y282266D01*
X538746Y282206D01*
X538846Y282126D01*
X538926Y282026D01*
X538986Y281916D01*
X539026Y281791D01*
X539036Y281666D01*
Y279236D01*
X539066Y279206D01*
X539166Y279066D01*
X539186Y279026D01*
X539201Y278991D01*
X539221Y278951D01*
X539236Y278911D01*
X539246Y278871D01*
X539261Y278826D01*
X539266Y278786D01*
X539276Y278746D01*
X539281Y278701D01*
Y278661D01*
X539286Y278616D01*
X539281Y278571D01*
Y278531D01*
X539276Y278486D01*
X539266Y278446D01*
X539261Y278406D01*
X539246Y278361D01*
X539236Y278321D01*
X539221Y278281D01*
X539201Y278241D01*
X539186Y278206D01*
X539166Y278166D01*
X539066Y278026D01*
X539036Y277996D01*
Y275866D01*
X539026Y275741D01*
X538986Y275616D01*
X538926Y275506D01*
X538846Y275406D01*
X538746Y275326D01*
X538636Y275266D01*
X538511Y275226D01*
X538386Y275216D01*
X538261Y275226D01*
X538136Y275266D01*
X538026Y275326D01*
X537926Y275406D01*
X537846Y275506D01*
X537786Y275616D01*
X537746Y275741D01*
X537736Y275866D01*
Y277991D01*
X537706Y278021D01*
X537681Y278056D01*
X537651Y278091D01*
X537631Y278126D01*
X537606Y278161D01*
X537566Y278241D01*
X537521Y278361D01*
X537511Y278401D01*
X537501Y278446D01*
X537496Y278486D01*
X537486Y278531D01*
Y278701D01*
X537496Y278746D01*
X537501Y278786D01*
X537511Y278831D01*
X537521Y278871D01*
X537566Y278991D01*
X537606Y279071D01*
X537631Y279106D01*
X537651Y279141D01*
X537681Y279176D01*
X537706Y279211D01*
X537736Y279241D01*
Y281666D01*
X537746Y281791D01*
X537786Y281916D01*
X537846Y282026D01*
X537926Y282126D01*
X538026Y282206D01*
X538136Y282266D01*
X538261Y282306D01*
X538386Y282316D01*
G37*
G36*
G01X543110D02*
X543235Y282306D01*
X543360Y282266D01*
X543470Y282206D01*
X543570Y282126D01*
X543650Y282026D01*
X543710Y281916D01*
X543750Y281791D01*
X543760Y281666D01*
Y279236D01*
X543790Y279206D01*
X543890Y279066D01*
X543910Y279026D01*
X543925Y278991D01*
X543945Y278951D01*
X543960Y278911D01*
X543970Y278871D01*
X543985Y278826D01*
X543990Y278786D01*
X544000Y278746D01*
X544005Y278701D01*
Y278661D01*
X544010Y278616D01*
X544005Y278571D01*
Y278531D01*
X544000Y278486D01*
X543990Y278446D01*
X543985Y278406D01*
X543970Y278361D01*
X543960Y278321D01*
X543945Y278281D01*
X543925Y278241D01*
X543910Y278206D01*
X543890Y278166D01*
X543790Y278026D01*
X543760Y277996D01*
Y275866D01*
X543750Y275741D01*
X543710Y275616D01*
X543650Y275506D01*
X543570Y275406D01*
X543470Y275326D01*
X543360Y275266D01*
X543235Y275226D01*
X543110Y275216D01*
X542985Y275226D01*
X542860Y275266D01*
X542750Y275326D01*
X542650Y275406D01*
X542570Y275506D01*
X542510Y275616D01*
X542470Y275741D01*
X542460Y275866D01*
Y277991D01*
X542430Y278021D01*
X542405Y278056D01*
X542375Y278091D01*
X542355Y278126D01*
X542330Y278161D01*
X542290Y278241D01*
X542245Y278361D01*
X542235Y278401D01*
X542225Y278446D01*
X542220Y278486D01*
X542210Y278531D01*
Y278701D01*
X542220Y278746D01*
X542225Y278786D01*
X542235Y278831D01*
X542245Y278871D01*
X542290Y278991D01*
X542330Y279071D01*
X542355Y279106D01*
X542375Y279141D01*
X542405Y279176D01*
X542430Y279211D01*
X542460Y279241D01*
Y281666D01*
X542470Y281791D01*
X542510Y281916D01*
X542570Y282026D01*
X542650Y282126D01*
X542750Y282206D01*
X542860Y282266D01*
X542985Y282306D01*
X543110Y282316D01*
G37*
G36*
G01X547835D02*
X547960Y282306D01*
X548085Y282266D01*
X548195Y282206D01*
X548295Y282126D01*
X548375Y282026D01*
X548435Y281916D01*
X548475Y281791D01*
X548485Y281666D01*
Y279236D01*
X548515Y279206D01*
X548615Y279066D01*
X548635Y279026D01*
X548650Y278991D01*
X548670Y278951D01*
X548685Y278911D01*
X548695Y278871D01*
X548710Y278826D01*
X548715Y278786D01*
X548725Y278746D01*
X548730Y278701D01*
Y278661D01*
X548735Y278616D01*
X548730Y278571D01*
Y278531D01*
X548725Y278486D01*
X548715Y278446D01*
X548710Y278406D01*
X548695Y278361D01*
X548685Y278321D01*
X548670Y278281D01*
X548650Y278241D01*
X548635Y278206D01*
X548615Y278166D01*
X548515Y278026D01*
X548485Y277996D01*
Y275866D01*
X548475Y275741D01*
X548435Y275616D01*
X548375Y275506D01*
X548295Y275406D01*
X548195Y275326D01*
X548085Y275266D01*
X547960Y275226D01*
X547835Y275216D01*
X547710Y275226D01*
X547585Y275266D01*
X547475Y275326D01*
X547375Y275406D01*
X547295Y275506D01*
X547235Y275616D01*
X547195Y275741D01*
X547185Y275866D01*
Y277991D01*
X547155Y278021D01*
X547130Y278056D01*
X547100Y278091D01*
X547080Y278126D01*
X547055Y278161D01*
X547015Y278241D01*
X546970Y278361D01*
X546960Y278401D01*
X546950Y278446D01*
X546945Y278486D01*
X546935Y278531D01*
Y278701D01*
X546945Y278746D01*
X546950Y278786D01*
X546960Y278831D01*
X546970Y278871D01*
X547015Y278991D01*
X547055Y279071D01*
X547080Y279106D01*
X547100Y279141D01*
X547130Y279176D01*
X547155Y279211D01*
X547185Y279241D01*
Y281666D01*
X547195Y281791D01*
X547235Y281916D01*
X547295Y282026D01*
X547375Y282126D01*
X547475Y282206D01*
X547585Y282266D01*
X547710Y282306D01*
X547835Y282316D01*
G37*
G36*
G01X552559D02*
X552684Y282306D01*
X552809Y282266D01*
X552919Y282206D01*
X553019Y282126D01*
X553099Y282026D01*
X553159Y281916D01*
X553199Y281791D01*
X553209Y281666D01*
Y279236D01*
X553239Y279206D01*
X553339Y279066D01*
X553359Y279026D01*
X553374Y278991D01*
X553394Y278951D01*
X553409Y278911D01*
X553419Y278871D01*
X553434Y278826D01*
X553439Y278786D01*
X553449Y278746D01*
X553454Y278701D01*
Y278661D01*
X553459Y278616D01*
X553454Y278571D01*
Y278531D01*
X553449Y278486D01*
X553439Y278446D01*
X553434Y278406D01*
X553419Y278361D01*
X553409Y278321D01*
X553394Y278281D01*
X553374Y278241D01*
X553359Y278206D01*
X553339Y278166D01*
X553239Y278026D01*
X553209Y277996D01*
Y275866D01*
X553199Y275741D01*
X553159Y275616D01*
X553099Y275506D01*
X553019Y275406D01*
X552919Y275326D01*
X552809Y275266D01*
X552684Y275226D01*
X552559Y275216D01*
X552434Y275226D01*
X552309Y275266D01*
X552199Y275326D01*
X552099Y275406D01*
X552019Y275506D01*
X551959Y275616D01*
X551919Y275741D01*
X551909Y275866D01*
Y277991D01*
X551879Y278021D01*
X551854Y278056D01*
X551824Y278091D01*
X551804Y278126D01*
X551779Y278161D01*
X551739Y278241D01*
X551694Y278361D01*
X551684Y278401D01*
X551674Y278446D01*
X551669Y278486D01*
X551659Y278531D01*
Y278701D01*
X551669Y278746D01*
X551674Y278786D01*
X551684Y278831D01*
X551694Y278871D01*
X551739Y278991D01*
X551779Y279071D01*
X551804Y279106D01*
X551824Y279141D01*
X551854Y279176D01*
X551879Y279211D01*
X551909Y279241D01*
Y281666D01*
X551919Y281791D01*
X551959Y281916D01*
X552019Y282026D01*
X552099Y282126D01*
X552199Y282206D01*
X552309Y282266D01*
X552434Y282306D01*
X552559Y282316D01*
G37*
G36*
G01X557284D02*
X557409Y282306D01*
X557534Y282266D01*
X557644Y282206D01*
X557744Y282126D01*
X557824Y282026D01*
X557884Y281916D01*
X557924Y281791D01*
X557934Y281666D01*
Y279236D01*
X557964Y279206D01*
X558064Y279066D01*
X558084Y279026D01*
X558099Y278991D01*
X558119Y278951D01*
X558134Y278911D01*
X558144Y278871D01*
X558159Y278826D01*
X558164Y278786D01*
X558174Y278746D01*
X558179Y278701D01*
Y278661D01*
X558184Y278616D01*
X558179Y278571D01*
Y278531D01*
X558174Y278486D01*
X558164Y278446D01*
X558159Y278406D01*
X558144Y278361D01*
X558134Y278321D01*
X558119Y278281D01*
X558099Y278241D01*
X558084Y278206D01*
X558064Y278166D01*
X557964Y278026D01*
X557934Y277996D01*
Y275866D01*
X557924Y275741D01*
X557884Y275616D01*
X557824Y275506D01*
X557744Y275406D01*
X557644Y275326D01*
X557534Y275266D01*
X557409Y275226D01*
X557284Y275216D01*
X557159Y275226D01*
X557034Y275266D01*
X556924Y275326D01*
X556824Y275406D01*
X556744Y275506D01*
X556684Y275616D01*
X556644Y275741D01*
X556634Y275866D01*
Y277991D01*
X556604Y278021D01*
X556579Y278056D01*
X556549Y278091D01*
X556529Y278126D01*
X556504Y278161D01*
X556464Y278241D01*
X556419Y278361D01*
X556409Y278401D01*
X556399Y278446D01*
X556394Y278486D01*
X556384Y278531D01*
Y278701D01*
X556394Y278746D01*
X556399Y278786D01*
X556409Y278831D01*
X556419Y278871D01*
X556464Y278991D01*
X556504Y279071D01*
X556529Y279106D01*
X556549Y279141D01*
X556579Y279176D01*
X556604Y279211D01*
X556634Y279241D01*
Y281666D01*
X556644Y281791D01*
X556684Y281916D01*
X556744Y282026D01*
X556824Y282126D01*
X556924Y282206D01*
X557034Y282266D01*
X557159Y282306D01*
X557284Y282316D01*
G37*
G36*
G01X562008D02*
X562133Y282306D01*
X562258Y282266D01*
X562368Y282206D01*
X562468Y282126D01*
X562548Y282026D01*
X562608Y281916D01*
X562648Y281791D01*
X562658Y281666D01*
Y279236D01*
X562688Y279206D01*
X562788Y279066D01*
X562808Y279026D01*
X562823Y278991D01*
X562843Y278951D01*
X562858Y278911D01*
X562868Y278871D01*
X562883Y278826D01*
X562888Y278786D01*
X562898Y278746D01*
X562903Y278701D01*
Y278661D01*
X562908Y278616D01*
X562903Y278571D01*
Y278531D01*
X562898Y278486D01*
X562888Y278446D01*
X562883Y278406D01*
X562868Y278361D01*
X562858Y278321D01*
X562843Y278281D01*
X562823Y278241D01*
X562808Y278206D01*
X562788Y278166D01*
X562688Y278026D01*
X562658Y277996D01*
Y275866D01*
X562648Y275741D01*
X562608Y275616D01*
X562548Y275506D01*
X562468Y275406D01*
X562368Y275326D01*
X562258Y275266D01*
X562133Y275226D01*
X562008Y275216D01*
X561883Y275226D01*
X561758Y275266D01*
X561648Y275326D01*
X561548Y275406D01*
X561468Y275506D01*
X561408Y275616D01*
X561368Y275741D01*
X561358Y275866D01*
Y277991D01*
X561328Y278021D01*
X561303Y278056D01*
X561273Y278091D01*
X561253Y278126D01*
X561228Y278161D01*
X561188Y278241D01*
X561143Y278361D01*
X561133Y278401D01*
X561123Y278446D01*
X561118Y278486D01*
X561108Y278531D01*
Y278701D01*
X561118Y278746D01*
X561123Y278786D01*
X561133Y278831D01*
X561143Y278871D01*
X561188Y278991D01*
X561228Y279071D01*
X561253Y279106D01*
X561273Y279141D01*
X561303Y279176D01*
X561328Y279211D01*
X561358Y279241D01*
Y281666D01*
X561368Y281791D01*
X561408Y281916D01*
X561468Y282026D01*
X561548Y282126D01*
X561648Y282206D01*
X561758Y282266D01*
X561883Y282306D01*
X562008Y282316D01*
G37*
G36*
G01X566733D02*
X566858Y282306D01*
X566983Y282266D01*
X567093Y282206D01*
X567193Y282126D01*
X567273Y282026D01*
X567333Y281916D01*
X567373Y281791D01*
X567383Y281666D01*
Y279236D01*
X567413Y279206D01*
X567513Y279066D01*
X567533Y279026D01*
X567548Y278991D01*
X567568Y278951D01*
X567583Y278911D01*
X567593Y278871D01*
X567608Y278826D01*
X567613Y278786D01*
X567623Y278746D01*
X567628Y278701D01*
Y278661D01*
X567633Y278616D01*
X567628Y278571D01*
Y278531D01*
X567623Y278486D01*
X567613Y278446D01*
X567608Y278406D01*
X567593Y278361D01*
X567583Y278321D01*
X567568Y278281D01*
X567548Y278241D01*
X567533Y278206D01*
X567513Y278166D01*
X567413Y278026D01*
X567383Y277996D01*
Y275866D01*
X567373Y275741D01*
X567333Y275616D01*
X567273Y275506D01*
X567193Y275406D01*
X567093Y275326D01*
X566983Y275266D01*
X566858Y275226D01*
X566733Y275216D01*
X566608Y275226D01*
X566483Y275266D01*
X566373Y275326D01*
X566273Y275406D01*
X566193Y275506D01*
X566133Y275616D01*
X566093Y275741D01*
X566083Y275866D01*
Y277991D01*
X566053Y278021D01*
X566028Y278056D01*
X565998Y278091D01*
X565978Y278126D01*
X565953Y278161D01*
X565913Y278241D01*
X565868Y278361D01*
X565858Y278401D01*
X565848Y278446D01*
X565843Y278486D01*
X565833Y278531D01*
Y278701D01*
X565843Y278746D01*
X565848Y278786D01*
X565858Y278831D01*
X565868Y278871D01*
X565913Y278991D01*
X565953Y279071D01*
X565978Y279106D01*
X565998Y279141D01*
X566028Y279176D01*
X566053Y279211D01*
X566083Y279241D01*
Y281666D01*
X566093Y281791D01*
X566133Y281916D01*
X566193Y282026D01*
X566273Y282126D01*
X566373Y282206D01*
X566483Y282266D01*
X566608Y282306D01*
X566733Y282316D01*
G37*
G36*
G01X571457D02*
X571582Y282306D01*
X571707Y282266D01*
X571817Y282206D01*
X571917Y282126D01*
X571997Y282026D01*
X572057Y281916D01*
X572097Y281791D01*
X572107Y281666D01*
Y279236D01*
X572137Y279206D01*
X572237Y279066D01*
X572257Y279026D01*
X572272Y278991D01*
X572292Y278951D01*
X572307Y278911D01*
X572317Y278871D01*
X572332Y278826D01*
X572337Y278786D01*
X572347Y278746D01*
X572352Y278701D01*
Y278661D01*
X572357Y278616D01*
X572352Y278571D01*
Y278531D01*
X572347Y278486D01*
X572337Y278446D01*
X572332Y278406D01*
X572317Y278361D01*
X572307Y278321D01*
X572292Y278281D01*
X572272Y278241D01*
X572257Y278206D01*
X572237Y278166D01*
X572137Y278026D01*
X572107Y277996D01*
Y275866D01*
X572097Y275741D01*
X572057Y275616D01*
X571997Y275506D01*
X571917Y275406D01*
X571817Y275326D01*
X571707Y275266D01*
X571582Y275226D01*
X571457Y275216D01*
X571332Y275226D01*
X571207Y275266D01*
X571097Y275326D01*
X570997Y275406D01*
X570917Y275506D01*
X570857Y275616D01*
X570817Y275741D01*
X570807Y275866D01*
Y277991D01*
X570777Y278021D01*
X570752Y278056D01*
X570722Y278091D01*
X570702Y278126D01*
X570677Y278161D01*
X570637Y278241D01*
X570592Y278361D01*
X570582Y278401D01*
X570572Y278446D01*
X570567Y278486D01*
X570557Y278531D01*
Y278701D01*
X570567Y278746D01*
X570572Y278786D01*
X570582Y278831D01*
X570592Y278871D01*
X570637Y278991D01*
X570677Y279071D01*
X570702Y279106D01*
X570722Y279141D01*
X570752Y279176D01*
X570777Y279211D01*
X570807Y279241D01*
Y281666D01*
X570817Y281791D01*
X570857Y281916D01*
X570917Y282026D01*
X570997Y282126D01*
X571097Y282206D01*
X571207Y282266D01*
X571332Y282306D01*
X571457Y282316D01*
G37*
G36*
G01X576181D02*
X576306Y282306D01*
X576431Y282266D01*
X576541Y282206D01*
X576641Y282126D01*
X576721Y282026D01*
X576781Y281916D01*
X576821Y281791D01*
X576831Y281666D01*
Y279236D01*
X576861Y279206D01*
X576961Y279066D01*
X576981Y279026D01*
X576996Y278991D01*
X577016Y278951D01*
X577031Y278911D01*
X577041Y278871D01*
X577056Y278826D01*
X577061Y278786D01*
X577071Y278746D01*
X577076Y278701D01*
Y278661D01*
X577081Y278616D01*
X577076Y278571D01*
Y278531D01*
X577071Y278486D01*
X577061Y278446D01*
X577056Y278406D01*
X577041Y278361D01*
X577031Y278321D01*
X577016Y278281D01*
X576996Y278241D01*
X576981Y278206D01*
X576961Y278166D01*
X576861Y278026D01*
X576831Y277996D01*
Y275866D01*
X576821Y275741D01*
X576781Y275616D01*
X576721Y275506D01*
X576641Y275406D01*
X576541Y275326D01*
X576431Y275266D01*
X576306Y275226D01*
X576181Y275216D01*
X576056Y275226D01*
X575931Y275266D01*
X575821Y275326D01*
X575721Y275406D01*
X575641Y275506D01*
X575581Y275616D01*
X575541Y275741D01*
X575531Y275866D01*
Y277991D01*
X575501Y278021D01*
X575476Y278056D01*
X575446Y278091D01*
X575426Y278126D01*
X575401Y278161D01*
X575361Y278241D01*
X575316Y278361D01*
X575306Y278401D01*
X575296Y278446D01*
X575291Y278486D01*
X575281Y278531D01*
Y278701D01*
X575291Y278746D01*
X575296Y278786D01*
X575306Y278831D01*
X575316Y278871D01*
X575361Y278991D01*
X575401Y279071D01*
X575426Y279106D01*
X575446Y279141D01*
X575476Y279176D01*
X575501Y279211D01*
X575531Y279241D01*
Y281666D01*
X575541Y281791D01*
X575581Y281916D01*
X575641Y282026D01*
X575721Y282126D01*
X575821Y282206D01*
X575931Y282266D01*
X576056Y282306D01*
X576181Y282316D01*
G37*
G36*
G01X580906D02*
X581031Y282306D01*
X581156Y282266D01*
X581266Y282206D01*
X581366Y282126D01*
X581446Y282026D01*
X581506Y281916D01*
X581546Y281791D01*
X581556Y281666D01*
Y279236D01*
X581586Y279206D01*
X581686Y279066D01*
X581706Y279026D01*
X581721Y278991D01*
X581741Y278951D01*
X581756Y278911D01*
X581766Y278871D01*
X581781Y278826D01*
X581786Y278786D01*
X581796Y278746D01*
X581801Y278701D01*
Y278661D01*
X581806Y278616D01*
X581801Y278571D01*
Y278531D01*
X581796Y278486D01*
X581786Y278446D01*
X581781Y278406D01*
X581766Y278361D01*
X581756Y278321D01*
X581741Y278281D01*
X581721Y278241D01*
X581706Y278206D01*
X581686Y278166D01*
X581586Y278026D01*
X581556Y277996D01*
Y275866D01*
X581546Y275741D01*
X581506Y275616D01*
X581446Y275506D01*
X581366Y275406D01*
X581266Y275326D01*
X581156Y275266D01*
X581031Y275226D01*
X580906Y275216D01*
X580781Y275226D01*
X580656Y275266D01*
X580546Y275326D01*
X580446Y275406D01*
X580366Y275506D01*
X580306Y275616D01*
X580266Y275741D01*
X580256Y275866D01*
Y277991D01*
X580226Y278021D01*
X580201Y278056D01*
X580171Y278091D01*
X580151Y278126D01*
X580126Y278161D01*
X580086Y278241D01*
X580041Y278361D01*
X580031Y278401D01*
X580021Y278446D01*
X580016Y278486D01*
X580006Y278531D01*
Y278701D01*
X580016Y278746D01*
X580021Y278786D01*
X580031Y278831D01*
X580041Y278871D01*
X580086Y278991D01*
X580126Y279071D01*
X580151Y279106D01*
X580171Y279141D01*
X580201Y279176D01*
X580226Y279211D01*
X580256Y279241D01*
Y281666D01*
X580266Y281791D01*
X580306Y281916D01*
X580366Y282026D01*
X580446Y282126D01*
X580546Y282206D01*
X580656Y282266D01*
X580781Y282306D01*
X580906Y282316D01*
G37*
G36*
G01X585630D02*
X585755Y282306D01*
X585880Y282266D01*
X585990Y282206D01*
X586090Y282126D01*
X586170Y282026D01*
X586230Y281916D01*
X586270Y281791D01*
X586280Y281666D01*
Y279236D01*
X586310Y279206D01*
X586410Y279066D01*
X586430Y279026D01*
X586445Y278991D01*
X586465Y278951D01*
X586480Y278911D01*
X586490Y278871D01*
X586505Y278826D01*
X586510Y278786D01*
X586520Y278746D01*
X586525Y278701D01*
Y278661D01*
X586530Y278616D01*
X586525Y278571D01*
Y278531D01*
X586520Y278486D01*
X586510Y278446D01*
X586505Y278406D01*
X586490Y278361D01*
X586480Y278321D01*
X586465Y278281D01*
X586445Y278241D01*
X586430Y278206D01*
X586410Y278166D01*
X586310Y278026D01*
X586280Y277996D01*
Y275866D01*
X586270Y275741D01*
X586230Y275616D01*
X586170Y275506D01*
X586090Y275406D01*
X585990Y275326D01*
X585880Y275266D01*
X585755Y275226D01*
X585630Y275216D01*
X585505Y275226D01*
X585380Y275266D01*
X585270Y275326D01*
X585170Y275406D01*
X585090Y275506D01*
X585030Y275616D01*
X584990Y275741D01*
X584980Y275866D01*
Y277991D01*
X584950Y278021D01*
X584925Y278056D01*
X584895Y278091D01*
X584875Y278126D01*
X584850Y278161D01*
X584810Y278241D01*
X584765Y278361D01*
X584755Y278401D01*
X584745Y278446D01*
X584740Y278486D01*
X584730Y278531D01*
Y278701D01*
X584740Y278746D01*
X584745Y278786D01*
X584755Y278831D01*
X584765Y278871D01*
X584810Y278991D01*
X584850Y279071D01*
X584875Y279106D01*
X584895Y279141D01*
X584925Y279176D01*
X584950Y279211D01*
X584980Y279241D01*
Y281666D01*
X584990Y281791D01*
X585030Y281916D01*
X585090Y282026D01*
X585170Y282126D01*
X585270Y282206D01*
X585380Y282266D01*
X585505Y282306D01*
X585630Y282316D01*
G37*
G36*
G01X590355D02*
X590480Y282306D01*
X590605Y282266D01*
X590715Y282206D01*
X590815Y282126D01*
X590895Y282026D01*
X590955Y281916D01*
X590995Y281791D01*
X591005Y281666D01*
Y279236D01*
X591035Y279206D01*
X591135Y279066D01*
X591155Y279026D01*
X591170Y278991D01*
X591190Y278951D01*
X591205Y278911D01*
X591215Y278871D01*
X591230Y278826D01*
X591235Y278786D01*
X591245Y278746D01*
X591250Y278701D01*
Y278661D01*
X591255Y278616D01*
X591250Y278571D01*
Y278531D01*
X591245Y278486D01*
X591235Y278446D01*
X591230Y278406D01*
X591215Y278361D01*
X591205Y278321D01*
X591190Y278281D01*
X591170Y278241D01*
X591155Y278206D01*
X591135Y278166D01*
X591035Y278026D01*
X591005Y277996D01*
Y275866D01*
X590995Y275741D01*
X590955Y275616D01*
X590895Y275506D01*
X590815Y275406D01*
X590715Y275326D01*
X590605Y275266D01*
X590480Y275226D01*
X590355Y275216D01*
X590230Y275226D01*
X590105Y275266D01*
X589995Y275326D01*
X589895Y275406D01*
X589815Y275506D01*
X589755Y275616D01*
X589715Y275741D01*
X589705Y275866D01*
Y277991D01*
X589675Y278021D01*
X589650Y278056D01*
X589620Y278091D01*
X589600Y278126D01*
X589575Y278161D01*
X589535Y278241D01*
X589490Y278361D01*
X589480Y278401D01*
X589470Y278446D01*
X589465Y278486D01*
X589455Y278531D01*
Y278701D01*
X589465Y278746D01*
X589470Y278786D01*
X589480Y278831D01*
X589490Y278871D01*
X589535Y278991D01*
X589575Y279071D01*
X589600Y279106D01*
X589620Y279141D01*
X589650Y279176D01*
X589675Y279211D01*
X589705Y279241D01*
Y281666D01*
X589715Y281791D01*
X589755Y281916D01*
X589815Y282026D01*
X589895Y282126D01*
X589995Y282206D01*
X590105Y282266D01*
X590230Y282306D01*
X590355Y282316D01*
G37*
G36*
G01X595079D02*
X595204Y282306D01*
X595329Y282266D01*
X595439Y282206D01*
X595539Y282126D01*
X595619Y282026D01*
X595679Y281916D01*
X595719Y281791D01*
X595729Y281666D01*
Y279236D01*
X595759Y279206D01*
X595859Y279066D01*
X595879Y279026D01*
X595894Y278991D01*
X595914Y278951D01*
X595929Y278911D01*
X595939Y278871D01*
X595954Y278826D01*
X595959Y278786D01*
X595969Y278746D01*
X595974Y278701D01*
Y278661D01*
X595979Y278616D01*
X595974Y278571D01*
Y278531D01*
X595969Y278486D01*
X595959Y278446D01*
X595954Y278406D01*
X595939Y278361D01*
X595929Y278321D01*
X595914Y278281D01*
X595894Y278241D01*
X595879Y278206D01*
X595859Y278166D01*
X595759Y278026D01*
X595729Y277996D01*
Y275866D01*
X595719Y275741D01*
X595679Y275616D01*
X595619Y275506D01*
X595539Y275406D01*
X595439Y275326D01*
X595329Y275266D01*
X595204Y275226D01*
X595079Y275216D01*
X594954Y275226D01*
X594829Y275266D01*
X594719Y275326D01*
X594619Y275406D01*
X594539Y275506D01*
X594479Y275616D01*
X594439Y275741D01*
X594429Y275866D01*
Y277991D01*
X594399Y278021D01*
X594374Y278056D01*
X594344Y278091D01*
X594324Y278126D01*
X594299Y278161D01*
X594259Y278241D01*
X594214Y278361D01*
X594204Y278401D01*
X594194Y278446D01*
X594189Y278486D01*
X594179Y278531D01*
Y278701D01*
X594189Y278746D01*
X594194Y278786D01*
X594204Y278831D01*
X594214Y278871D01*
X594259Y278991D01*
X594299Y279071D01*
X594324Y279106D01*
X594344Y279141D01*
X594374Y279176D01*
X594399Y279211D01*
X594429Y279241D01*
Y281666D01*
X594439Y281791D01*
X594479Y281916D01*
X594539Y282026D01*
X594619Y282126D01*
X594719Y282206D01*
X594829Y282266D01*
X594954Y282306D01*
X595079Y282316D01*
G37*
G36*
G01X599803D02*
X599928Y282306D01*
X600053Y282266D01*
X600163Y282206D01*
X600263Y282126D01*
X600343Y282026D01*
X600403Y281916D01*
X600443Y281791D01*
X600453Y281666D01*
Y279236D01*
X600483Y279206D01*
X600583Y279066D01*
X600603Y279026D01*
X600618Y278991D01*
X600638Y278951D01*
X600653Y278911D01*
X600663Y278871D01*
X600678Y278826D01*
X600683Y278786D01*
X600693Y278746D01*
X600698Y278701D01*
Y278661D01*
X600703Y278616D01*
X600698Y278571D01*
Y278531D01*
X600693Y278486D01*
X600683Y278446D01*
X600678Y278406D01*
X600663Y278361D01*
X600653Y278321D01*
X600638Y278281D01*
X600618Y278241D01*
X600603Y278206D01*
X600583Y278166D01*
X600483Y278026D01*
X600453Y277996D01*
Y275866D01*
X600443Y275741D01*
X600403Y275616D01*
X600343Y275506D01*
X600263Y275406D01*
X600163Y275326D01*
X600053Y275266D01*
X599928Y275226D01*
X599803Y275216D01*
X599678Y275226D01*
X599553Y275266D01*
X599443Y275326D01*
X599343Y275406D01*
X599263Y275506D01*
X599203Y275616D01*
X599163Y275741D01*
X599153Y275866D01*
Y277991D01*
X599123Y278021D01*
X599098Y278056D01*
X599068Y278091D01*
X599048Y278126D01*
X599023Y278161D01*
X598983Y278241D01*
X598938Y278361D01*
X598928Y278401D01*
X598918Y278446D01*
X598913Y278486D01*
X598903Y278531D01*
Y278701D01*
X598913Y278746D01*
X598918Y278786D01*
X598928Y278831D01*
X598938Y278871D01*
X598983Y278991D01*
X599023Y279071D01*
X599048Y279106D01*
X599068Y279141D01*
X599098Y279176D01*
X599123Y279211D01*
X599153Y279241D01*
Y281666D01*
X599163Y281791D01*
X599203Y281916D01*
X599263Y282026D01*
X599343Y282126D01*
X599443Y282206D01*
X599553Y282266D01*
X599678Y282306D01*
X599803Y282316D01*
G37*
G36*
G01X604528D02*
X604653Y282306D01*
X604778Y282266D01*
X604888Y282206D01*
X604988Y282126D01*
X605068Y282026D01*
X605128Y281916D01*
X605168Y281791D01*
X605178Y281666D01*
Y279236D01*
X605208Y279206D01*
X605308Y279066D01*
X605328Y279026D01*
X605343Y278991D01*
X605363Y278951D01*
X605378Y278911D01*
X605388Y278871D01*
X605403Y278826D01*
X605408Y278786D01*
X605418Y278746D01*
X605423Y278701D01*
Y278661D01*
X605428Y278616D01*
X605423Y278571D01*
Y278531D01*
X605418Y278486D01*
X605408Y278446D01*
X605403Y278406D01*
X605388Y278361D01*
X605378Y278321D01*
X605363Y278281D01*
X605343Y278241D01*
X605328Y278206D01*
X605308Y278166D01*
X605208Y278026D01*
X605178Y277996D01*
Y275866D01*
X605168Y275741D01*
X605128Y275616D01*
X605068Y275506D01*
X604988Y275406D01*
X604888Y275326D01*
X604778Y275266D01*
X604653Y275226D01*
X604528Y275216D01*
X604403Y275226D01*
X604278Y275266D01*
X604168Y275326D01*
X604068Y275406D01*
X603988Y275506D01*
X603928Y275616D01*
X603888Y275741D01*
X603878Y275866D01*
Y277991D01*
X603848Y278021D01*
X603823Y278056D01*
X603793Y278091D01*
X603773Y278126D01*
X603748Y278161D01*
X603708Y278241D01*
X603663Y278361D01*
X603653Y278401D01*
X603643Y278446D01*
X603638Y278486D01*
X603628Y278531D01*
Y278701D01*
X603638Y278746D01*
X603643Y278786D01*
X603653Y278831D01*
X603663Y278871D01*
X603708Y278991D01*
X603748Y279071D01*
X603773Y279106D01*
X603793Y279141D01*
X603823Y279176D01*
X603848Y279211D01*
X603878Y279241D01*
Y281666D01*
X603888Y281791D01*
X603928Y281916D01*
X603988Y282026D01*
X604068Y282126D01*
X604168Y282206D01*
X604278Y282266D01*
X604403Y282306D01*
X604528Y282316D01*
G37*
G36*
G01X609252D02*
X609377Y282306D01*
X609502Y282266D01*
X609612Y282206D01*
X609712Y282126D01*
X609792Y282026D01*
X609852Y281916D01*
X609892Y281791D01*
X609902Y281666D01*
Y279236D01*
X609932Y279206D01*
X610032Y279066D01*
X610052Y279026D01*
X610067Y278991D01*
X610087Y278951D01*
X610102Y278911D01*
X610112Y278871D01*
X610127Y278826D01*
X610132Y278786D01*
X610142Y278746D01*
X610147Y278701D01*
Y278661D01*
X610152Y278616D01*
X610147Y278571D01*
Y278531D01*
X610142Y278486D01*
X610132Y278446D01*
X610127Y278406D01*
X610112Y278361D01*
X610102Y278321D01*
X610087Y278281D01*
X610067Y278241D01*
X610052Y278206D01*
X610032Y278166D01*
X609932Y278026D01*
X609902Y277996D01*
Y275866D01*
X609892Y275741D01*
X609852Y275616D01*
X609792Y275506D01*
X609712Y275406D01*
X609612Y275326D01*
X609502Y275266D01*
X609377Y275226D01*
X609252Y275216D01*
X609127Y275226D01*
X609002Y275266D01*
X608892Y275326D01*
X608792Y275406D01*
X608712Y275506D01*
X608652Y275616D01*
X608612Y275741D01*
X608602Y275866D01*
Y277991D01*
X608572Y278021D01*
X608547Y278056D01*
X608517Y278091D01*
X608497Y278126D01*
X608472Y278161D01*
X608432Y278241D01*
X608387Y278361D01*
X608377Y278401D01*
X608367Y278446D01*
X608362Y278486D01*
X608352Y278531D01*
Y278701D01*
X608362Y278746D01*
X608367Y278786D01*
X608377Y278831D01*
X608387Y278871D01*
X608432Y278991D01*
X608472Y279071D01*
X608497Y279106D01*
X608517Y279141D01*
X608547Y279176D01*
X608572Y279211D01*
X608602Y279241D01*
Y281666D01*
X608612Y281791D01*
X608652Y281916D01*
X608712Y282026D01*
X608792Y282126D01*
X608892Y282206D01*
X609002Y282266D01*
X609127Y282306D01*
X609252Y282316D01*
G37*
G36*
G01X613977D02*
X614102Y282306D01*
X614227Y282266D01*
X614337Y282206D01*
X614437Y282126D01*
X614517Y282026D01*
X614577Y281916D01*
X614617Y281791D01*
X614627Y281666D01*
Y279236D01*
X614657Y279206D01*
X614757Y279066D01*
X614777Y279026D01*
X614792Y278991D01*
X614812Y278951D01*
X614827Y278911D01*
X614837Y278871D01*
X614852Y278826D01*
X614857Y278786D01*
X614867Y278746D01*
X614872Y278701D01*
Y278661D01*
X614877Y278616D01*
X614872Y278571D01*
Y278531D01*
X614867Y278486D01*
X614857Y278446D01*
X614852Y278406D01*
X614837Y278361D01*
X614827Y278321D01*
X614812Y278281D01*
X614792Y278241D01*
X614777Y278206D01*
X614757Y278166D01*
X614657Y278026D01*
X614627Y277996D01*
Y275866D01*
X614617Y275741D01*
X614577Y275616D01*
X614517Y275506D01*
X614437Y275406D01*
X614337Y275326D01*
X614227Y275266D01*
X614102Y275226D01*
X613977Y275216D01*
X613852Y275226D01*
X613727Y275266D01*
X613617Y275326D01*
X613517Y275406D01*
X613437Y275506D01*
X613377Y275616D01*
X613337Y275741D01*
X613327Y275866D01*
Y277991D01*
X613297Y278021D01*
X613272Y278056D01*
X613242Y278091D01*
X613222Y278126D01*
X613197Y278161D01*
X613157Y278241D01*
X613112Y278361D01*
X613102Y278401D01*
X613092Y278446D01*
X613087Y278486D01*
X613077Y278531D01*
Y278701D01*
X613087Y278746D01*
X613092Y278786D01*
X613102Y278831D01*
X613112Y278871D01*
X613157Y278991D01*
X613197Y279071D01*
X613222Y279106D01*
X613242Y279141D01*
X613272Y279176D01*
X613297Y279211D01*
X613327Y279241D01*
Y281666D01*
X613337Y281791D01*
X613377Y281916D01*
X613437Y282026D01*
X613517Y282126D01*
X613617Y282206D01*
X613727Y282266D01*
X613852Y282306D01*
X613977Y282316D01*
G37*
G36*
G01X618701D02*
X618826Y282306D01*
X618951Y282266D01*
X619061Y282206D01*
X619161Y282126D01*
X619241Y282026D01*
X619301Y281916D01*
X619341Y281791D01*
X619351Y281666D01*
Y279236D01*
X619381Y279206D01*
X619481Y279066D01*
X619501Y279026D01*
X619516Y278991D01*
X619536Y278951D01*
X619551Y278911D01*
X619561Y278871D01*
X619576Y278826D01*
X619581Y278786D01*
X619591Y278746D01*
X619596Y278701D01*
Y278661D01*
X619601Y278616D01*
X619596Y278571D01*
Y278531D01*
X619591Y278486D01*
X619581Y278446D01*
X619576Y278406D01*
X619561Y278361D01*
X619551Y278321D01*
X619536Y278281D01*
X619516Y278241D01*
X619501Y278206D01*
X619481Y278166D01*
X619381Y278026D01*
X619351Y277996D01*
Y275866D01*
X619341Y275741D01*
X619301Y275616D01*
X619241Y275506D01*
X619161Y275406D01*
X619061Y275326D01*
X618951Y275266D01*
X618826Y275226D01*
X618701Y275216D01*
X618576Y275226D01*
X618451Y275266D01*
X618341Y275326D01*
X618241Y275406D01*
X618161Y275506D01*
X618101Y275616D01*
X618061Y275741D01*
X618051Y275866D01*
Y277991D01*
X618021Y278021D01*
X617996Y278056D01*
X617966Y278091D01*
X617946Y278126D01*
X617921Y278161D01*
X617881Y278241D01*
X617836Y278361D01*
X617826Y278401D01*
X617816Y278446D01*
X617811Y278486D01*
X617801Y278531D01*
Y278701D01*
X617811Y278746D01*
X617816Y278786D01*
X617826Y278831D01*
X617836Y278871D01*
X617881Y278991D01*
X617921Y279071D01*
X617946Y279106D01*
X617966Y279141D01*
X617996Y279176D01*
X618021Y279211D01*
X618051Y279241D01*
Y281666D01*
X618061Y281791D01*
X618101Y281916D01*
X618161Y282026D01*
X618241Y282126D01*
X618341Y282206D01*
X618451Y282266D01*
X618576Y282306D01*
X618701Y282316D01*
G37*
G36*
G01X623425D02*
X623550Y282306D01*
X623675Y282266D01*
X623785Y282206D01*
X623885Y282126D01*
X623965Y282026D01*
X624025Y281916D01*
X624065Y281791D01*
X624075Y281666D01*
Y279236D01*
X624105Y279206D01*
X624205Y279066D01*
X624225Y279026D01*
X624240Y278991D01*
X624260Y278951D01*
X624275Y278911D01*
X624285Y278871D01*
X624300Y278826D01*
X624305Y278786D01*
X624315Y278746D01*
X624320Y278701D01*
Y278661D01*
X624325Y278616D01*
X624320Y278571D01*
Y278531D01*
X624315Y278486D01*
X624305Y278446D01*
X624300Y278406D01*
X624285Y278361D01*
X624275Y278321D01*
X624260Y278281D01*
X624240Y278241D01*
X624225Y278206D01*
X624205Y278166D01*
X624105Y278026D01*
X624075Y277996D01*
Y275866D01*
X624065Y275741D01*
X624025Y275616D01*
X623965Y275506D01*
X623885Y275406D01*
X623785Y275326D01*
X623675Y275266D01*
X623550Y275226D01*
X623425Y275216D01*
X623300Y275226D01*
X623175Y275266D01*
X623065Y275326D01*
X622965Y275406D01*
X622885Y275506D01*
X622825Y275616D01*
X622785Y275741D01*
X622775Y275866D01*
Y277991D01*
X622745Y278021D01*
X622720Y278056D01*
X622690Y278091D01*
X622670Y278126D01*
X622645Y278161D01*
X622605Y278241D01*
X622560Y278361D01*
X622550Y278401D01*
X622540Y278446D01*
X622535Y278486D01*
X622525Y278531D01*
Y278701D01*
X622535Y278746D01*
X622540Y278786D01*
X622550Y278831D01*
X622560Y278871D01*
X622605Y278991D01*
X622645Y279071D01*
X622670Y279106D01*
X622690Y279141D01*
X622720Y279176D01*
X622745Y279211D01*
X622775Y279241D01*
Y281666D01*
X622785Y281791D01*
X622825Y281916D01*
X622885Y282026D01*
X622965Y282126D01*
X623065Y282206D01*
X623175Y282266D01*
X623300Y282306D01*
X623425Y282316D01*
G37*
G36*
G01X628150D02*
X628275Y282306D01*
X628400Y282266D01*
X628510Y282206D01*
X628610Y282126D01*
X628690Y282026D01*
X628750Y281916D01*
X628790Y281791D01*
X628800Y281666D01*
Y279236D01*
X628830Y279206D01*
X628930Y279066D01*
X628950Y279026D01*
X628965Y278991D01*
X628985Y278951D01*
X629000Y278911D01*
X629010Y278871D01*
X629025Y278826D01*
X629030Y278786D01*
X629040Y278746D01*
X629045Y278701D01*
Y278661D01*
X629050Y278616D01*
X629045Y278571D01*
Y278531D01*
X629040Y278486D01*
X629030Y278446D01*
X629025Y278406D01*
X629010Y278361D01*
X629000Y278321D01*
X628985Y278281D01*
X628965Y278241D01*
X628950Y278206D01*
X628930Y278166D01*
X628830Y278026D01*
X628800Y277996D01*
Y275866D01*
X628790Y275741D01*
X628750Y275616D01*
X628690Y275506D01*
X628610Y275406D01*
X628510Y275326D01*
X628400Y275266D01*
X628275Y275226D01*
X628150Y275216D01*
X628025Y275226D01*
X627900Y275266D01*
X627790Y275326D01*
X627690Y275406D01*
X627610Y275506D01*
X627550Y275616D01*
X627510Y275741D01*
X627500Y275866D01*
Y277991D01*
X627470Y278021D01*
X627445Y278056D01*
X627415Y278091D01*
X627395Y278126D01*
X627370Y278161D01*
X627330Y278241D01*
X627285Y278361D01*
X627275Y278401D01*
X627265Y278446D01*
X627260Y278486D01*
X627250Y278531D01*
Y278701D01*
X627260Y278746D01*
X627265Y278786D01*
X627275Y278831D01*
X627285Y278871D01*
X627330Y278991D01*
X627370Y279071D01*
X627395Y279106D01*
X627415Y279141D01*
X627445Y279176D01*
X627470Y279211D01*
X627500Y279241D01*
Y281666D01*
X627510Y281791D01*
X627550Y281916D01*
X627610Y282026D01*
X627690Y282126D01*
X627790Y282206D01*
X627900Y282266D01*
X628025Y282306D01*
X628150Y282316D01*
G37*
G36*
G01X632874D02*
X632999Y282306D01*
X633124Y282266D01*
X633234Y282206D01*
X633334Y282126D01*
X633414Y282026D01*
X633474Y281916D01*
X633514Y281791D01*
X633524Y281666D01*
Y279236D01*
X633554Y279206D01*
X633654Y279066D01*
X633674Y279026D01*
X633689Y278991D01*
X633709Y278951D01*
X633724Y278911D01*
X633734Y278871D01*
X633749Y278826D01*
X633754Y278786D01*
X633764Y278746D01*
X633769Y278701D01*
Y278661D01*
X633774Y278616D01*
X633769Y278571D01*
Y278531D01*
X633764Y278486D01*
X633754Y278446D01*
X633749Y278406D01*
X633734Y278361D01*
X633724Y278321D01*
X633709Y278281D01*
X633689Y278241D01*
X633674Y278206D01*
X633654Y278166D01*
X633554Y278026D01*
X633524Y277996D01*
Y275866D01*
X633514Y275741D01*
X633474Y275616D01*
X633414Y275506D01*
X633334Y275406D01*
X633234Y275326D01*
X633124Y275266D01*
X632999Y275226D01*
X632874Y275216D01*
X632749Y275226D01*
X632624Y275266D01*
X632514Y275326D01*
X632414Y275406D01*
X632334Y275506D01*
X632274Y275616D01*
X632234Y275741D01*
X632224Y275866D01*
Y277991D01*
X632194Y278021D01*
X632169Y278056D01*
X632139Y278091D01*
X632119Y278126D01*
X632094Y278161D01*
X632054Y278241D01*
X632009Y278361D01*
X631999Y278401D01*
X631989Y278446D01*
X631984Y278486D01*
X631974Y278531D01*
Y278701D01*
X631984Y278746D01*
X631989Y278786D01*
X631999Y278831D01*
X632009Y278871D01*
X632054Y278991D01*
X632094Y279071D01*
X632119Y279106D01*
X632139Y279141D01*
X632169Y279176D01*
X632194Y279211D01*
X632224Y279241D01*
Y281666D01*
X632234Y281791D01*
X632274Y281916D01*
X632334Y282026D01*
X632414Y282126D01*
X632514Y282206D01*
X632624Y282266D01*
X632749Y282306D01*
X632874Y282316D01*
G37*
G36*
G01X637599D02*
X637724Y282306D01*
X637849Y282266D01*
X637959Y282206D01*
X638059Y282126D01*
X638139Y282026D01*
X638199Y281916D01*
X638239Y281791D01*
X638249Y281666D01*
Y279236D01*
X638279Y279206D01*
X638379Y279066D01*
X638399Y279026D01*
X638414Y278991D01*
X638434Y278951D01*
X638449Y278911D01*
X638459Y278871D01*
X638474Y278826D01*
X638479Y278786D01*
X638489Y278746D01*
X638494Y278701D01*
Y278661D01*
X638499Y278616D01*
X638494Y278571D01*
Y278531D01*
X638489Y278486D01*
X638479Y278446D01*
X638474Y278406D01*
X638459Y278361D01*
X638449Y278321D01*
X638434Y278281D01*
X638414Y278241D01*
X638399Y278206D01*
X638379Y278166D01*
X638279Y278026D01*
X638249Y277996D01*
Y275866D01*
X638239Y275741D01*
X638199Y275616D01*
X638139Y275506D01*
X638059Y275406D01*
X637959Y275326D01*
X637849Y275266D01*
X637724Y275226D01*
X637599Y275216D01*
X637474Y275226D01*
X637349Y275266D01*
X637239Y275326D01*
X637139Y275406D01*
X637059Y275506D01*
X636999Y275616D01*
X636959Y275741D01*
X636949Y275866D01*
Y277991D01*
X636919Y278021D01*
X636894Y278056D01*
X636864Y278091D01*
X636844Y278126D01*
X636819Y278161D01*
X636779Y278241D01*
X636734Y278361D01*
X636724Y278401D01*
X636714Y278446D01*
X636709Y278486D01*
X636699Y278531D01*
Y278701D01*
X636709Y278746D01*
X636714Y278786D01*
X636724Y278831D01*
X636734Y278871D01*
X636779Y278991D01*
X636819Y279071D01*
X636844Y279106D01*
X636864Y279141D01*
X636894Y279176D01*
X636919Y279211D01*
X636949Y279241D01*
Y281666D01*
X636959Y281791D01*
X636999Y281916D01*
X637059Y282026D01*
X637139Y282126D01*
X637239Y282206D01*
X637349Y282266D01*
X637474Y282306D01*
X637599Y282316D01*
G37*
G36*
G01X642323D02*
X642448Y282306D01*
X642573Y282266D01*
X642683Y282206D01*
X642783Y282126D01*
X642863Y282026D01*
X642923Y281916D01*
X642963Y281791D01*
X642973Y281666D01*
Y279236D01*
X643003Y279206D01*
X643103Y279066D01*
X643123Y279026D01*
X643138Y278991D01*
X643158Y278951D01*
X643173Y278911D01*
X643183Y278871D01*
X643198Y278826D01*
X643203Y278786D01*
X643213Y278746D01*
X643218Y278701D01*
Y278661D01*
X643223Y278616D01*
X643218Y278571D01*
Y278531D01*
X643213Y278486D01*
X643203Y278446D01*
X643198Y278406D01*
X643183Y278361D01*
X643173Y278321D01*
X643158Y278281D01*
X643138Y278241D01*
X643123Y278206D01*
X643103Y278166D01*
X643003Y278026D01*
X642973Y277996D01*
Y275866D01*
X642963Y275741D01*
X642923Y275616D01*
X642863Y275506D01*
X642783Y275406D01*
X642683Y275326D01*
X642573Y275266D01*
X642448Y275226D01*
X642323Y275216D01*
X642198Y275226D01*
X642073Y275266D01*
X641963Y275326D01*
X641863Y275406D01*
X641783Y275506D01*
X641723Y275616D01*
X641683Y275741D01*
X641673Y275866D01*
Y277991D01*
X641643Y278021D01*
X641618Y278056D01*
X641588Y278091D01*
X641568Y278126D01*
X641543Y278161D01*
X641503Y278241D01*
X641458Y278361D01*
X641448Y278401D01*
X641438Y278446D01*
X641433Y278486D01*
X641423Y278531D01*
Y278701D01*
X641433Y278746D01*
X641438Y278786D01*
X641448Y278831D01*
X641458Y278871D01*
X641503Y278991D01*
X641543Y279071D01*
X641568Y279106D01*
X641588Y279141D01*
X641618Y279176D01*
X641643Y279211D01*
X641673Y279241D01*
Y281666D01*
X641683Y281791D01*
X641723Y281916D01*
X641783Y282026D01*
X641863Y282126D01*
X641963Y282206D01*
X642073Y282266D01*
X642198Y282306D01*
X642323Y282316D01*
G37*
G36*
G01X647047D02*
X647172Y282306D01*
X647297Y282266D01*
X647407Y282206D01*
X647507Y282126D01*
X647587Y282026D01*
X647647Y281916D01*
X647687Y281791D01*
X647697Y281666D01*
Y279236D01*
X647727Y279206D01*
X647827Y279066D01*
X647847Y279026D01*
X647862Y278991D01*
X647882Y278951D01*
X647897Y278911D01*
X647907Y278871D01*
X647922Y278826D01*
X647927Y278786D01*
X647937Y278746D01*
X647942Y278701D01*
Y278661D01*
X647947Y278616D01*
X647942Y278571D01*
Y278531D01*
X647937Y278486D01*
X647927Y278446D01*
X647922Y278406D01*
X647907Y278361D01*
X647897Y278321D01*
X647882Y278281D01*
X647862Y278241D01*
X647847Y278206D01*
X647827Y278166D01*
X647727Y278026D01*
X647697Y277996D01*
Y275866D01*
X647687Y275741D01*
X647647Y275616D01*
X647587Y275506D01*
X647507Y275406D01*
X647407Y275326D01*
X647297Y275266D01*
X647172Y275226D01*
X647047Y275216D01*
X646922Y275226D01*
X646797Y275266D01*
X646687Y275326D01*
X646587Y275406D01*
X646507Y275506D01*
X646447Y275616D01*
X646407Y275741D01*
X646397Y275866D01*
Y277991D01*
X646367Y278021D01*
X646342Y278056D01*
X646312Y278091D01*
X646292Y278126D01*
X646267Y278161D01*
X646227Y278241D01*
X646182Y278361D01*
X646172Y278401D01*
X646162Y278446D01*
X646157Y278486D01*
X646147Y278531D01*
Y278701D01*
X646157Y278746D01*
X646162Y278786D01*
X646172Y278831D01*
X646182Y278871D01*
X646227Y278991D01*
X646267Y279071D01*
X646292Y279106D01*
X646312Y279141D01*
X646342Y279176D01*
X646367Y279211D01*
X646397Y279241D01*
Y281666D01*
X646407Y281791D01*
X646447Y281916D01*
X646507Y282026D01*
X646587Y282126D01*
X646687Y282206D01*
X646797Y282266D01*
X646922Y282306D01*
X647047Y282316D01*
G37*
G36*
G01X651772D02*
X651897Y282306D01*
X652022Y282266D01*
X652132Y282206D01*
X652232Y282126D01*
X652312Y282026D01*
X652372Y281916D01*
X652412Y281791D01*
X652422Y281666D01*
Y279236D01*
X652452Y279206D01*
X652552Y279066D01*
X652572Y279026D01*
X652587Y278991D01*
X652607Y278951D01*
X652622Y278911D01*
X652632Y278871D01*
X652647Y278826D01*
X652652Y278786D01*
X652662Y278746D01*
X652667Y278701D01*
Y278661D01*
X652672Y278616D01*
X652667Y278571D01*
Y278531D01*
X652662Y278486D01*
X652652Y278446D01*
X652647Y278406D01*
X652632Y278361D01*
X652622Y278321D01*
X652607Y278281D01*
X652587Y278241D01*
X652572Y278206D01*
X652552Y278166D01*
X652452Y278026D01*
X652422Y277996D01*
Y275866D01*
X652412Y275741D01*
X652372Y275616D01*
X652312Y275506D01*
X652232Y275406D01*
X652132Y275326D01*
X652022Y275266D01*
X651897Y275226D01*
X651772Y275216D01*
X651647Y275226D01*
X651522Y275266D01*
X651412Y275326D01*
X651312Y275406D01*
X651232Y275506D01*
X651172Y275616D01*
X651132Y275741D01*
X651122Y275866D01*
Y277991D01*
X651092Y278021D01*
X651067Y278056D01*
X651037Y278091D01*
X651017Y278126D01*
X650992Y278161D01*
X650952Y278241D01*
X650907Y278361D01*
X650897Y278401D01*
X650887Y278446D01*
X650882Y278486D01*
X650872Y278531D01*
Y278701D01*
X650882Y278746D01*
X650887Y278786D01*
X650897Y278831D01*
X650907Y278871D01*
X650952Y278991D01*
X650992Y279071D01*
X651017Y279106D01*
X651037Y279141D01*
X651067Y279176D01*
X651092Y279211D01*
X651122Y279241D01*
Y281666D01*
X651132Y281791D01*
X651172Y281916D01*
X651232Y282026D01*
X651312Y282126D01*
X651412Y282206D01*
X651522Y282266D01*
X651647Y282306D01*
X651772Y282316D01*
G37*
G36*
G01X665945D02*
X666070Y282306D01*
X666195Y282266D01*
X666305Y282206D01*
X666405Y282126D01*
X666485Y282026D01*
X666545Y281916D01*
X666585Y281791D01*
X666595Y281666D01*
Y279236D01*
X666625Y279206D01*
X666725Y279066D01*
X666745Y279026D01*
X666760Y278991D01*
X666780Y278951D01*
X666795Y278911D01*
X666805Y278871D01*
X666820Y278826D01*
X666825Y278786D01*
X666835Y278746D01*
X666840Y278701D01*
Y278661D01*
X666845Y278616D01*
X666840Y278571D01*
Y278531D01*
X666835Y278486D01*
X666825Y278446D01*
X666820Y278406D01*
X666805Y278361D01*
X666795Y278321D01*
X666780Y278281D01*
X666760Y278241D01*
X666745Y278206D01*
X666725Y278166D01*
X666625Y278026D01*
X666595Y277996D01*
Y275866D01*
X666585Y275741D01*
X666545Y275616D01*
X666485Y275506D01*
X666405Y275406D01*
X666305Y275326D01*
X666195Y275266D01*
X666070Y275226D01*
X665945Y275216D01*
X665820Y275226D01*
X665695Y275266D01*
X665585Y275326D01*
X665485Y275406D01*
X665405Y275506D01*
X665345Y275616D01*
X665305Y275741D01*
X665295Y275866D01*
Y277991D01*
X665265Y278021D01*
X665240Y278056D01*
X665210Y278091D01*
X665190Y278126D01*
X665165Y278161D01*
X665125Y278241D01*
X665080Y278361D01*
X665070Y278401D01*
X665060Y278446D01*
X665055Y278486D01*
X665045Y278531D01*
Y278701D01*
X665055Y278746D01*
X665060Y278786D01*
X665070Y278831D01*
X665080Y278871D01*
X665125Y278991D01*
X665165Y279071D01*
X665190Y279106D01*
X665210Y279141D01*
X665240Y279176D01*
X665265Y279211D01*
X665295Y279241D01*
Y281666D01*
X665305Y281791D01*
X665345Y281916D01*
X665405Y282026D01*
X665485Y282126D01*
X665585Y282206D01*
X665695Y282266D01*
X665820Y282306D01*
X665945Y282316D01*
G37*
G36*
G01X670670D02*
X670795Y282306D01*
X670920Y282266D01*
X671030Y282206D01*
X671130Y282126D01*
X671210Y282026D01*
X671270Y281916D01*
X671310Y281791D01*
X671320Y281666D01*
Y279236D01*
X671350Y279206D01*
X671450Y279066D01*
X671470Y279026D01*
X671485Y278991D01*
X671505Y278951D01*
X671520Y278911D01*
X671530Y278871D01*
X671545Y278826D01*
X671550Y278786D01*
X671560Y278746D01*
X671565Y278701D01*
Y278661D01*
X671570Y278616D01*
X671565Y278571D01*
Y278531D01*
X671560Y278486D01*
X671550Y278446D01*
X671545Y278406D01*
X671530Y278361D01*
X671520Y278321D01*
X671505Y278281D01*
X671485Y278241D01*
X671470Y278206D01*
X671450Y278166D01*
X671350Y278026D01*
X671320Y277996D01*
Y275866D01*
X671310Y275741D01*
X671270Y275616D01*
X671210Y275506D01*
X671130Y275406D01*
X671030Y275326D01*
X670920Y275266D01*
X670795Y275226D01*
X670670Y275216D01*
X670545Y275226D01*
X670420Y275266D01*
X670310Y275326D01*
X670210Y275406D01*
X670130Y275506D01*
X670070Y275616D01*
X670030Y275741D01*
X670020Y275866D01*
Y277991D01*
X669990Y278021D01*
X669965Y278056D01*
X669935Y278091D01*
X669915Y278126D01*
X669890Y278161D01*
X669850Y278241D01*
X669805Y278361D01*
X669795Y278401D01*
X669785Y278446D01*
X669780Y278486D01*
X669770Y278531D01*
Y278701D01*
X669780Y278746D01*
X669785Y278786D01*
X669795Y278831D01*
X669805Y278871D01*
X669850Y278991D01*
X669890Y279071D01*
X669915Y279106D01*
X669935Y279141D01*
X669965Y279176D01*
X669990Y279211D01*
X670020Y279241D01*
Y281666D01*
X670030Y281791D01*
X670070Y281916D01*
X670130Y282026D01*
X670210Y282126D01*
X670310Y282206D01*
X670420Y282266D01*
X670545Y282306D01*
X670670Y282316D01*
G37*
G36*
G01X675394D02*
X675519Y282306D01*
X675644Y282266D01*
X675754Y282206D01*
X675854Y282126D01*
X675934Y282026D01*
X675994Y281916D01*
X676034Y281791D01*
X676044Y281666D01*
Y279236D01*
X676074Y279206D01*
X676174Y279066D01*
X676194Y279026D01*
X676209Y278991D01*
X676229Y278951D01*
X676244Y278911D01*
X676254Y278871D01*
X676269Y278826D01*
X676274Y278786D01*
X676284Y278746D01*
X676289Y278701D01*
Y278661D01*
X676294Y278616D01*
X676289Y278571D01*
Y278531D01*
X676284Y278486D01*
X676274Y278446D01*
X676269Y278406D01*
X676254Y278361D01*
X676244Y278321D01*
X676229Y278281D01*
X676209Y278241D01*
X676194Y278206D01*
X676174Y278166D01*
X676074Y278026D01*
X676044Y277996D01*
Y275866D01*
X676034Y275741D01*
X675994Y275616D01*
X675934Y275506D01*
X675854Y275406D01*
X675754Y275326D01*
X675644Y275266D01*
X675519Y275226D01*
X675394Y275216D01*
X675269Y275226D01*
X675144Y275266D01*
X675034Y275326D01*
X674934Y275406D01*
X674854Y275506D01*
X674794Y275616D01*
X674754Y275741D01*
X674744Y275866D01*
Y277991D01*
X674714Y278021D01*
X674689Y278056D01*
X674659Y278091D01*
X674639Y278126D01*
X674614Y278161D01*
X674574Y278241D01*
X674529Y278361D01*
X674519Y278401D01*
X674509Y278446D01*
X674504Y278486D01*
X674494Y278531D01*
Y278701D01*
X674504Y278746D01*
X674509Y278786D01*
X674519Y278831D01*
X674529Y278871D01*
X674574Y278991D01*
X674614Y279071D01*
X674639Y279106D01*
X674659Y279141D01*
X674689Y279176D01*
X674714Y279211D01*
X674744Y279241D01*
Y281666D01*
X674754Y281791D01*
X674794Y281916D01*
X674854Y282026D01*
X674934Y282126D01*
X675034Y282206D01*
X675144Y282266D01*
X675269Y282306D01*
X675394Y282316D01*
G37*
G36*
G01X680118D02*
X680243Y282306D01*
X680368Y282266D01*
X680478Y282206D01*
X680578Y282126D01*
X680658Y282026D01*
X680718Y281916D01*
X680758Y281791D01*
X680768Y281666D01*
Y279236D01*
X680798Y279206D01*
X680898Y279066D01*
X680918Y279026D01*
X680933Y278991D01*
X680953Y278951D01*
X680968Y278911D01*
X680978Y278871D01*
X680993Y278826D01*
X680998Y278786D01*
X681008Y278746D01*
X681013Y278701D01*
Y278661D01*
X681018Y278616D01*
X681013Y278571D01*
Y278531D01*
X681008Y278486D01*
X680998Y278446D01*
X680993Y278406D01*
X680978Y278361D01*
X680968Y278321D01*
X680953Y278281D01*
X680933Y278241D01*
X680918Y278206D01*
X680898Y278166D01*
X680798Y278026D01*
X680768Y277996D01*
Y275866D01*
X680758Y275741D01*
X680718Y275616D01*
X680658Y275506D01*
X680578Y275406D01*
X680478Y275326D01*
X680368Y275266D01*
X680243Y275226D01*
X680118Y275216D01*
X679993Y275226D01*
X679868Y275266D01*
X679758Y275326D01*
X679658Y275406D01*
X679578Y275506D01*
X679518Y275616D01*
X679478Y275741D01*
X679468Y275866D01*
Y277991D01*
X679438Y278021D01*
X679413Y278056D01*
X679383Y278091D01*
X679363Y278126D01*
X679338Y278161D01*
X679298Y278241D01*
X679253Y278361D01*
X679243Y278401D01*
X679233Y278446D01*
X679228Y278486D01*
X679218Y278531D01*
Y278701D01*
X679228Y278746D01*
X679233Y278786D01*
X679243Y278831D01*
X679253Y278871D01*
X679298Y278991D01*
X679338Y279071D01*
X679363Y279106D01*
X679383Y279141D01*
X679413Y279176D01*
X679438Y279211D01*
X679468Y279241D01*
Y281666D01*
X679478Y281791D01*
X679518Y281916D01*
X679578Y282026D01*
X679658Y282126D01*
X679758Y282206D01*
X679868Y282266D01*
X679993Y282306D01*
X680118Y282316D01*
G37*
G36*
G01X684843D02*
X684968Y282306D01*
X685093Y282266D01*
X685203Y282206D01*
X685303Y282126D01*
X685383Y282026D01*
X685443Y281916D01*
X685483Y281791D01*
X685493Y281666D01*
Y279236D01*
X685523Y279206D01*
X685623Y279066D01*
X685643Y279026D01*
X685658Y278991D01*
X685678Y278951D01*
X685693Y278911D01*
X685703Y278871D01*
X685718Y278826D01*
X685723Y278786D01*
X685733Y278746D01*
X685738Y278701D01*
Y278661D01*
X685743Y278616D01*
X685738Y278571D01*
Y278531D01*
X685733Y278486D01*
X685723Y278446D01*
X685718Y278406D01*
X685703Y278361D01*
X685693Y278321D01*
X685678Y278281D01*
X685658Y278241D01*
X685643Y278206D01*
X685623Y278166D01*
X685523Y278026D01*
X685493Y277996D01*
Y275866D01*
X685483Y275741D01*
X685443Y275616D01*
X685383Y275506D01*
X685303Y275406D01*
X685203Y275326D01*
X685093Y275266D01*
X684968Y275226D01*
X684843Y275216D01*
X684718Y275226D01*
X684593Y275266D01*
X684483Y275326D01*
X684383Y275406D01*
X684303Y275506D01*
X684243Y275616D01*
X684203Y275741D01*
X684193Y275866D01*
Y277991D01*
X684163Y278021D01*
X684138Y278056D01*
X684108Y278091D01*
X684088Y278126D01*
X684063Y278161D01*
X684023Y278241D01*
X683978Y278361D01*
X683968Y278401D01*
X683958Y278446D01*
X683953Y278486D01*
X683943Y278531D01*
Y278701D01*
X683953Y278746D01*
X683958Y278786D01*
X683968Y278831D01*
X683978Y278871D01*
X684023Y278991D01*
X684063Y279071D01*
X684088Y279106D01*
X684108Y279141D01*
X684138Y279176D01*
X684163Y279211D01*
X684193Y279241D01*
Y281666D01*
X684203Y281791D01*
X684243Y281916D01*
X684303Y282026D01*
X684383Y282126D01*
X684483Y282206D01*
X684593Y282266D01*
X684718Y282306D01*
X684843Y282316D01*
G37*
G36*
G01X689567D02*
X689692Y282306D01*
X689817Y282266D01*
X689927Y282206D01*
X690027Y282126D01*
X690107Y282026D01*
X690167Y281916D01*
X690207Y281791D01*
X690217Y281666D01*
Y279236D01*
X690247Y279206D01*
X690347Y279066D01*
X690367Y279026D01*
X690382Y278991D01*
X690402Y278951D01*
X690417Y278911D01*
X690427Y278871D01*
X690442Y278826D01*
X690447Y278786D01*
X690457Y278746D01*
X690462Y278701D01*
Y278661D01*
X690467Y278616D01*
X690462Y278571D01*
Y278531D01*
X690457Y278486D01*
X690447Y278446D01*
X690442Y278406D01*
X690427Y278361D01*
X690417Y278321D01*
X690402Y278281D01*
X690382Y278241D01*
X690367Y278206D01*
X690347Y278166D01*
X690247Y278026D01*
X690217Y277996D01*
Y275866D01*
X690207Y275741D01*
X690167Y275616D01*
X690107Y275506D01*
X690027Y275406D01*
X689927Y275326D01*
X689817Y275266D01*
X689692Y275226D01*
X689567Y275216D01*
X689442Y275226D01*
X689317Y275266D01*
X689207Y275326D01*
X689107Y275406D01*
X689027Y275506D01*
X688967Y275616D01*
X688927Y275741D01*
X688917Y275866D01*
Y277991D01*
X688887Y278021D01*
X688862Y278056D01*
X688832Y278091D01*
X688812Y278126D01*
X688787Y278161D01*
X688747Y278241D01*
X688702Y278361D01*
X688692Y278401D01*
X688682Y278446D01*
X688677Y278486D01*
X688667Y278531D01*
Y278701D01*
X688677Y278746D01*
X688682Y278786D01*
X688692Y278831D01*
X688702Y278871D01*
X688747Y278991D01*
X688787Y279071D01*
X688812Y279106D01*
X688832Y279141D01*
X688862Y279176D01*
X688887Y279211D01*
X688917Y279241D01*
Y281666D01*
X688927Y281791D01*
X688967Y281916D01*
X689027Y282026D01*
X689107Y282126D01*
X689207Y282206D01*
X689317Y282266D01*
X689442Y282306D01*
X689567Y282316D01*
G37*
G36*
G01X694292D02*
X694417Y282306D01*
X694542Y282266D01*
X694652Y282206D01*
X694752Y282126D01*
X694832Y282026D01*
X694892Y281916D01*
X694932Y281791D01*
X694942Y281666D01*
Y279236D01*
X694972Y279206D01*
X695072Y279066D01*
X695092Y279026D01*
X695107Y278991D01*
X695127Y278951D01*
X695142Y278911D01*
X695152Y278871D01*
X695167Y278826D01*
X695172Y278786D01*
X695182Y278746D01*
X695187Y278701D01*
Y278661D01*
X695192Y278616D01*
X695187Y278571D01*
Y278531D01*
X695182Y278486D01*
X695172Y278446D01*
X695167Y278406D01*
X695152Y278361D01*
X695142Y278321D01*
X695127Y278281D01*
X695107Y278241D01*
X695092Y278206D01*
X695072Y278166D01*
X694972Y278026D01*
X694942Y277996D01*
Y275866D01*
X694932Y275741D01*
X694892Y275616D01*
X694832Y275506D01*
X694752Y275406D01*
X694652Y275326D01*
X694542Y275266D01*
X694417Y275226D01*
X694292Y275216D01*
X694167Y275226D01*
X694042Y275266D01*
X693932Y275326D01*
X693832Y275406D01*
X693752Y275506D01*
X693692Y275616D01*
X693652Y275741D01*
X693642Y275866D01*
Y277991D01*
X693612Y278021D01*
X693587Y278056D01*
X693557Y278091D01*
X693537Y278126D01*
X693512Y278161D01*
X693472Y278241D01*
X693427Y278361D01*
X693417Y278401D01*
X693407Y278446D01*
X693402Y278486D01*
X693392Y278531D01*
Y278701D01*
X693402Y278746D01*
X693407Y278786D01*
X693417Y278831D01*
X693427Y278871D01*
X693472Y278991D01*
X693512Y279071D01*
X693537Y279106D01*
X693557Y279141D01*
X693587Y279176D01*
X693612Y279211D01*
X693642Y279241D01*
Y281666D01*
X693652Y281791D01*
X693692Y281916D01*
X693752Y282026D01*
X693832Y282126D01*
X693932Y282206D01*
X694042Y282266D01*
X694167Y282306D01*
X694292Y282316D01*
G37*
G36*
G01X699016D02*
X699141Y282306D01*
X699266Y282266D01*
X699376Y282206D01*
X699476Y282126D01*
X699556Y282026D01*
X699616Y281916D01*
X699656Y281791D01*
X699666Y281666D01*
Y279236D01*
X699696Y279206D01*
X699796Y279066D01*
X699816Y279026D01*
X699831Y278991D01*
X699851Y278951D01*
X699866Y278911D01*
X699876Y278871D01*
X699891Y278826D01*
X699896Y278786D01*
X699906Y278746D01*
X699911Y278701D01*
Y278661D01*
X699916Y278616D01*
X699911Y278571D01*
Y278531D01*
X699906Y278486D01*
X699896Y278446D01*
X699891Y278406D01*
X699876Y278361D01*
X699866Y278321D01*
X699851Y278281D01*
X699831Y278241D01*
X699816Y278206D01*
X699796Y278166D01*
X699696Y278026D01*
X699666Y277996D01*
Y275866D01*
X699656Y275741D01*
X699616Y275616D01*
X699556Y275506D01*
X699476Y275406D01*
X699376Y275326D01*
X699266Y275266D01*
X699141Y275226D01*
X699016Y275216D01*
X698891Y275226D01*
X698766Y275266D01*
X698656Y275326D01*
X698556Y275406D01*
X698476Y275506D01*
X698416Y275616D01*
X698376Y275741D01*
X698366Y275866D01*
Y277991D01*
X698336Y278021D01*
X698311Y278056D01*
X698281Y278091D01*
X698261Y278126D01*
X698236Y278161D01*
X698196Y278241D01*
X698151Y278361D01*
X698141Y278401D01*
X698131Y278446D01*
X698126Y278486D01*
X698116Y278531D01*
Y278701D01*
X698126Y278746D01*
X698131Y278786D01*
X698141Y278831D01*
X698151Y278871D01*
X698196Y278991D01*
X698236Y279071D01*
X698261Y279106D01*
X698281Y279141D01*
X698311Y279176D01*
X698336Y279211D01*
X698366Y279241D01*
Y281666D01*
X698376Y281791D01*
X698416Y281916D01*
X698476Y282026D01*
X698556Y282126D01*
X698656Y282206D01*
X698766Y282266D01*
X698891Y282306D01*
X699016Y282316D01*
G37*
G36*
G01X703740D02*
X703865Y282306D01*
X703990Y282266D01*
X704100Y282206D01*
X704200Y282126D01*
X704280Y282026D01*
X704340Y281916D01*
X704380Y281791D01*
X704390Y281666D01*
Y279236D01*
X704420Y279206D01*
X704520Y279066D01*
X704540Y279026D01*
X704555Y278991D01*
X704575Y278951D01*
X704590Y278911D01*
X704600Y278871D01*
X704615Y278826D01*
X704620Y278786D01*
X704630Y278746D01*
X704635Y278701D01*
Y278661D01*
X704640Y278616D01*
X704635Y278571D01*
Y278531D01*
X704630Y278486D01*
X704620Y278446D01*
X704615Y278406D01*
X704600Y278361D01*
X704590Y278321D01*
X704575Y278281D01*
X704555Y278241D01*
X704540Y278206D01*
X704520Y278166D01*
X704420Y278026D01*
X704390Y277996D01*
Y275866D01*
X704380Y275741D01*
X704340Y275616D01*
X704280Y275506D01*
X704200Y275406D01*
X704100Y275326D01*
X703990Y275266D01*
X703865Y275226D01*
X703740Y275216D01*
X703615Y275226D01*
X703490Y275266D01*
X703380Y275326D01*
X703280Y275406D01*
X703200Y275506D01*
X703140Y275616D01*
X703100Y275741D01*
X703090Y275866D01*
Y277991D01*
X703060Y278021D01*
X703035Y278056D01*
X703005Y278091D01*
X702985Y278126D01*
X702960Y278161D01*
X702920Y278241D01*
X702875Y278361D01*
X702865Y278401D01*
X702855Y278446D01*
X702850Y278486D01*
X702840Y278531D01*
Y278701D01*
X702850Y278746D01*
X702855Y278786D01*
X702865Y278831D01*
X702875Y278871D01*
X702920Y278991D01*
X702960Y279071D01*
X702985Y279106D01*
X703005Y279141D01*
X703035Y279176D01*
X703060Y279211D01*
X703090Y279241D01*
Y281666D01*
X703100Y281791D01*
X703140Y281916D01*
X703200Y282026D01*
X703280Y282126D01*
X703380Y282206D01*
X703490Y282266D01*
X703615Y282306D01*
X703740Y282316D01*
G37*
G36*
G01X708465D02*
X708590Y282306D01*
X708715Y282266D01*
X708825Y282206D01*
X708925Y282126D01*
X709005Y282026D01*
X709065Y281916D01*
X709105Y281791D01*
X709115Y281666D01*
Y279236D01*
X709145Y279206D01*
X709245Y279066D01*
X709265Y279026D01*
X709280Y278991D01*
X709300Y278951D01*
X709315Y278911D01*
X709325Y278871D01*
X709340Y278826D01*
X709345Y278786D01*
X709355Y278746D01*
X709360Y278701D01*
Y278661D01*
X709365Y278616D01*
X709360Y278571D01*
Y278531D01*
X709355Y278486D01*
X709345Y278446D01*
X709340Y278406D01*
X709325Y278361D01*
X709315Y278321D01*
X709300Y278281D01*
X709280Y278241D01*
X709265Y278206D01*
X709245Y278166D01*
X709145Y278026D01*
X709115Y277996D01*
Y275866D01*
X709105Y275741D01*
X709065Y275616D01*
X709005Y275506D01*
X708925Y275406D01*
X708825Y275326D01*
X708715Y275266D01*
X708590Y275226D01*
X708465Y275216D01*
X708340Y275226D01*
X708215Y275266D01*
X708105Y275326D01*
X708005Y275406D01*
X707925Y275506D01*
X707865Y275616D01*
X707825Y275741D01*
X707815Y275866D01*
Y277991D01*
X707785Y278021D01*
X707760Y278056D01*
X707730Y278091D01*
X707710Y278126D01*
X707685Y278161D01*
X707645Y278241D01*
X707600Y278361D01*
X707590Y278401D01*
X707580Y278446D01*
X707575Y278486D01*
X707565Y278531D01*
Y278701D01*
X707575Y278746D01*
X707580Y278786D01*
X707590Y278831D01*
X707600Y278871D01*
X707645Y278991D01*
X707685Y279071D01*
X707710Y279106D01*
X707730Y279141D01*
X707760Y279176D01*
X707785Y279211D01*
X707815Y279241D01*
Y281666D01*
X707825Y281791D01*
X707865Y281916D01*
X707925Y282026D01*
X708005Y282126D01*
X708105Y282206D01*
X708215Y282266D01*
X708340Y282306D01*
X708465Y282316D01*
G37*
G36*
G01X713189D02*
X713314Y282306D01*
X713439Y282266D01*
X713549Y282206D01*
X713649Y282126D01*
X713729Y282026D01*
X713789Y281916D01*
X713829Y281791D01*
X713839Y281666D01*
Y279236D01*
X713869Y279206D01*
X713969Y279066D01*
X713989Y279026D01*
X714004Y278991D01*
X714024Y278951D01*
X714039Y278911D01*
X714049Y278871D01*
X714064Y278826D01*
X714069Y278786D01*
X714079Y278746D01*
X714084Y278701D01*
Y278661D01*
X714089Y278616D01*
X714084Y278571D01*
Y278531D01*
X714079Y278486D01*
X714069Y278446D01*
X714064Y278406D01*
X714049Y278361D01*
X714039Y278321D01*
X714024Y278281D01*
X714004Y278241D01*
X713989Y278206D01*
X713969Y278166D01*
X713869Y278026D01*
X713839Y277996D01*
Y275866D01*
X713829Y275741D01*
X713789Y275616D01*
X713729Y275506D01*
X713649Y275406D01*
X713549Y275326D01*
X713439Y275266D01*
X713314Y275226D01*
X713189Y275216D01*
X713064Y275226D01*
X712939Y275266D01*
X712829Y275326D01*
X712729Y275406D01*
X712649Y275506D01*
X712589Y275616D01*
X712549Y275741D01*
X712539Y275866D01*
Y277991D01*
X712509Y278021D01*
X712484Y278056D01*
X712454Y278091D01*
X712434Y278126D01*
X712409Y278161D01*
X712369Y278241D01*
X712324Y278361D01*
X712314Y278401D01*
X712304Y278446D01*
X712299Y278486D01*
X712289Y278531D01*
Y278701D01*
X712299Y278746D01*
X712304Y278786D01*
X712314Y278831D01*
X712324Y278871D01*
X712369Y278991D01*
X712409Y279071D01*
X712434Y279106D01*
X712454Y279141D01*
X712484Y279176D01*
X712509Y279211D01*
X712539Y279241D01*
Y281666D01*
X712549Y281791D01*
X712589Y281916D01*
X712649Y282026D01*
X712729Y282126D01*
X712829Y282206D01*
X712939Y282266D01*
X713064Y282306D01*
X713189Y282316D01*
G37*
G36*
G01X717914D02*
X718039Y282306D01*
X718164Y282266D01*
X718274Y282206D01*
X718374Y282126D01*
X718454Y282026D01*
X718514Y281916D01*
X718554Y281791D01*
X718564Y281666D01*
Y279236D01*
X718594Y279206D01*
X718694Y279066D01*
X718714Y279026D01*
X718729Y278991D01*
X718749Y278951D01*
X718764Y278911D01*
X718774Y278871D01*
X718789Y278826D01*
X718794Y278786D01*
X718804Y278746D01*
X718809Y278701D01*
Y278661D01*
X718814Y278616D01*
X718809Y278571D01*
Y278531D01*
X718804Y278486D01*
X718794Y278446D01*
X718789Y278406D01*
X718774Y278361D01*
X718764Y278321D01*
X718749Y278281D01*
X718729Y278241D01*
X718714Y278206D01*
X718694Y278166D01*
X718594Y278026D01*
X718564Y277996D01*
Y275866D01*
X718554Y275741D01*
X718514Y275616D01*
X718454Y275506D01*
X718374Y275406D01*
X718274Y275326D01*
X718164Y275266D01*
X718039Y275226D01*
X717914Y275216D01*
X717789Y275226D01*
X717664Y275266D01*
X717554Y275326D01*
X717454Y275406D01*
X717374Y275506D01*
X717314Y275616D01*
X717274Y275741D01*
X717264Y275866D01*
Y277991D01*
X717234Y278021D01*
X717209Y278056D01*
X717179Y278091D01*
X717159Y278126D01*
X717134Y278161D01*
X717094Y278241D01*
X717049Y278361D01*
X717039Y278401D01*
X717029Y278446D01*
X717024Y278486D01*
X717014Y278531D01*
Y278701D01*
X717024Y278746D01*
X717029Y278786D01*
X717039Y278831D01*
X717049Y278871D01*
X717094Y278991D01*
X717134Y279071D01*
X717159Y279106D01*
X717179Y279141D01*
X717209Y279176D01*
X717234Y279211D01*
X717264Y279241D01*
Y281666D01*
X717274Y281791D01*
X717314Y281916D01*
X717374Y282026D01*
X717454Y282126D01*
X717554Y282206D01*
X717664Y282266D01*
X717789Y282306D01*
X717914Y282316D01*
G37*
G36*
G01X722638D02*
X722763Y282306D01*
X722888Y282266D01*
X722998Y282206D01*
X723098Y282126D01*
X723178Y282026D01*
X723238Y281916D01*
X723278Y281791D01*
X723288Y281666D01*
Y279236D01*
X723318Y279206D01*
X723418Y279066D01*
X723438Y279026D01*
X723453Y278991D01*
X723473Y278951D01*
X723488Y278911D01*
X723498Y278871D01*
X723513Y278826D01*
X723518Y278786D01*
X723528Y278746D01*
X723533Y278701D01*
Y278661D01*
X723538Y278616D01*
X723533Y278571D01*
Y278531D01*
X723528Y278486D01*
X723518Y278446D01*
X723513Y278406D01*
X723498Y278361D01*
X723488Y278321D01*
X723473Y278281D01*
X723453Y278241D01*
X723438Y278206D01*
X723418Y278166D01*
X723318Y278026D01*
X723288Y277996D01*
Y275866D01*
X723278Y275741D01*
X723238Y275616D01*
X723178Y275506D01*
X723098Y275406D01*
X722998Y275326D01*
X722888Y275266D01*
X722763Y275226D01*
X722638Y275216D01*
X722513Y275226D01*
X722388Y275266D01*
X722278Y275326D01*
X722178Y275406D01*
X722098Y275506D01*
X722038Y275616D01*
X721998Y275741D01*
X721988Y275866D01*
Y277991D01*
X721958Y278021D01*
X721933Y278056D01*
X721903Y278091D01*
X721883Y278126D01*
X721858Y278161D01*
X721818Y278241D01*
X721773Y278361D01*
X721763Y278401D01*
X721753Y278446D01*
X721748Y278486D01*
X721738Y278531D01*
Y278701D01*
X721748Y278746D01*
X721753Y278786D01*
X721763Y278831D01*
X721773Y278871D01*
X721818Y278991D01*
X721858Y279071D01*
X721883Y279106D01*
X721903Y279141D01*
X721933Y279176D01*
X721958Y279211D01*
X721988Y279241D01*
Y281666D01*
X721998Y281791D01*
X722038Y281916D01*
X722098Y282026D01*
X722178Y282126D01*
X722278Y282206D01*
X722388Y282266D01*
X722513Y282306D01*
X722638Y282316D01*
G37*
G36*
G01X727362D02*
X727487Y282306D01*
X727612Y282266D01*
X727722Y282206D01*
X727822Y282126D01*
X727902Y282026D01*
X727962Y281916D01*
X728002Y281791D01*
X728012Y281666D01*
Y279236D01*
X728042Y279206D01*
X728142Y279066D01*
X728162Y279026D01*
X728177Y278991D01*
X728197Y278951D01*
X728212Y278911D01*
X728222Y278871D01*
X728237Y278826D01*
X728242Y278786D01*
X728252Y278746D01*
X728257Y278701D01*
Y278661D01*
X728262Y278616D01*
X728257Y278571D01*
Y278531D01*
X728252Y278486D01*
X728242Y278446D01*
X728237Y278406D01*
X728222Y278361D01*
X728212Y278321D01*
X728197Y278281D01*
X728177Y278241D01*
X728162Y278206D01*
X728142Y278166D01*
X728042Y278026D01*
X728012Y277996D01*
Y275866D01*
X728002Y275741D01*
X727962Y275616D01*
X727902Y275506D01*
X727822Y275406D01*
X727722Y275326D01*
X727612Y275266D01*
X727487Y275226D01*
X727362Y275216D01*
X727237Y275226D01*
X727112Y275266D01*
X727002Y275326D01*
X726902Y275406D01*
X726822Y275506D01*
X726762Y275616D01*
X726722Y275741D01*
X726712Y275866D01*
Y277991D01*
X726682Y278021D01*
X726657Y278056D01*
X726627Y278091D01*
X726607Y278126D01*
X726582Y278161D01*
X726542Y278241D01*
X726497Y278361D01*
X726487Y278401D01*
X726477Y278446D01*
X726472Y278486D01*
X726462Y278531D01*
Y278701D01*
X726472Y278746D01*
X726477Y278786D01*
X726487Y278831D01*
X726497Y278871D01*
X726542Y278991D01*
X726582Y279071D01*
X726607Y279106D01*
X726627Y279141D01*
X726657Y279176D01*
X726682Y279211D01*
X726712Y279241D01*
Y281666D01*
X726722Y281791D01*
X726762Y281916D01*
X726822Y282026D01*
X726902Y282126D01*
X727002Y282206D01*
X727112Y282266D01*
X727237Y282306D01*
X727362Y282316D01*
G37*
G36*
G01X732087D02*
X732212Y282306D01*
X732337Y282266D01*
X732447Y282206D01*
X732547Y282126D01*
X732627Y282026D01*
X732687Y281916D01*
X732727Y281791D01*
X732737Y281666D01*
Y279236D01*
X732767Y279206D01*
X732867Y279066D01*
X732887Y279026D01*
X732902Y278991D01*
X732922Y278951D01*
X732937Y278911D01*
X732947Y278871D01*
X732962Y278826D01*
X732967Y278786D01*
X732977Y278746D01*
X732982Y278701D01*
Y278661D01*
X732987Y278616D01*
X732982Y278571D01*
Y278531D01*
X732977Y278486D01*
X732967Y278446D01*
X732962Y278406D01*
X732947Y278361D01*
X732937Y278321D01*
X732922Y278281D01*
X732902Y278241D01*
X732887Y278206D01*
X732867Y278166D01*
X732767Y278026D01*
X732737Y277996D01*
Y275866D01*
X732727Y275741D01*
X732687Y275616D01*
X732627Y275506D01*
X732547Y275406D01*
X732447Y275326D01*
X732337Y275266D01*
X732212Y275226D01*
X732087Y275216D01*
X731962Y275226D01*
X731837Y275266D01*
X731727Y275326D01*
X731627Y275406D01*
X731547Y275506D01*
X731487Y275616D01*
X731447Y275741D01*
X731437Y275866D01*
Y277991D01*
X731407Y278021D01*
X731382Y278056D01*
X731352Y278091D01*
X731332Y278126D01*
X731307Y278161D01*
X731267Y278241D01*
X731222Y278361D01*
X731212Y278401D01*
X731202Y278446D01*
X731197Y278486D01*
X731187Y278531D01*
Y278701D01*
X731197Y278746D01*
X731202Y278786D01*
X731212Y278831D01*
X731222Y278871D01*
X731267Y278991D01*
X731307Y279071D01*
X731332Y279106D01*
X731352Y279141D01*
X731382Y279176D01*
X731407Y279211D01*
X731437Y279241D01*
Y281666D01*
X731447Y281791D01*
X731487Y281916D01*
X731547Y282026D01*
X731627Y282126D01*
X731727Y282206D01*
X731837Y282266D01*
X731962Y282306D01*
X732087Y282316D01*
G37*
G36*
G01X736811D02*
X736936Y282306D01*
X737061Y282266D01*
X737171Y282206D01*
X737271Y282126D01*
X737351Y282026D01*
X737411Y281916D01*
X737451Y281791D01*
X737461Y281666D01*
Y279236D01*
X737491Y279206D01*
X737591Y279066D01*
X737611Y279026D01*
X737626Y278991D01*
X737646Y278951D01*
X737661Y278911D01*
X737671Y278871D01*
X737686Y278826D01*
X737691Y278786D01*
X737701Y278746D01*
X737706Y278701D01*
Y278661D01*
X737711Y278616D01*
X737706Y278571D01*
Y278531D01*
X737701Y278486D01*
X737691Y278446D01*
X737686Y278406D01*
X737671Y278361D01*
X737661Y278321D01*
X737646Y278281D01*
X737626Y278241D01*
X737611Y278206D01*
X737591Y278166D01*
X737491Y278026D01*
X737461Y277996D01*
Y275866D01*
X737451Y275741D01*
X737411Y275616D01*
X737351Y275506D01*
X737271Y275406D01*
X737171Y275326D01*
X737061Y275266D01*
X736936Y275226D01*
X736811Y275216D01*
X736686Y275226D01*
X736561Y275266D01*
X736451Y275326D01*
X736351Y275406D01*
X736271Y275506D01*
X736211Y275616D01*
X736171Y275741D01*
X736161Y275866D01*
Y277991D01*
X736131Y278021D01*
X736106Y278056D01*
X736076Y278091D01*
X736056Y278126D01*
X736031Y278161D01*
X735991Y278241D01*
X735946Y278361D01*
X735936Y278401D01*
X735926Y278446D01*
X735921Y278486D01*
X735911Y278531D01*
Y278701D01*
X735921Y278746D01*
X735926Y278786D01*
X735936Y278831D01*
X735946Y278871D01*
X735991Y278991D01*
X736031Y279071D01*
X736056Y279106D01*
X736076Y279141D01*
X736106Y279176D01*
X736131Y279211D01*
X736161Y279241D01*
Y281666D01*
X736171Y281791D01*
X736211Y281916D01*
X736271Y282026D01*
X736351Y282126D01*
X736451Y282206D01*
X736561Y282266D01*
X736686Y282306D01*
X736811Y282316D01*
G37*
G36*
G01X741536D02*
X741661Y282306D01*
X741786Y282266D01*
X741896Y282206D01*
X741996Y282126D01*
X742076Y282026D01*
X742136Y281916D01*
X742176Y281791D01*
X742186Y281666D01*
Y279236D01*
X742216Y279206D01*
X742316Y279066D01*
X742336Y279026D01*
X742351Y278991D01*
X742371Y278951D01*
X742386Y278911D01*
X742396Y278871D01*
X742411Y278826D01*
X742416Y278786D01*
X742426Y278746D01*
X742431Y278701D01*
Y278661D01*
X742436Y278616D01*
X742431Y278571D01*
Y278531D01*
X742426Y278486D01*
X742416Y278446D01*
X742411Y278406D01*
X742396Y278361D01*
X742386Y278321D01*
X742371Y278281D01*
X742351Y278241D01*
X742336Y278206D01*
X742316Y278166D01*
X742216Y278026D01*
X742186Y277996D01*
Y275866D01*
X742176Y275741D01*
X742136Y275616D01*
X742076Y275506D01*
X741996Y275406D01*
X741896Y275326D01*
X741786Y275266D01*
X741661Y275226D01*
X741536Y275216D01*
X741411Y275226D01*
X741286Y275266D01*
X741176Y275326D01*
X741076Y275406D01*
X740996Y275506D01*
X740936Y275616D01*
X740896Y275741D01*
X740886Y275866D01*
Y277991D01*
X740856Y278021D01*
X740831Y278056D01*
X740801Y278091D01*
X740781Y278126D01*
X740756Y278161D01*
X740716Y278241D01*
X740671Y278361D01*
X740661Y278401D01*
X740651Y278446D01*
X740646Y278486D01*
X740636Y278531D01*
Y278701D01*
X740646Y278746D01*
X740651Y278786D01*
X740661Y278831D01*
X740671Y278871D01*
X740716Y278991D01*
X740756Y279071D01*
X740781Y279106D01*
X740801Y279141D01*
X740831Y279176D01*
X740856Y279211D01*
X740886Y279241D01*
Y281666D01*
X740896Y281791D01*
X740936Y281916D01*
X740996Y282026D01*
X741076Y282126D01*
X741176Y282206D01*
X741286Y282266D01*
X741411Y282306D01*
X741536Y282316D01*
G37*
G36*
G01X746260D02*
X746385Y282306D01*
X746510Y282266D01*
X746620Y282206D01*
X746720Y282126D01*
X746800Y282026D01*
X746860Y281916D01*
X746900Y281791D01*
X746910Y281666D01*
Y279236D01*
X746940Y279206D01*
X747040Y279066D01*
X747060Y279026D01*
X747075Y278991D01*
X747095Y278951D01*
X747110Y278911D01*
X747120Y278871D01*
X747135Y278826D01*
X747140Y278786D01*
X747150Y278746D01*
X747155Y278701D01*
Y278661D01*
X747160Y278616D01*
X747155Y278571D01*
Y278531D01*
X747150Y278486D01*
X747140Y278446D01*
X747135Y278406D01*
X747120Y278361D01*
X747110Y278321D01*
X747095Y278281D01*
X747075Y278241D01*
X747060Y278206D01*
X747040Y278166D01*
X746940Y278026D01*
X746910Y277996D01*
Y275866D01*
X746900Y275741D01*
X746860Y275616D01*
X746800Y275506D01*
X746720Y275406D01*
X746620Y275326D01*
X746510Y275266D01*
X746385Y275226D01*
X746260Y275216D01*
X746135Y275226D01*
X746010Y275266D01*
X745900Y275326D01*
X745800Y275406D01*
X745720Y275506D01*
X745660Y275616D01*
X745620Y275741D01*
X745610Y275866D01*
Y277991D01*
X745580Y278021D01*
X745555Y278056D01*
X745525Y278091D01*
X745505Y278126D01*
X745480Y278161D01*
X745440Y278241D01*
X745395Y278361D01*
X745385Y278401D01*
X745375Y278446D01*
X745370Y278486D01*
X745360Y278531D01*
Y278701D01*
X745370Y278746D01*
X745375Y278786D01*
X745385Y278831D01*
X745395Y278871D01*
X745440Y278991D01*
X745480Y279071D01*
X745505Y279106D01*
X745525Y279141D01*
X745555Y279176D01*
X745580Y279211D01*
X745610Y279241D01*
Y281666D01*
X745620Y281791D01*
X745660Y281916D01*
X745720Y282026D01*
X745800Y282126D01*
X745900Y282206D01*
X746010Y282266D01*
X746135Y282306D01*
X746260Y282316D01*
G37*
G54D12*
X11500Y68500D03*
X12000Y279000D03*
X816000Y280000D03*
G54D132*
X792515Y137280D03*
G54D141*
X792900Y180250D03*
Y179750D03*
X792800Y183850D03*
Y184350D03*
G54D142*
G01X70851Y-113865D02*
Y-96365D01*
G01X80021D02*
Y-113865D01*
G01Y-105115D02*
X70851D01*
G01X92936Y-113865D02*
X91626Y-113573D01*
X90316Y-112407D01*
X89442Y-110365D01*
X89006Y-108032D01*
X89442Y-105698D01*
X90316Y-103657D01*
X91626Y-102490D01*
X92936Y-102199D01*
X94246Y-102490D01*
X95556Y-103657D01*
X96429Y-105698D01*
X96648Y-108032D01*
X96429Y-110365D01*
X95556Y-112407D01*
X94246Y-113573D01*
X92936Y-113865D01*
G01X106724D02*
Y-102199D01*
G01Y-105115D02*
X107598Y-103657D01*
X108908Y-102490D01*
X110654Y-102199D01*
X112182Y-102490D01*
X113493Y-103657D01*
X114148Y-105698D01*
Y-113865D01*
G01X124661Y-105990D02*
X131648D01*
X130993Y-103948D01*
X129901Y-102782D01*
X128373Y-102199D01*
X126844Y-102490D01*
X125534Y-103365D01*
X124661Y-105407D01*
X124224Y-107157D01*
Y-108907D01*
X124661Y-110657D01*
X125753Y-112407D01*
X127063Y-113573D01*
X128591Y-113865D01*
X130119Y-113282D01*
X131648Y-111532D01*
G01X140851Y-119115D02*
X142161Y-119698D01*
X143908Y-119115D01*
X144999Y-117949D01*
X145873Y-116490D01*
X147182Y-111824D01*
X150021Y-102199D01*
G01X143034D02*
X147182Y-111824D01*
G01X182182Y-104532D02*
X183056Y-103657D01*
X183711Y-102199D01*
X184148Y-100156D01*
X183711Y-98407D01*
X182838Y-97240D01*
X181309Y-96365D01*
X175414D01*
Y-113865D01*
X182619D01*
X184148Y-112699D01*
X185021Y-110948D01*
X185458Y-108907D01*
X185021Y-106865D01*
X183711Y-105115D01*
X182182Y-104532D01*
X175414D01*
G01X201866Y-113865D02*
Y-102199D01*
G01Y-104240D02*
X200993Y-103074D01*
X199682Y-102490D01*
X198154Y-102199D01*
X196626Y-102782D01*
X195316Y-103948D01*
X194442Y-105698D01*
X194006Y-108032D01*
X194442Y-110365D01*
X195316Y-112115D01*
X196626Y-113282D01*
X198154Y-113865D01*
X199682Y-113573D01*
X200993Y-112699D01*
X201866Y-111532D01*
G01X219366Y-96365D02*
Y-113865D01*
G01Y-111241D02*
X218493Y-112699D01*
X217182Y-113573D01*
X215654Y-113865D01*
X213908Y-113282D01*
X212598Y-111824D01*
X211724Y-110074D01*
X211506Y-108032D01*
X211724Y-105990D01*
X212598Y-104240D01*
X213908Y-102782D01*
X215654Y-102199D01*
X217182Y-102490D01*
X218274Y-103074D01*
X219366Y-104240D01*
G01X229879Y-118240D02*
X231408Y-119407D01*
X233154Y-119698D01*
X234682Y-119407D01*
X235993Y-117949D01*
X236866Y-115907D01*
Y-102199D01*
G01Y-104532D02*
X235993Y-103365D01*
X234682Y-102490D01*
X233154Y-102199D01*
X231408Y-102782D01*
X230316Y-103948D01*
X229442Y-105990D01*
X229006Y-108032D01*
X229224Y-109782D01*
X230098Y-111824D01*
X231408Y-113282D01*
X233154Y-113865D01*
X234464Y-113573D01*
X235993Y-112407D01*
X236866Y-111241D01*
G01X247161Y-105990D02*
X254148D01*
X253493Y-103948D01*
X252401Y-102782D01*
X250873Y-102199D01*
X249344Y-102490D01*
X248034Y-103365D01*
X247161Y-105407D01*
X246724Y-107157D01*
Y-108907D01*
X247161Y-110657D01*
X248253Y-112407D01*
X249563Y-113573D01*
X251091Y-113865D01*
X252619Y-113282D01*
X254148Y-111532D01*
G01X264879Y-113865D02*
Y-102199D01*
G01Y-104532D02*
X265971Y-103365D01*
X267063Y-102490D01*
X268591Y-102199D01*
X269682Y-102490D01*
X270993Y-103365D01*
G01X298569Y-113865D02*
Y-96365D01*
X303809D01*
X305556Y-97240D01*
X306866Y-99282D01*
X307303Y-101615D01*
X306866Y-103948D01*
X305774Y-105698D01*
X303809Y-106574D01*
X298569D01*
G01X324366Y-113865D02*
Y-102199D01*
G01Y-104240D02*
X323493Y-103074D01*
X322182Y-102490D01*
X320654Y-102199D01*
X319126Y-102782D01*
X317816Y-103948D01*
X316942Y-105698D01*
X316506Y-108032D01*
X316942Y-110365D01*
X317816Y-112115D01*
X319126Y-113282D01*
X320654Y-113865D01*
X322182Y-113573D01*
X323493Y-112699D01*
X324366Y-111532D01*
G01X334224Y-113865D02*
Y-102199D01*
G01Y-105115D02*
X335098Y-103657D01*
X336408Y-102490D01*
X338154Y-102199D01*
X339682Y-102490D01*
X340993Y-103657D01*
X341648Y-105698D01*
Y-113865D01*
G01X355436Y-96365D02*
Y-113865D01*
G01X352379Y-102199D02*
X358493D01*
G01X369224Y-113865D02*
Y-96365D01*
G01Y-104823D02*
X370316Y-103365D01*
X371408Y-102490D01*
X373154Y-102199D01*
X374464Y-102490D01*
X375993Y-103657D01*
X376648Y-105407D01*
Y-113865D01*
G01X387161Y-105990D02*
X394148D01*
X393493Y-103948D01*
X392401Y-102782D01*
X390873Y-102199D01*
X389344Y-102490D01*
X388034Y-103365D01*
X387161Y-105407D01*
X386724Y-107157D01*
Y-108907D01*
X387161Y-110657D01*
X388253Y-112407D01*
X389563Y-113573D01*
X391091Y-113865D01*
X392619Y-113282D01*
X394148Y-111532D01*
G01X404879Y-113865D02*
Y-102199D01*
G01Y-104532D02*
X405971Y-103365D01*
X407063Y-102490D01*
X408591Y-102199D01*
X409682Y-102490D01*
X410993Y-103365D01*
G01X437259Y-113865D02*
Y-96365D01*
X442936Y-110948D01*
X448613Y-96365D01*
Y-113865D01*
G01X462182Y-104532D02*
X463056Y-103657D01*
X463711Y-102199D01*
X464148Y-100156D01*
X463711Y-98407D01*
X462838Y-97240D01*
X461309Y-96365D01*
X455414D01*
Y-113865D01*
X462619D01*
X464148Y-112699D01*
X465021Y-110948D01*
X465458Y-108907D01*
X465021Y-106865D01*
X463711Y-105115D01*
X462182Y-104532D01*
X455414D01*
G01X227259Y-68865D02*
Y-51365D01*
X232936Y-65948D01*
X238613Y-51365D01*
Y-68865D01*
G01X250436D02*
X249126Y-68573D01*
X247816Y-67407D01*
X246942Y-65365D01*
X246506Y-63032D01*
X246942Y-60698D01*
X247816Y-58657D01*
X249126Y-57490D01*
X250436Y-57199D01*
X251746Y-57490D01*
X253056Y-58657D01*
X253929Y-60698D01*
X254148Y-63032D01*
X253929Y-65365D01*
X253056Y-67407D01*
X251746Y-68573D01*
X250436Y-68865D01*
G01X271866Y-51365D02*
Y-68865D01*
G01Y-66241D02*
X270993Y-67699D01*
X269682Y-68573D01*
X268154Y-68865D01*
X266408Y-68282D01*
X265098Y-66824D01*
X264224Y-65074D01*
X264006Y-63032D01*
X264224Y-60990D01*
X265098Y-59240D01*
X266408Y-57782D01*
X268154Y-57199D01*
X269682Y-57490D01*
X270774Y-58074D01*
X271866Y-59240D01*
G01X282161Y-60990D02*
X289148D01*
X288493Y-58948D01*
X287401Y-57782D01*
X285873Y-57199D01*
X284344Y-57490D01*
X283034Y-58365D01*
X282161Y-60407D01*
X281724Y-62157D01*
Y-63907D01*
X282161Y-65657D01*
X283253Y-67407D01*
X284563Y-68573D01*
X286091Y-68865D01*
X287619Y-68282D01*
X289148Y-66532D01*
G01X302936Y-68865D02*
Y-51365D01*
G01X542319Y-68865D02*
Y-51365D01*
X547559D01*
X549306Y-52240D01*
X550616Y-54282D01*
X551053Y-56615D01*
X550616Y-58948D01*
X549524Y-60698D01*
X547559Y-61574D01*
X542319D01*
G01X568989Y-52824D02*
X567679Y-51948D01*
X566151Y-51365D01*
X564404D01*
X562439Y-52240D01*
X560911Y-53698D01*
X559819Y-55449D01*
X558946Y-58365D01*
X558727Y-60990D01*
X559164Y-63615D01*
X559819Y-65365D01*
X561129Y-67115D01*
X562658Y-68282D01*
X564186Y-68865D01*
X565714D01*
X567243Y-68282D01*
X568553Y-67407D01*
X569645Y-66241D01*
G01X583432Y-59532D02*
X584306Y-58657D01*
X584961Y-57199D01*
X585398Y-55156D01*
X584961Y-53407D01*
X584088Y-52240D01*
X582559Y-51365D01*
X576664D01*
Y-68865D01*
X583869D01*
X585398Y-67699D01*
X586271Y-65948D01*
X586708Y-63907D01*
X586271Y-61865D01*
X584961Y-60115D01*
X583432Y-59532D01*
X576664D01*
G01X592636Y-74698D02*
X605736D01*
G01X611664Y-68865D02*
Y-51365D01*
X621708Y-68865D01*
Y-51365D01*
G01X634186Y-68865D02*
X632439Y-68573D01*
X630911Y-67407D01*
X629601Y-65657D01*
X628727Y-63615D01*
X628291Y-61282D01*
Y-58948D01*
X628727Y-56615D01*
X629601Y-54573D01*
X630911Y-52824D01*
X632439Y-51657D01*
X634186Y-51365D01*
X635932Y-51657D01*
X637461Y-52824D01*
X638771Y-54573D01*
X639645Y-56615D01*
X640081Y-58948D01*
Y-61282D01*
X639645Y-63615D01*
X638771Y-65657D01*
X637461Y-67407D01*
X635932Y-68573D01*
X634186Y-68865D01*
G01X555436Y-113865D02*
Y-96365D01*
X552816Y-99865D01*
G01Y-113865D02*
X558056D01*
G01X568133Y-110365D02*
X569442Y-112407D01*
X571189Y-113573D01*
X573154Y-113865D01*
X574901Y-113573D01*
X576648Y-112115D01*
X577739Y-110365D01*
X577958Y-108615D01*
X577521Y-106574D01*
X575993Y-105115D01*
X574464Y-104532D01*
X572499D01*
G01X574464D02*
X575774Y-103657D01*
X576866Y-102199D01*
X577303Y-100449D01*
X576866Y-98698D01*
X575774Y-97240D01*
X573809Y-96365D01*
X571844Y-96657D01*
X569879Y-97824D01*
G01X590436Y-113865D02*
Y-96365D01*
X587816Y-99865D01*
G01Y-113865D02*
X593056D01*
G01X603133Y-110365D02*
X604442Y-112407D01*
X606189Y-113573D01*
X608154Y-113865D01*
X609901Y-113573D01*
X611648Y-112115D01*
X612739Y-110365D01*
X612958Y-108615D01*
X612521Y-106574D01*
X610993Y-105115D01*
X609464Y-104532D01*
X607499D01*
G01X609464D02*
X610774Y-103657D01*
X611866Y-102199D01*
X612303Y-100449D01*
X611866Y-98698D01*
X610774Y-97240D01*
X608809Y-96365D01*
X606844Y-96657D01*
X604879Y-97824D01*
G01X625436Y-96365D02*
X623689Y-96948D01*
X622379Y-98407D01*
X621506Y-100156D01*
X620851Y-102490D01*
X620633Y-105115D01*
X620851Y-107740D01*
X621506Y-110074D01*
X622379Y-111824D01*
X623689Y-113282D01*
X625436Y-113865D01*
X627182Y-113282D01*
X628493Y-111824D01*
X629366Y-110074D01*
X630021Y-107740D01*
X630239Y-105115D01*
X630021Y-102490D01*
X629366Y-100156D01*
X628493Y-98407D01*
X627182Y-96948D01*
X625436Y-96365D01*
G01X685027Y-51365D02*
X690486Y-68865D01*
X695945Y-51365D01*
G01X712353Y-68865D02*
X703619D01*
Y-51365D01*
X712353D01*
G01X708859Y-59823D02*
X703619D01*
G01X721119Y-68865D02*
Y-51365D01*
X726578D01*
X728324Y-52240D01*
X729416Y-53407D01*
X729853Y-55740D01*
X729416Y-58074D01*
X728106Y-59532D01*
X726578Y-60407D01*
X721119D01*
G01X726578D02*
X729853Y-68865D01*
G01X742986Y-69448D02*
X742549Y-69157D01*
Y-68573D01*
X742986Y-68282D01*
X743423Y-68573D01*
Y-69157D01*
X742986Y-69448D01*
G01X707986Y-113865D02*
Y-96365D01*
X705366Y-99865D01*
G01Y-113865D02*
X710606D01*
G01X727232Y-104532D02*
X728106Y-103657D01*
X728761Y-102199D01*
X729198Y-100156D01*
X728761Y-98407D01*
X727888Y-97240D01*
X726359Y-96365D01*
X720464D01*
Y-113865D01*
X727669D01*
X729198Y-112699D01*
X730071Y-110948D01*
X730508Y-108907D01*
X730071Y-106865D01*
X728761Y-105115D01*
X727232Y-104532D01*
X720464D01*
G01X822936Y-96365D02*
Y-113865D01*
G01X817914Y-96365D02*
X827958D01*
G01X834759Y-113865D02*
Y-96365D01*
X840436Y-110948D01*
X846113Y-96365D01*
Y-113865D01*
G01X852477D02*
X857936Y-96365D01*
X863395Y-113865D01*
G01X861429Y-107740D02*
X854442D01*
G01X870851Y-111532D02*
X872598Y-112990D01*
X874563Y-113865D01*
X876309D01*
X878056Y-112990D01*
X879366Y-111532D01*
X880021Y-109490D01*
X879584Y-107449D01*
X878493Y-105698D01*
X876528Y-104532D01*
X873908Y-103948D01*
X872379Y-102782D01*
X871724Y-100740D01*
X872161Y-98698D01*
X873253Y-97240D01*
X874781Y-96365D01*
X876309D01*
X877838Y-96948D01*
X879148Y-98407D01*
G01X888133Y-113865D02*
Y-96365D01*
G01X896429D02*
X888133Y-107157D01*
G01X897739Y-113865D02*
X891844Y-102199D01*
G01X818569Y-51365D02*
Y-68865D01*
X827303D01*
G01X844366D02*
Y-57199D01*
G01Y-59240D02*
X843493Y-58074D01*
X842182Y-57490D01*
X840654Y-57199D01*
X839126Y-57782D01*
X837816Y-58948D01*
X836942Y-60698D01*
X836506Y-63032D01*
X836942Y-65365D01*
X837816Y-67115D01*
X839126Y-68282D01*
X840654Y-68865D01*
X842182Y-68573D01*
X843493Y-67699D01*
X844366Y-66532D01*
G01X853351Y-74115D02*
X854661Y-74698D01*
X856408Y-74115D01*
X857499Y-72949D01*
X858373Y-71490D01*
X859682Y-66824D01*
X862521Y-57199D01*
G01X855534D02*
X859682Y-66824D01*
G01X872161Y-60990D02*
X879148D01*
X878493Y-58948D01*
X877401Y-57782D01*
X875873Y-57199D01*
X874344Y-57490D01*
X873034Y-58365D01*
X872161Y-60407D01*
X871724Y-62157D01*
Y-63907D01*
X872161Y-65657D01*
X873253Y-67407D01*
X874563Y-68573D01*
X876091Y-68865D01*
X877619Y-68282D01*
X879148Y-66532D01*
G01X889879Y-68865D02*
Y-57199D01*
G01Y-59532D02*
X890971Y-58365D01*
X892063Y-57490D01*
X893591Y-57199D01*
X894682Y-57490D01*
X895993Y-58365D01*
G01X943619Y-110365D02*
X944711Y-112115D01*
X946021Y-113282D01*
X947549Y-113865D01*
X949296Y-113282D01*
X950606Y-112115D01*
X951916Y-110365D01*
X952353Y-108032D01*
Y-96365D01*
G01X965486Y-113865D02*
X963739Y-113573D01*
X962211Y-112407D01*
X960901Y-110657D01*
X960027Y-108615D01*
X959591Y-106282D01*
Y-103948D01*
X960027Y-101615D01*
X960901Y-99573D01*
X962211Y-97824D01*
X963739Y-96657D01*
X965486Y-96365D01*
X967232Y-96657D01*
X968761Y-97824D01*
X970071Y-99573D01*
X970945Y-101615D01*
X971381Y-103948D01*
Y-106282D01*
X970945Y-108615D01*
X970071Y-110657D01*
X968761Y-112407D01*
X967232Y-113573D01*
X965486Y-113865D01*
G01X978401Y-111532D02*
X980148Y-112990D01*
X982113Y-113865D01*
X983859D01*
X985606Y-112990D01*
X986916Y-111532D01*
X987571Y-109490D01*
X987134Y-107449D01*
X986043Y-105698D01*
X984078Y-104532D01*
X981458Y-103948D01*
X979929Y-102782D01*
X979274Y-100740D01*
X979711Y-98698D01*
X980803Y-97240D01*
X982331Y-96365D01*
X983859D01*
X985388Y-96948D01*
X986698Y-98407D01*
G01X1004853Y-113865D02*
X996119D01*
Y-96365D01*
X1004853D01*
G01X1001359Y-104823D02*
X996119D01*
G01X1013619Y-113865D02*
Y-96365D01*
X1018859D01*
X1020606Y-97240D01*
X1021916Y-99282D01*
X1022353Y-101615D01*
X1021916Y-103948D01*
X1020824Y-105698D01*
X1018859Y-106574D01*
X1013619D01*
G01X1030901Y-113865D02*
Y-96365D01*
G01X1040071D02*
Y-113865D01*
G01Y-105115D02*
X1030901D01*
G01X1066119Y-96365D02*
Y-113865D01*
X1074853D01*
G01X1082527D02*
X1087986Y-96365D01*
X1093445Y-113865D01*
G01X1091479Y-107740D02*
X1084492D01*
G01X1100683Y-96365D02*
Y-108907D01*
X1101556Y-111532D01*
X1103303Y-113282D01*
X1105486Y-113865D01*
X1107669Y-113282D01*
X1109416Y-111532D01*
X1110289Y-108907D01*
Y-96365D01*
G01X960683Y-68865D02*
Y-51365D01*
X965049D01*
X966796Y-52240D01*
X968106Y-53407D01*
X969198Y-55156D01*
X970071Y-57199D01*
X970289Y-60115D01*
X970071Y-63032D01*
X969198Y-65074D01*
X968106Y-66824D01*
X966796Y-67990D01*
X965049Y-68865D01*
X960683D01*
G01X979711Y-60990D02*
X986698D01*
X986043Y-58948D01*
X984951Y-57782D01*
X983423Y-57199D01*
X981894Y-57490D01*
X980584Y-58365D01*
X979711Y-60407D01*
X979274Y-62157D01*
Y-63907D01*
X979711Y-65657D01*
X980803Y-67407D01*
X982113Y-68573D01*
X983641Y-68865D01*
X985169Y-68282D01*
X986698Y-66532D01*
G01X997211Y-66824D02*
X998303Y-67990D01*
X999831Y-68865D01*
X1001141D01*
X1002451Y-68282D01*
X1003324Y-67407D01*
X1003761Y-66241D01*
X1003543Y-64490D01*
X1002669Y-63615D01*
X998739Y-61865D01*
X997866Y-59823D01*
X998303Y-58365D01*
X999176Y-57490D01*
X1000486Y-57199D01*
X1001796Y-57490D01*
X1003106Y-58365D01*
G01X1017986Y-57199D02*
Y-68865D01*
G01Y-52532D02*
X1017549Y-52240D01*
Y-51657D01*
X1017986Y-51365D01*
X1018423Y-51657D01*
Y-52240D01*
X1017986Y-52532D01*
G01X1032429Y-73240D02*
X1033958Y-74407D01*
X1035704Y-74698D01*
X1037232Y-74407D01*
X1038543Y-72949D01*
X1039416Y-70907D01*
Y-57199D01*
G01Y-59532D02*
X1038543Y-58365D01*
X1037232Y-57490D01*
X1035704Y-57199D01*
X1033958Y-57782D01*
X1032866Y-58948D01*
X1031992Y-60990D01*
X1031556Y-63032D01*
X1031774Y-64782D01*
X1032648Y-66824D01*
X1033958Y-68282D01*
X1035704Y-68865D01*
X1037014Y-68573D01*
X1038543Y-67407D01*
X1039416Y-66241D01*
G01X1049274Y-68865D02*
Y-57199D01*
G01Y-60115D02*
X1050148Y-58657D01*
X1051458Y-57490D01*
X1053204Y-57199D01*
X1054732Y-57490D01*
X1056043Y-58657D01*
X1056698Y-60698D01*
Y-68865D01*
G01X1067211Y-60990D02*
X1074198D01*
X1073543Y-58948D01*
X1072451Y-57782D01*
X1070923Y-57199D01*
X1069394Y-57490D01*
X1068084Y-58365D01*
X1067211Y-60407D01*
X1066774Y-62157D01*
Y-63907D01*
X1067211Y-65657D01*
X1068303Y-67407D01*
X1069613Y-68573D01*
X1071141Y-68865D01*
X1072669Y-68282D01*
X1074198Y-66532D01*
G01X1084929Y-68865D02*
Y-57199D01*
G01Y-59532D02*
X1086021Y-58365D01*
X1087113Y-57490D01*
X1088641Y-57199D01*
X1089732Y-57490D01*
X1091043Y-58365D01*
G01X1131686Y-113865D02*
Y-96365D01*
X1129066Y-99865D01*
G01Y-113865D02*
X1134306D01*
G01X1149186D02*
Y-96365D01*
X1146566Y-99865D01*
G01Y-113865D02*
X1151806D01*
G01X1162756Y-114448D02*
X1170616Y-96365D01*
G01X1184186Y-113865D02*
Y-96365D01*
X1181566Y-99865D01*
G01Y-113865D02*
X1186806D01*
G01X1196883Y-110365D02*
X1198192Y-112407D01*
X1199939Y-113573D01*
X1201904Y-113865D01*
X1203651Y-113573D01*
X1205398Y-112115D01*
X1206489Y-110365D01*
X1206708Y-108615D01*
X1206271Y-106574D01*
X1204743Y-105115D01*
X1203214Y-104532D01*
X1201249D01*
G01X1203214D02*
X1204524Y-103657D01*
X1205616Y-102199D01*
X1206053Y-100449D01*
X1205616Y-98698D01*
X1204524Y-97240D01*
X1202559Y-96365D01*
X1200594Y-96657D01*
X1198629Y-97824D01*
G01X1215256Y-114448D02*
X1223116Y-96365D01*
G01X1232538Y-99282D02*
X1233848Y-97532D01*
X1235376Y-96657D01*
X1237123Y-96365D01*
X1239306Y-96948D01*
X1240834Y-98407D01*
X1241271Y-100156D01*
X1241053Y-101907D01*
X1240179Y-103365D01*
X1235813Y-106282D01*
X1233848Y-108323D01*
X1232538Y-111241D01*
X1232101Y-113865D01*
X1241271D01*
G01X1254186Y-96365D02*
X1252439Y-96948D01*
X1251129Y-98407D01*
X1250256Y-100156D01*
X1249601Y-102490D01*
X1249383Y-105115D01*
X1249601Y-107740D01*
X1250256Y-110074D01*
X1251129Y-111824D01*
X1252439Y-113282D01*
X1254186Y-113865D01*
X1255932Y-113282D01*
X1257243Y-111824D01*
X1258116Y-110074D01*
X1258771Y-107740D01*
X1258989Y-105115D01*
X1258771Y-102490D01*
X1258116Y-100156D01*
X1257243Y-98407D01*
X1255932Y-96948D01*
X1254186Y-96365D01*
G01X1271686Y-113865D02*
Y-96365D01*
X1269066Y-99865D01*
G01Y-113865D02*
X1274306D01*
G01X1291806D02*
Y-96365D01*
X1283727Y-108907D01*
X1294645D01*
G01X1179383Y-68865D02*
Y-51365D01*
X1183749D01*
X1185496Y-52240D01*
X1186806Y-53407D01*
X1187898Y-55156D01*
X1188771Y-57199D01*
X1188989Y-60115D01*
X1188771Y-63032D01*
X1187898Y-65074D01*
X1186806Y-66824D01*
X1185496Y-67990D01*
X1183749Y-68865D01*
X1179383D01*
G01X1205616D02*
Y-57199D01*
G01Y-59240D02*
X1204743Y-58074D01*
X1203432Y-57490D01*
X1201904Y-57199D01*
X1200376Y-57782D01*
X1199066Y-58948D01*
X1198192Y-60698D01*
X1197756Y-63032D01*
X1198192Y-65365D01*
X1199066Y-67115D01*
X1200376Y-68282D01*
X1201904Y-68865D01*
X1203432Y-68573D01*
X1204743Y-67699D01*
X1205616Y-66532D01*
G01X1219186Y-51365D02*
Y-68865D01*
G01X1216129Y-57199D02*
X1222243D01*
G01X1233411Y-60990D02*
X1240398D01*
X1239743Y-58948D01*
X1238651Y-57782D01*
X1237123Y-57199D01*
X1235594Y-57490D01*
X1234284Y-58365D01*
X1233411Y-60407D01*
X1232974Y-62157D01*
Y-63907D01*
X1233411Y-65657D01*
X1234503Y-67407D01*
X1235813Y-68573D01*
X1237341Y-68865D01*
X1238869Y-68282D01*
X1240398Y-66532D01*
G54D31*
X43500Y143500D03*
X55000Y101500D03*
G54D115*
X583700Y194750D03*
G54D13*
X20000Y103800D03*
Y97200D03*
X32200Y98400D03*
Y91800D03*
X26100Y109800D03*
Y116400D03*
X33200Y109800D03*
Y116400D03*
X28550Y161900D03*
Y168500D03*
X62200Y131700D03*
Y138300D03*
X74000Y52700D03*
Y59300D03*
X79100Y89000D03*
Y95600D03*
X130500Y213100D03*
X137600D03*
X130500Y219700D03*
X137600D03*
X144700Y213100D03*
Y219700D03*
X165900Y208700D03*
Y215300D03*
X184500Y259800D03*
Y253200D03*
X188500Y264700D03*
Y271300D03*
X181000Y264700D03*
Y271300D03*
X192000Y259800D03*
Y253200D03*
X211500Y264700D03*
Y271300D03*
X219000Y264700D03*
Y271300D03*
X233500Y226800D03*
Y220200D03*
X226000Y226800D03*
Y220200D03*
X228500Y247700D03*
Y254300D03*
X236700Y207600D03*
Y201000D03*
X243800Y207600D03*
Y201000D03*
X241000Y226800D03*
Y220200D03*
X248500Y226800D03*
Y220200D03*
X236000Y247700D03*
Y254300D03*
X250600Y247700D03*
Y254300D03*
X243500Y247700D03*
Y254300D03*
X257700Y247700D03*
Y254300D03*
X339000Y56200D03*
Y62800D03*
X346500Y56200D03*
Y62800D03*
X377000Y52200D03*
Y58800D03*
X583000Y229700D03*
Y236300D03*
X590500Y229700D03*
Y236300D03*
X617000Y47707D03*
Y54307D03*
X624500Y47707D03*
Y54307D03*
X630000Y230200D03*
Y236800D03*
X637500Y230200D03*
Y236800D03*
X661000Y47707D03*
Y54307D03*
X668100Y47707D03*
Y54307D03*
G54D133*
X785015Y132549D03*
X800015D03*
X795015D03*
X790015D03*
G54D22*
X25800Y146500D03*
X19200D03*
X25800Y139400D03*
X19200D03*
X44450Y255500D03*
X64300Y118500D03*
X57700D03*
X60300Y171900D03*
X55800Y259000D03*
X62400D03*
X51050Y255500D03*
X66900Y171900D03*
X114200Y196500D03*
X120800D03*
X114200Y204000D03*
X120800D03*
X153200Y61000D03*
X159800D03*
X222200Y191000D03*
X228800D03*
X457200Y162200D03*
X463800D03*
X457200Y155100D03*
X463800D03*
X664300Y105000D03*
X657700D03*
X664300Y97500D03*
X657700D03*
X664300Y133000D03*
X657700D03*
X664300Y125500D03*
X657700D03*
X787700Y114000D03*
Y123000D03*
X780700Y256200D03*
X774100D03*
X794300Y114000D03*
Y123000D03*
X797800Y229400D03*
X804400D03*
X797800Y222300D03*
X804400D03*
G54D124*
X681500Y194250D03*
X686500D03*
X691500D03*
Y213750D03*
X686500D03*
X681500D03*
X696500Y194250D03*
Y213750D03*
G36*
G01X502953Y282316D02*
X503078Y282306D01*
X503203Y282266D01*
X503313Y282206D01*
X503413Y282126D01*
X503493Y282026D01*
X503553Y281916D01*
X503593Y281791D01*
X503603Y281666D01*
Y278236D01*
X503633Y278206D01*
X503733Y278066D01*
X503753Y278026D01*
X503768Y277991D01*
X503788Y277951D01*
X503803Y277911D01*
X503813Y277871D01*
X503828Y277826D01*
X503833Y277786D01*
X503843Y277746D01*
X503848Y277701D01*
Y277661D01*
X503853Y277616D01*
X503848Y277571D01*
Y277531D01*
X503843Y277486D01*
X503833Y277446D01*
X503828Y277406D01*
X503813Y277361D01*
X503803Y277321D01*
X503788Y277281D01*
X503768Y277241D01*
X503753Y277206D01*
X503733Y277166D01*
X503633Y277026D01*
X503603Y276996D01*
Y275866D01*
X503593Y275741D01*
X503553Y275616D01*
X503493Y275506D01*
X503413Y275406D01*
X503313Y275326D01*
X503203Y275266D01*
X503078Y275226D01*
X502953Y275216D01*
X502828Y275226D01*
X502703Y275266D01*
X502593Y275326D01*
X502493Y275406D01*
X502413Y275506D01*
X502353Y275616D01*
X502313Y275741D01*
X502303Y275866D01*
Y276996D01*
X502273Y277026D01*
X502173Y277166D01*
X502153Y277206D01*
X502138Y277241D01*
X502118Y277281D01*
X502103Y277321D01*
X502093Y277361D01*
X502078Y277406D01*
X502073Y277446D01*
X502063Y277486D01*
X502058Y277531D01*
Y277571D01*
X502053Y277616D01*
X502058Y277661D01*
Y277701D01*
X502063Y277746D01*
X502073Y277786D01*
X502078Y277826D01*
X502093Y277871D01*
X502103Y277911D01*
X502118Y277951D01*
X502138Y277991D01*
X502153Y278026D01*
X502173Y278066D01*
X502273Y278206D01*
X502303Y278236D01*
Y281666D01*
X502313Y281791D01*
X502353Y281916D01*
X502413Y282026D01*
X502493Y282126D01*
X502593Y282206D01*
X502703Y282266D01*
X502828Y282306D01*
X502953Y282316D01*
G37*
G36*
G01X507677D02*
X507802Y282306D01*
X507927Y282266D01*
X508037Y282206D01*
X508137Y282126D01*
X508217Y282026D01*
X508277Y281916D01*
X508317Y281791D01*
X508327Y281666D01*
Y278236D01*
X508357Y278206D01*
X508457Y278066D01*
X508477Y278026D01*
X508492Y277991D01*
X508512Y277951D01*
X508527Y277911D01*
X508537Y277871D01*
X508552Y277826D01*
X508557Y277786D01*
X508567Y277746D01*
X508572Y277701D01*
Y277661D01*
X508577Y277616D01*
X508572Y277571D01*
Y277531D01*
X508567Y277486D01*
X508557Y277446D01*
X508552Y277406D01*
X508537Y277361D01*
X508527Y277321D01*
X508512Y277281D01*
X508492Y277241D01*
X508477Y277206D01*
X508457Y277166D01*
X508357Y277026D01*
X508327Y276996D01*
Y275866D01*
X508317Y275741D01*
X508277Y275616D01*
X508217Y275506D01*
X508137Y275406D01*
X508037Y275326D01*
X507927Y275266D01*
X507802Y275226D01*
X507677Y275216D01*
X507552Y275226D01*
X507427Y275266D01*
X507317Y275326D01*
X507217Y275406D01*
X507137Y275506D01*
X507077Y275616D01*
X507037Y275741D01*
X507027Y275866D01*
Y276996D01*
X506997Y277026D01*
X506897Y277166D01*
X506877Y277206D01*
X506862Y277241D01*
X506842Y277281D01*
X506827Y277321D01*
X506817Y277361D01*
X506802Y277406D01*
X506797Y277446D01*
X506787Y277486D01*
X506782Y277531D01*
Y277571D01*
X506777Y277616D01*
X506782Y277661D01*
Y277701D01*
X506787Y277746D01*
X506797Y277786D01*
X506802Y277826D01*
X506817Y277871D01*
X506827Y277911D01*
X506842Y277951D01*
X506862Y277991D01*
X506877Y278026D01*
X506897Y278066D01*
X506997Y278206D01*
X507027Y278236D01*
Y281666D01*
X507037Y281791D01*
X507077Y281916D01*
X507137Y282026D01*
X507217Y282126D01*
X507317Y282206D01*
X507427Y282266D01*
X507552Y282306D01*
X507677Y282316D01*
G37*
G36*
G01X512402D02*
X512527Y282306D01*
X512652Y282266D01*
X512762Y282206D01*
X512862Y282126D01*
X512942Y282026D01*
X513002Y281916D01*
X513042Y281791D01*
X513052Y281666D01*
Y278236D01*
X513082Y278206D01*
X513182Y278066D01*
X513202Y278026D01*
X513217Y277991D01*
X513237Y277951D01*
X513252Y277911D01*
X513262Y277871D01*
X513277Y277826D01*
X513282Y277786D01*
X513292Y277746D01*
X513297Y277701D01*
Y277661D01*
X513302Y277616D01*
X513297Y277571D01*
Y277531D01*
X513292Y277486D01*
X513282Y277446D01*
X513277Y277406D01*
X513262Y277361D01*
X513252Y277321D01*
X513237Y277281D01*
X513217Y277241D01*
X513202Y277206D01*
X513182Y277166D01*
X513082Y277026D01*
X513052Y276996D01*
Y275866D01*
X513042Y275741D01*
X513002Y275616D01*
X512942Y275506D01*
X512862Y275406D01*
X512762Y275326D01*
X512652Y275266D01*
X512527Y275226D01*
X512402Y275216D01*
X512277Y275226D01*
X512152Y275266D01*
X512042Y275326D01*
X511942Y275406D01*
X511862Y275506D01*
X511802Y275616D01*
X511762Y275741D01*
X511752Y275866D01*
Y276996D01*
X511722Y277026D01*
X511622Y277166D01*
X511602Y277206D01*
X511587Y277241D01*
X511567Y277281D01*
X511552Y277321D01*
X511542Y277361D01*
X511527Y277406D01*
X511522Y277446D01*
X511512Y277486D01*
X511507Y277531D01*
Y277571D01*
X511502Y277616D01*
X511507Y277661D01*
Y277701D01*
X511512Y277746D01*
X511522Y277786D01*
X511527Y277826D01*
X511542Y277871D01*
X511552Y277911D01*
X511567Y277951D01*
X511587Y277991D01*
X511602Y278026D01*
X511622Y278066D01*
X511722Y278206D01*
X511752Y278236D01*
Y281666D01*
X511762Y281791D01*
X511802Y281916D01*
X511862Y282026D01*
X511942Y282126D01*
X512042Y282206D01*
X512152Y282266D01*
X512277Y282306D01*
X512402Y282316D01*
G37*
G36*
G01X517126D02*
X517251Y282306D01*
X517376Y282266D01*
X517486Y282206D01*
X517586Y282126D01*
X517666Y282026D01*
X517726Y281916D01*
X517766Y281791D01*
X517776Y281666D01*
Y278236D01*
X517806Y278206D01*
X517906Y278066D01*
X517926Y278026D01*
X517941Y277991D01*
X517961Y277951D01*
X517976Y277911D01*
X517986Y277871D01*
X518001Y277826D01*
X518006Y277786D01*
X518016Y277746D01*
X518021Y277701D01*
Y277661D01*
X518026Y277616D01*
X518021Y277571D01*
Y277531D01*
X518016Y277486D01*
X518006Y277446D01*
X518001Y277406D01*
X517986Y277361D01*
X517976Y277321D01*
X517961Y277281D01*
X517941Y277241D01*
X517926Y277206D01*
X517906Y277166D01*
X517806Y277026D01*
X517776Y276996D01*
Y275866D01*
X517766Y275741D01*
X517726Y275616D01*
X517666Y275506D01*
X517586Y275406D01*
X517486Y275326D01*
X517376Y275266D01*
X517251Y275226D01*
X517126Y275216D01*
X517001Y275226D01*
X516876Y275266D01*
X516766Y275326D01*
X516666Y275406D01*
X516586Y275506D01*
X516526Y275616D01*
X516486Y275741D01*
X516476Y275866D01*
Y276996D01*
X516446Y277026D01*
X516346Y277166D01*
X516326Y277206D01*
X516311Y277241D01*
X516291Y277281D01*
X516276Y277321D01*
X516266Y277361D01*
X516251Y277406D01*
X516246Y277446D01*
X516236Y277486D01*
X516231Y277531D01*
Y277571D01*
X516226Y277616D01*
X516231Y277661D01*
Y277701D01*
X516236Y277746D01*
X516246Y277786D01*
X516251Y277826D01*
X516266Y277871D01*
X516276Y277911D01*
X516291Y277951D01*
X516311Y277991D01*
X516326Y278026D01*
X516346Y278066D01*
X516446Y278206D01*
X516476Y278236D01*
Y281666D01*
X516486Y281791D01*
X516526Y281916D01*
X516586Y282026D01*
X516666Y282126D01*
X516766Y282206D01*
X516876Y282266D01*
X517001Y282306D01*
X517126Y282316D01*
G37*
G36*
G01X521851D02*
X521976Y282306D01*
X522101Y282266D01*
X522211Y282206D01*
X522311Y282126D01*
X522391Y282026D01*
X522451Y281916D01*
X522491Y281791D01*
X522501Y281666D01*
Y278236D01*
X522531Y278206D01*
X522631Y278066D01*
X522651Y278026D01*
X522666Y277991D01*
X522686Y277951D01*
X522701Y277911D01*
X522711Y277871D01*
X522726Y277826D01*
X522731Y277786D01*
X522741Y277746D01*
X522746Y277701D01*
Y277661D01*
X522751Y277616D01*
X522746Y277571D01*
Y277531D01*
X522741Y277486D01*
X522731Y277446D01*
X522726Y277406D01*
X522711Y277361D01*
X522701Y277321D01*
X522686Y277281D01*
X522666Y277241D01*
X522651Y277206D01*
X522631Y277166D01*
X522531Y277026D01*
X522501Y276996D01*
Y275866D01*
X522491Y275741D01*
X522451Y275616D01*
X522391Y275506D01*
X522311Y275406D01*
X522211Y275326D01*
X522101Y275266D01*
X521976Y275226D01*
X521851Y275216D01*
X521726Y275226D01*
X521601Y275266D01*
X521491Y275326D01*
X521391Y275406D01*
X521311Y275506D01*
X521251Y275616D01*
X521211Y275741D01*
X521201Y275866D01*
Y276996D01*
X521171Y277026D01*
X521071Y277166D01*
X521051Y277206D01*
X521036Y277241D01*
X521016Y277281D01*
X521001Y277321D01*
X520991Y277361D01*
X520976Y277406D01*
X520971Y277446D01*
X520961Y277486D01*
X520956Y277531D01*
Y277571D01*
X520951Y277616D01*
X520956Y277661D01*
Y277701D01*
X520961Y277746D01*
X520971Y277786D01*
X520976Y277826D01*
X520991Y277871D01*
X521001Y277911D01*
X521016Y277951D01*
X521036Y277991D01*
X521051Y278026D01*
X521071Y278066D01*
X521171Y278206D01*
X521201Y278236D01*
Y281666D01*
X521211Y281791D01*
X521251Y281916D01*
X521311Y282026D01*
X521391Y282126D01*
X521491Y282206D01*
X521601Y282266D01*
X521726Y282306D01*
X521851Y282316D01*
G37*
G36*
G01X526575D02*
X526700Y282306D01*
X526825Y282266D01*
X526935Y282206D01*
X527035Y282126D01*
X527115Y282026D01*
X527175Y281916D01*
X527215Y281791D01*
X527225Y281666D01*
Y278236D01*
X527255Y278206D01*
X527355Y278066D01*
X527375Y278026D01*
X527390Y277991D01*
X527410Y277951D01*
X527425Y277911D01*
X527435Y277871D01*
X527450Y277826D01*
X527455Y277786D01*
X527465Y277746D01*
X527470Y277701D01*
Y277661D01*
X527475Y277616D01*
X527470Y277571D01*
Y277531D01*
X527465Y277486D01*
X527455Y277446D01*
X527450Y277406D01*
X527435Y277361D01*
X527425Y277321D01*
X527410Y277281D01*
X527390Y277241D01*
X527375Y277206D01*
X527355Y277166D01*
X527255Y277026D01*
X527225Y276996D01*
Y275866D01*
X527215Y275741D01*
X527175Y275616D01*
X527115Y275506D01*
X527035Y275406D01*
X526935Y275326D01*
X526825Y275266D01*
X526700Y275226D01*
X526575Y275216D01*
X526450Y275226D01*
X526325Y275266D01*
X526215Y275326D01*
X526115Y275406D01*
X526035Y275506D01*
X525975Y275616D01*
X525935Y275741D01*
X525925Y275866D01*
Y276996D01*
X525895Y277026D01*
X525795Y277166D01*
X525775Y277206D01*
X525760Y277241D01*
X525740Y277281D01*
X525725Y277321D01*
X525715Y277361D01*
X525700Y277406D01*
X525695Y277446D01*
X525685Y277486D01*
X525680Y277531D01*
Y277571D01*
X525675Y277616D01*
X525680Y277661D01*
Y277701D01*
X525685Y277746D01*
X525695Y277786D01*
X525700Y277826D01*
X525715Y277871D01*
X525725Y277911D01*
X525740Y277951D01*
X525760Y277991D01*
X525775Y278026D01*
X525795Y278066D01*
X525895Y278206D01*
X525925Y278236D01*
Y281666D01*
X525935Y281791D01*
X525975Y281916D01*
X526035Y282026D01*
X526115Y282126D01*
X526215Y282206D01*
X526325Y282266D01*
X526450Y282306D01*
X526575Y282316D01*
G37*
G36*
G01X531299D02*
X531424Y282306D01*
X531549Y282266D01*
X531659Y282206D01*
X531759Y282126D01*
X531839Y282026D01*
X531899Y281916D01*
X531939Y281791D01*
X531949Y281666D01*
Y278236D01*
X531979Y278206D01*
X532079Y278066D01*
X532099Y278026D01*
X532114Y277991D01*
X532134Y277951D01*
X532149Y277911D01*
X532159Y277871D01*
X532174Y277826D01*
X532179Y277786D01*
X532189Y277746D01*
X532194Y277701D01*
Y277661D01*
X532199Y277616D01*
X532194Y277571D01*
Y277531D01*
X532189Y277486D01*
X532179Y277446D01*
X532174Y277406D01*
X532159Y277361D01*
X532149Y277321D01*
X532134Y277281D01*
X532114Y277241D01*
X532099Y277206D01*
X532079Y277166D01*
X531979Y277026D01*
X531949Y276996D01*
Y275866D01*
X531939Y275741D01*
X531899Y275616D01*
X531839Y275506D01*
X531759Y275406D01*
X531659Y275326D01*
X531549Y275266D01*
X531424Y275226D01*
X531299Y275216D01*
X531174Y275226D01*
X531049Y275266D01*
X530939Y275326D01*
X530839Y275406D01*
X530759Y275506D01*
X530699Y275616D01*
X530659Y275741D01*
X530649Y275866D01*
Y276996D01*
X530619Y277026D01*
X530519Y277166D01*
X530499Y277206D01*
X530484Y277241D01*
X530464Y277281D01*
X530449Y277321D01*
X530439Y277361D01*
X530424Y277406D01*
X530419Y277446D01*
X530409Y277486D01*
X530404Y277531D01*
Y277571D01*
X530399Y277616D01*
X530404Y277661D01*
Y277701D01*
X530409Y277746D01*
X530419Y277786D01*
X530424Y277826D01*
X530439Y277871D01*
X530449Y277911D01*
X530464Y277951D01*
X530484Y277991D01*
X530499Y278026D01*
X530519Y278066D01*
X530619Y278206D01*
X530649Y278236D01*
Y281666D01*
X530659Y281791D01*
X530699Y281916D01*
X530759Y282026D01*
X530839Y282126D01*
X530939Y282206D01*
X531049Y282266D01*
X531174Y282306D01*
X531299Y282316D01*
G37*
G36*
G01X536024D02*
X536149Y282306D01*
X536274Y282266D01*
X536384Y282206D01*
X536484Y282126D01*
X536564Y282026D01*
X536624Y281916D01*
X536664Y281791D01*
X536674Y281666D01*
Y278236D01*
X536704Y278206D01*
X536804Y278066D01*
X536824Y278026D01*
X536839Y277991D01*
X536859Y277951D01*
X536874Y277911D01*
X536884Y277871D01*
X536899Y277826D01*
X536904Y277786D01*
X536914Y277746D01*
X536919Y277701D01*
Y277661D01*
X536924Y277616D01*
X536919Y277571D01*
Y277531D01*
X536914Y277486D01*
X536904Y277446D01*
X536899Y277406D01*
X536884Y277361D01*
X536874Y277321D01*
X536859Y277281D01*
X536839Y277241D01*
X536824Y277206D01*
X536804Y277166D01*
X536704Y277026D01*
X536674Y276996D01*
Y275866D01*
X536664Y275741D01*
X536624Y275616D01*
X536564Y275506D01*
X536484Y275406D01*
X536384Y275326D01*
X536274Y275266D01*
X536149Y275226D01*
X536024Y275216D01*
X535899Y275226D01*
X535774Y275266D01*
X535664Y275326D01*
X535564Y275406D01*
X535484Y275506D01*
X535424Y275616D01*
X535384Y275741D01*
X535374Y275866D01*
Y276996D01*
X535344Y277026D01*
X535244Y277166D01*
X535224Y277206D01*
X535209Y277241D01*
X535189Y277281D01*
X535174Y277321D01*
X535164Y277361D01*
X535149Y277406D01*
X535144Y277446D01*
X535134Y277486D01*
X535129Y277531D01*
Y277571D01*
X535124Y277616D01*
X535129Y277661D01*
Y277701D01*
X535134Y277746D01*
X535144Y277786D01*
X535149Y277826D01*
X535164Y277871D01*
X535174Y277911D01*
X535189Y277951D01*
X535209Y277991D01*
X535224Y278026D01*
X535244Y278066D01*
X535344Y278206D01*
X535374Y278236D01*
Y281666D01*
X535384Y281791D01*
X535424Y281916D01*
X535484Y282026D01*
X535564Y282126D01*
X535664Y282206D01*
X535774Y282266D01*
X535899Y282306D01*
X536024Y282316D01*
G37*
G36*
G01X540748D02*
X540873Y282306D01*
X540998Y282266D01*
X541108Y282206D01*
X541208Y282126D01*
X541288Y282026D01*
X541348Y281916D01*
X541388Y281791D01*
X541398Y281666D01*
Y278236D01*
X541428Y278206D01*
X541528Y278066D01*
X541548Y278026D01*
X541563Y277991D01*
X541583Y277951D01*
X541598Y277911D01*
X541608Y277871D01*
X541623Y277826D01*
X541628Y277786D01*
X541638Y277746D01*
X541643Y277701D01*
Y277661D01*
X541648Y277616D01*
X541643Y277571D01*
Y277531D01*
X541638Y277486D01*
X541628Y277446D01*
X541623Y277406D01*
X541608Y277361D01*
X541598Y277321D01*
X541583Y277281D01*
X541563Y277241D01*
X541548Y277206D01*
X541528Y277166D01*
X541428Y277026D01*
X541398Y276996D01*
Y275866D01*
X541388Y275741D01*
X541348Y275616D01*
X541288Y275506D01*
X541208Y275406D01*
X541108Y275326D01*
X540998Y275266D01*
X540873Y275226D01*
X540748Y275216D01*
X540623Y275226D01*
X540498Y275266D01*
X540388Y275326D01*
X540288Y275406D01*
X540208Y275506D01*
X540148Y275616D01*
X540108Y275741D01*
X540098Y275866D01*
Y276996D01*
X540068Y277026D01*
X539968Y277166D01*
X539948Y277206D01*
X539933Y277241D01*
X539913Y277281D01*
X539898Y277321D01*
X539888Y277361D01*
X539873Y277406D01*
X539868Y277446D01*
X539858Y277486D01*
X539853Y277531D01*
Y277571D01*
X539848Y277616D01*
X539853Y277661D01*
Y277701D01*
X539858Y277746D01*
X539868Y277786D01*
X539873Y277826D01*
X539888Y277871D01*
X539898Y277911D01*
X539913Y277951D01*
X539933Y277991D01*
X539948Y278026D01*
X539968Y278066D01*
X540068Y278206D01*
X540098Y278236D01*
Y281666D01*
X540108Y281791D01*
X540148Y281916D01*
X540208Y282026D01*
X540288Y282126D01*
X540388Y282206D01*
X540498Y282266D01*
X540623Y282306D01*
X540748Y282316D01*
G37*
G36*
G01X545473D02*
X545598Y282306D01*
X545723Y282266D01*
X545833Y282206D01*
X545933Y282126D01*
X546013Y282026D01*
X546073Y281916D01*
X546113Y281791D01*
X546123Y281666D01*
Y278236D01*
X546153Y278206D01*
X546253Y278066D01*
X546273Y278026D01*
X546288Y277991D01*
X546308Y277951D01*
X546323Y277911D01*
X546333Y277871D01*
X546348Y277826D01*
X546353Y277786D01*
X546363Y277746D01*
X546368Y277701D01*
Y277661D01*
X546373Y277616D01*
X546368Y277571D01*
Y277531D01*
X546363Y277486D01*
X546353Y277446D01*
X546348Y277406D01*
X546333Y277361D01*
X546323Y277321D01*
X546308Y277281D01*
X546288Y277241D01*
X546273Y277206D01*
X546253Y277166D01*
X546153Y277026D01*
X546123Y276996D01*
Y275866D01*
X546113Y275741D01*
X546073Y275616D01*
X546013Y275506D01*
X545933Y275406D01*
X545833Y275326D01*
X545723Y275266D01*
X545598Y275226D01*
X545473Y275216D01*
X545348Y275226D01*
X545223Y275266D01*
X545113Y275326D01*
X545013Y275406D01*
X544933Y275506D01*
X544873Y275616D01*
X544833Y275741D01*
X544823Y275866D01*
Y276996D01*
X544793Y277026D01*
X544693Y277166D01*
X544673Y277206D01*
X544658Y277241D01*
X544638Y277281D01*
X544623Y277321D01*
X544613Y277361D01*
X544598Y277406D01*
X544593Y277446D01*
X544583Y277486D01*
X544578Y277531D01*
Y277571D01*
X544573Y277616D01*
X544578Y277661D01*
Y277701D01*
X544583Y277746D01*
X544593Y277786D01*
X544598Y277826D01*
X544613Y277871D01*
X544623Y277911D01*
X544638Y277951D01*
X544658Y277991D01*
X544673Y278026D01*
X544693Y278066D01*
X544793Y278206D01*
X544823Y278236D01*
Y281666D01*
X544833Y281791D01*
X544873Y281916D01*
X544933Y282026D01*
X545013Y282126D01*
X545113Y282206D01*
X545223Y282266D01*
X545348Y282306D01*
X545473Y282316D01*
G37*
G36*
G01X550197D02*
X550322Y282306D01*
X550447Y282266D01*
X550557Y282206D01*
X550657Y282126D01*
X550737Y282026D01*
X550797Y281916D01*
X550837Y281791D01*
X550847Y281666D01*
Y278236D01*
X550877Y278206D01*
X550977Y278066D01*
X550997Y278026D01*
X551012Y277991D01*
X551032Y277951D01*
X551047Y277911D01*
X551057Y277871D01*
X551072Y277826D01*
X551077Y277786D01*
X551087Y277746D01*
X551092Y277701D01*
Y277661D01*
X551097Y277616D01*
X551092Y277571D01*
Y277531D01*
X551087Y277486D01*
X551077Y277446D01*
X551072Y277406D01*
X551057Y277361D01*
X551047Y277321D01*
X551032Y277281D01*
X551012Y277241D01*
X550997Y277206D01*
X550977Y277166D01*
X550877Y277026D01*
X550847Y276996D01*
Y275866D01*
X550837Y275741D01*
X550797Y275616D01*
X550737Y275506D01*
X550657Y275406D01*
X550557Y275326D01*
X550447Y275266D01*
X550322Y275226D01*
X550197Y275216D01*
X550072Y275226D01*
X549947Y275266D01*
X549837Y275326D01*
X549737Y275406D01*
X549657Y275506D01*
X549597Y275616D01*
X549557Y275741D01*
X549547Y275866D01*
Y276996D01*
X549517Y277026D01*
X549417Y277166D01*
X549397Y277206D01*
X549382Y277241D01*
X549362Y277281D01*
X549347Y277321D01*
X549337Y277361D01*
X549322Y277406D01*
X549317Y277446D01*
X549307Y277486D01*
X549302Y277531D01*
Y277571D01*
X549297Y277616D01*
X549302Y277661D01*
Y277701D01*
X549307Y277746D01*
X549317Y277786D01*
X549322Y277826D01*
X549337Y277871D01*
X549347Y277911D01*
X549362Y277951D01*
X549382Y277991D01*
X549397Y278026D01*
X549417Y278066D01*
X549517Y278206D01*
X549547Y278236D01*
Y281666D01*
X549557Y281791D01*
X549597Y281916D01*
X549657Y282026D01*
X549737Y282126D01*
X549837Y282206D01*
X549947Y282266D01*
X550072Y282306D01*
X550197Y282316D01*
G37*
G36*
G01X554922D02*
X555047Y282306D01*
X555172Y282266D01*
X555282Y282206D01*
X555382Y282126D01*
X555462Y282026D01*
X555522Y281916D01*
X555562Y281791D01*
X555572Y281666D01*
Y278236D01*
X555602Y278206D01*
X555702Y278066D01*
X555722Y278026D01*
X555737Y277991D01*
X555757Y277951D01*
X555772Y277911D01*
X555782Y277871D01*
X555797Y277826D01*
X555802Y277786D01*
X555812Y277746D01*
X555817Y277701D01*
Y277661D01*
X555822Y277616D01*
X555817Y277571D01*
Y277531D01*
X555812Y277486D01*
X555802Y277446D01*
X555797Y277406D01*
X555782Y277361D01*
X555772Y277321D01*
X555757Y277281D01*
X555737Y277241D01*
X555722Y277206D01*
X555702Y277166D01*
X555602Y277026D01*
X555572Y276996D01*
Y275866D01*
X555562Y275741D01*
X555522Y275616D01*
X555462Y275506D01*
X555382Y275406D01*
X555282Y275326D01*
X555172Y275266D01*
X555047Y275226D01*
X554922Y275216D01*
X554797Y275226D01*
X554672Y275266D01*
X554562Y275326D01*
X554462Y275406D01*
X554382Y275506D01*
X554322Y275616D01*
X554282Y275741D01*
X554272Y275866D01*
Y276996D01*
X554242Y277026D01*
X554142Y277166D01*
X554122Y277206D01*
X554107Y277241D01*
X554087Y277281D01*
X554072Y277321D01*
X554062Y277361D01*
X554047Y277406D01*
X554042Y277446D01*
X554032Y277486D01*
X554027Y277531D01*
Y277571D01*
X554022Y277616D01*
X554027Y277661D01*
Y277701D01*
X554032Y277746D01*
X554042Y277786D01*
X554047Y277826D01*
X554062Y277871D01*
X554072Y277911D01*
X554087Y277951D01*
X554107Y277991D01*
X554122Y278026D01*
X554142Y278066D01*
X554242Y278206D01*
X554272Y278236D01*
Y281666D01*
X554282Y281791D01*
X554322Y281916D01*
X554382Y282026D01*
X554462Y282126D01*
X554562Y282206D01*
X554672Y282266D01*
X554797Y282306D01*
X554922Y282316D01*
G37*
G36*
G01X559646D02*
X559771Y282306D01*
X559896Y282266D01*
X560006Y282206D01*
X560106Y282126D01*
X560186Y282026D01*
X560246Y281916D01*
X560286Y281791D01*
X560296Y281666D01*
Y278236D01*
X560326Y278206D01*
X560426Y278066D01*
X560446Y278026D01*
X560461Y277991D01*
X560481Y277951D01*
X560496Y277911D01*
X560506Y277871D01*
X560521Y277826D01*
X560526Y277786D01*
X560536Y277746D01*
X560541Y277701D01*
Y277661D01*
X560546Y277616D01*
X560541Y277571D01*
Y277531D01*
X560536Y277486D01*
X560526Y277446D01*
X560521Y277406D01*
X560506Y277361D01*
X560496Y277321D01*
X560481Y277281D01*
X560461Y277241D01*
X560446Y277206D01*
X560426Y277166D01*
X560326Y277026D01*
X560296Y276996D01*
Y275866D01*
X560286Y275741D01*
X560246Y275616D01*
X560186Y275506D01*
X560106Y275406D01*
X560006Y275326D01*
X559896Y275266D01*
X559771Y275226D01*
X559646Y275216D01*
X559521Y275226D01*
X559396Y275266D01*
X559286Y275326D01*
X559186Y275406D01*
X559106Y275506D01*
X559046Y275616D01*
X559006Y275741D01*
X558996Y275866D01*
Y276996D01*
X558966Y277026D01*
X558866Y277166D01*
X558846Y277206D01*
X558831Y277241D01*
X558811Y277281D01*
X558796Y277321D01*
X558786Y277361D01*
X558771Y277406D01*
X558766Y277446D01*
X558756Y277486D01*
X558751Y277531D01*
Y277571D01*
X558746Y277616D01*
X558751Y277661D01*
Y277701D01*
X558756Y277746D01*
X558766Y277786D01*
X558771Y277826D01*
X558786Y277871D01*
X558796Y277911D01*
X558811Y277951D01*
X558831Y277991D01*
X558846Y278026D01*
X558866Y278066D01*
X558966Y278206D01*
X558996Y278236D01*
Y281666D01*
X559006Y281791D01*
X559046Y281916D01*
X559106Y282026D01*
X559186Y282126D01*
X559286Y282206D01*
X559396Y282266D01*
X559521Y282306D01*
X559646Y282316D01*
G37*
G36*
G01X564370D02*
X564495Y282306D01*
X564620Y282266D01*
X564730Y282206D01*
X564830Y282126D01*
X564910Y282026D01*
X564970Y281916D01*
X565010Y281791D01*
X565020Y281666D01*
Y278236D01*
X565050Y278206D01*
X565150Y278066D01*
X565170Y278026D01*
X565185Y277991D01*
X565205Y277951D01*
X565220Y277911D01*
X565230Y277871D01*
X565245Y277826D01*
X565250Y277786D01*
X565260Y277746D01*
X565265Y277701D01*
Y277661D01*
X565270Y277616D01*
X565265Y277571D01*
Y277531D01*
X565260Y277486D01*
X565250Y277446D01*
X565245Y277406D01*
X565230Y277361D01*
X565220Y277321D01*
X565205Y277281D01*
X565185Y277241D01*
X565170Y277206D01*
X565150Y277166D01*
X565050Y277026D01*
X565020Y276996D01*
Y275866D01*
X565010Y275741D01*
X564970Y275616D01*
X564910Y275506D01*
X564830Y275406D01*
X564730Y275326D01*
X564620Y275266D01*
X564495Y275226D01*
X564370Y275216D01*
X564245Y275226D01*
X564120Y275266D01*
X564010Y275326D01*
X563910Y275406D01*
X563830Y275506D01*
X563770Y275616D01*
X563730Y275741D01*
X563720Y275866D01*
Y276996D01*
X563690Y277026D01*
X563590Y277166D01*
X563570Y277206D01*
X563555Y277241D01*
X563535Y277281D01*
X563520Y277321D01*
X563510Y277361D01*
X563495Y277406D01*
X563490Y277446D01*
X563480Y277486D01*
X563475Y277531D01*
Y277571D01*
X563470Y277616D01*
X563475Y277661D01*
Y277701D01*
X563480Y277746D01*
X563490Y277786D01*
X563495Y277826D01*
X563510Y277871D01*
X563520Y277911D01*
X563535Y277951D01*
X563555Y277991D01*
X563570Y278026D01*
X563590Y278066D01*
X563690Y278206D01*
X563720Y278236D01*
Y281666D01*
X563730Y281791D01*
X563770Y281916D01*
X563830Y282026D01*
X563910Y282126D01*
X564010Y282206D01*
X564120Y282266D01*
X564245Y282306D01*
X564370Y282316D01*
G37*
G36*
G01X569095D02*
X569220Y282306D01*
X569345Y282266D01*
X569455Y282206D01*
X569555Y282126D01*
X569635Y282026D01*
X569695Y281916D01*
X569735Y281791D01*
X569745Y281666D01*
Y278236D01*
X569775Y278206D01*
X569875Y278066D01*
X569895Y278026D01*
X569910Y277991D01*
X569930Y277951D01*
X569945Y277911D01*
X569955Y277871D01*
X569970Y277826D01*
X569975Y277786D01*
X569985Y277746D01*
X569990Y277701D01*
Y277661D01*
X569995Y277616D01*
X569990Y277571D01*
Y277531D01*
X569985Y277486D01*
X569975Y277446D01*
X569970Y277406D01*
X569955Y277361D01*
X569945Y277321D01*
X569930Y277281D01*
X569910Y277241D01*
X569895Y277206D01*
X569875Y277166D01*
X569775Y277026D01*
X569745Y276996D01*
Y275866D01*
X569735Y275741D01*
X569695Y275616D01*
X569635Y275506D01*
X569555Y275406D01*
X569455Y275326D01*
X569345Y275266D01*
X569220Y275226D01*
X569095Y275216D01*
X568970Y275226D01*
X568845Y275266D01*
X568735Y275326D01*
X568635Y275406D01*
X568555Y275506D01*
X568495Y275616D01*
X568455Y275741D01*
X568445Y275866D01*
Y276996D01*
X568415Y277026D01*
X568315Y277166D01*
X568295Y277206D01*
X568280Y277241D01*
X568260Y277281D01*
X568245Y277321D01*
X568235Y277361D01*
X568220Y277406D01*
X568215Y277446D01*
X568205Y277486D01*
X568200Y277531D01*
Y277571D01*
X568195Y277616D01*
X568200Y277661D01*
Y277701D01*
X568205Y277746D01*
X568215Y277786D01*
X568220Y277826D01*
X568235Y277871D01*
X568245Y277911D01*
X568260Y277951D01*
X568280Y277991D01*
X568295Y278026D01*
X568315Y278066D01*
X568415Y278206D01*
X568445Y278236D01*
Y281666D01*
X568455Y281791D01*
X568495Y281916D01*
X568555Y282026D01*
X568635Y282126D01*
X568735Y282206D01*
X568845Y282266D01*
X568970Y282306D01*
X569095Y282316D01*
G37*
G36*
G01X573819D02*
X573944Y282306D01*
X574069Y282266D01*
X574179Y282206D01*
X574279Y282126D01*
X574359Y282026D01*
X574419Y281916D01*
X574459Y281791D01*
X574469Y281666D01*
Y278236D01*
X574499Y278206D01*
X574599Y278066D01*
X574619Y278026D01*
X574634Y277991D01*
X574654Y277951D01*
X574669Y277911D01*
X574679Y277871D01*
X574694Y277826D01*
X574699Y277786D01*
X574709Y277746D01*
X574714Y277701D01*
Y277661D01*
X574719Y277616D01*
X574714Y277571D01*
Y277531D01*
X574709Y277486D01*
X574699Y277446D01*
X574694Y277406D01*
X574679Y277361D01*
X574669Y277321D01*
X574654Y277281D01*
X574634Y277241D01*
X574619Y277206D01*
X574599Y277166D01*
X574499Y277026D01*
X574469Y276996D01*
Y275866D01*
X574459Y275741D01*
X574419Y275616D01*
X574359Y275506D01*
X574279Y275406D01*
X574179Y275326D01*
X574069Y275266D01*
X573944Y275226D01*
X573819Y275216D01*
X573694Y275226D01*
X573569Y275266D01*
X573459Y275326D01*
X573359Y275406D01*
X573279Y275506D01*
X573219Y275616D01*
X573179Y275741D01*
X573169Y275866D01*
Y276996D01*
X573139Y277026D01*
X573039Y277166D01*
X573019Y277206D01*
X573004Y277241D01*
X572984Y277281D01*
X572969Y277321D01*
X572959Y277361D01*
X572944Y277406D01*
X572939Y277446D01*
X572929Y277486D01*
X572924Y277531D01*
Y277571D01*
X572919Y277616D01*
X572924Y277661D01*
Y277701D01*
X572929Y277746D01*
X572939Y277786D01*
X572944Y277826D01*
X572959Y277871D01*
X572969Y277911D01*
X572984Y277951D01*
X573004Y277991D01*
X573019Y278026D01*
X573039Y278066D01*
X573139Y278206D01*
X573169Y278236D01*
Y281666D01*
X573179Y281791D01*
X573219Y281916D01*
X573279Y282026D01*
X573359Y282126D01*
X573459Y282206D01*
X573569Y282266D01*
X573694Y282306D01*
X573819Y282316D01*
G37*
G36*
G01X578544D02*
X578669Y282306D01*
X578794Y282266D01*
X578904Y282206D01*
X579004Y282126D01*
X579084Y282026D01*
X579144Y281916D01*
X579184Y281791D01*
X579194Y281666D01*
Y278236D01*
X579224Y278206D01*
X579324Y278066D01*
X579344Y278026D01*
X579359Y277991D01*
X579379Y277951D01*
X579394Y277911D01*
X579404Y277871D01*
X579419Y277826D01*
X579424Y277786D01*
X579434Y277746D01*
X579439Y277701D01*
Y277661D01*
X579444Y277616D01*
X579439Y277571D01*
Y277531D01*
X579434Y277486D01*
X579424Y277446D01*
X579419Y277406D01*
X579404Y277361D01*
X579394Y277321D01*
X579379Y277281D01*
X579359Y277241D01*
X579344Y277206D01*
X579324Y277166D01*
X579224Y277026D01*
X579194Y276996D01*
Y275866D01*
X579184Y275741D01*
X579144Y275616D01*
X579084Y275506D01*
X579004Y275406D01*
X578904Y275326D01*
X578794Y275266D01*
X578669Y275226D01*
X578544Y275216D01*
X578419Y275226D01*
X578294Y275266D01*
X578184Y275326D01*
X578084Y275406D01*
X578004Y275506D01*
X577944Y275616D01*
X577904Y275741D01*
X577894Y275866D01*
Y276996D01*
X577864Y277026D01*
X577764Y277166D01*
X577744Y277206D01*
X577729Y277241D01*
X577709Y277281D01*
X577694Y277321D01*
X577684Y277361D01*
X577669Y277406D01*
X577664Y277446D01*
X577654Y277486D01*
X577649Y277531D01*
Y277571D01*
X577644Y277616D01*
X577649Y277661D01*
Y277701D01*
X577654Y277746D01*
X577664Y277786D01*
X577669Y277826D01*
X577684Y277871D01*
X577694Y277911D01*
X577709Y277951D01*
X577729Y277991D01*
X577744Y278026D01*
X577764Y278066D01*
X577864Y278206D01*
X577894Y278236D01*
Y281666D01*
X577904Y281791D01*
X577944Y281916D01*
X578004Y282026D01*
X578084Y282126D01*
X578184Y282206D01*
X578294Y282266D01*
X578419Y282306D01*
X578544Y282316D01*
G37*
G36*
G01X583268D02*
X583393Y282306D01*
X583518Y282266D01*
X583628Y282206D01*
X583728Y282126D01*
X583808Y282026D01*
X583868Y281916D01*
X583908Y281791D01*
X583918Y281666D01*
Y278236D01*
X583948Y278206D01*
X584048Y278066D01*
X584068Y278026D01*
X584083Y277991D01*
X584103Y277951D01*
X584118Y277911D01*
X584128Y277871D01*
X584143Y277826D01*
X584148Y277786D01*
X584158Y277746D01*
X584163Y277701D01*
Y277661D01*
X584168Y277616D01*
X584163Y277571D01*
Y277531D01*
X584158Y277486D01*
X584148Y277446D01*
X584143Y277406D01*
X584128Y277361D01*
X584118Y277321D01*
X584103Y277281D01*
X584083Y277241D01*
X584068Y277206D01*
X584048Y277166D01*
X583948Y277026D01*
X583918Y276996D01*
Y275866D01*
X583908Y275741D01*
X583868Y275616D01*
X583808Y275506D01*
X583728Y275406D01*
X583628Y275326D01*
X583518Y275266D01*
X583393Y275226D01*
X583268Y275216D01*
X583143Y275226D01*
X583018Y275266D01*
X582908Y275326D01*
X582808Y275406D01*
X582728Y275506D01*
X582668Y275616D01*
X582628Y275741D01*
X582618Y275866D01*
Y276996D01*
X582588Y277026D01*
X582488Y277166D01*
X582468Y277206D01*
X582453Y277241D01*
X582433Y277281D01*
X582418Y277321D01*
X582408Y277361D01*
X582393Y277406D01*
X582388Y277446D01*
X582378Y277486D01*
X582373Y277531D01*
Y277571D01*
X582368Y277616D01*
X582373Y277661D01*
Y277701D01*
X582378Y277746D01*
X582388Y277786D01*
X582393Y277826D01*
X582408Y277871D01*
X582418Y277911D01*
X582433Y277951D01*
X582453Y277991D01*
X582468Y278026D01*
X582488Y278066D01*
X582588Y278206D01*
X582618Y278236D01*
Y281666D01*
X582628Y281791D01*
X582668Y281916D01*
X582728Y282026D01*
X582808Y282126D01*
X582908Y282206D01*
X583018Y282266D01*
X583143Y282306D01*
X583268Y282316D01*
G37*
G36*
G01X587992D02*
X588117Y282306D01*
X588242Y282266D01*
X588352Y282206D01*
X588452Y282126D01*
X588532Y282026D01*
X588592Y281916D01*
X588632Y281791D01*
X588642Y281666D01*
Y278236D01*
X588672Y278206D01*
X588772Y278066D01*
X588792Y278026D01*
X588807Y277991D01*
X588827Y277951D01*
X588842Y277911D01*
X588852Y277871D01*
X588867Y277826D01*
X588872Y277786D01*
X588882Y277746D01*
X588887Y277701D01*
Y277661D01*
X588892Y277616D01*
X588887Y277571D01*
Y277531D01*
X588882Y277486D01*
X588872Y277446D01*
X588867Y277406D01*
X588852Y277361D01*
X588842Y277321D01*
X588827Y277281D01*
X588807Y277241D01*
X588792Y277206D01*
X588772Y277166D01*
X588672Y277026D01*
X588642Y276996D01*
Y275866D01*
X588632Y275741D01*
X588592Y275616D01*
X588532Y275506D01*
X588452Y275406D01*
X588352Y275326D01*
X588242Y275266D01*
X588117Y275226D01*
X587992Y275216D01*
X587867Y275226D01*
X587742Y275266D01*
X587632Y275326D01*
X587532Y275406D01*
X587452Y275506D01*
X587392Y275616D01*
X587352Y275741D01*
X587342Y275866D01*
Y276996D01*
X587312Y277026D01*
X587212Y277166D01*
X587192Y277206D01*
X587177Y277241D01*
X587157Y277281D01*
X587142Y277321D01*
X587132Y277361D01*
X587117Y277406D01*
X587112Y277446D01*
X587102Y277486D01*
X587097Y277531D01*
Y277571D01*
X587092Y277616D01*
X587097Y277661D01*
Y277701D01*
X587102Y277746D01*
X587112Y277786D01*
X587117Y277826D01*
X587132Y277871D01*
X587142Y277911D01*
X587157Y277951D01*
X587177Y277991D01*
X587192Y278026D01*
X587212Y278066D01*
X587312Y278206D01*
X587342Y278236D01*
Y281666D01*
X587352Y281791D01*
X587392Y281916D01*
X587452Y282026D01*
X587532Y282126D01*
X587632Y282206D01*
X587742Y282266D01*
X587867Y282306D01*
X587992Y282316D01*
G37*
G36*
G01X592717D02*
X592842Y282306D01*
X592967Y282266D01*
X593077Y282206D01*
X593177Y282126D01*
X593257Y282026D01*
X593317Y281916D01*
X593357Y281791D01*
X593367Y281666D01*
Y278236D01*
X593397Y278206D01*
X593497Y278066D01*
X593517Y278026D01*
X593532Y277991D01*
X593552Y277951D01*
X593567Y277911D01*
X593577Y277871D01*
X593592Y277826D01*
X593597Y277786D01*
X593607Y277746D01*
X593612Y277701D01*
Y277661D01*
X593617Y277616D01*
X593612Y277571D01*
Y277531D01*
X593607Y277486D01*
X593597Y277446D01*
X593592Y277406D01*
X593577Y277361D01*
X593567Y277321D01*
X593552Y277281D01*
X593532Y277241D01*
X593517Y277206D01*
X593497Y277166D01*
X593397Y277026D01*
X593367Y276996D01*
Y275866D01*
X593357Y275741D01*
X593317Y275616D01*
X593257Y275506D01*
X593177Y275406D01*
X593077Y275326D01*
X592967Y275266D01*
X592842Y275226D01*
X592717Y275216D01*
X592592Y275226D01*
X592467Y275266D01*
X592357Y275326D01*
X592257Y275406D01*
X592177Y275506D01*
X592117Y275616D01*
X592077Y275741D01*
X592067Y275866D01*
Y276996D01*
X592037Y277026D01*
X591937Y277166D01*
X591917Y277206D01*
X591902Y277241D01*
X591882Y277281D01*
X591867Y277321D01*
X591857Y277361D01*
X591842Y277406D01*
X591837Y277446D01*
X591827Y277486D01*
X591822Y277531D01*
Y277571D01*
X591817Y277616D01*
X591822Y277661D01*
Y277701D01*
X591827Y277746D01*
X591837Y277786D01*
X591842Y277826D01*
X591857Y277871D01*
X591867Y277911D01*
X591882Y277951D01*
X591902Y277991D01*
X591917Y278026D01*
X591937Y278066D01*
X592037Y278206D01*
X592067Y278236D01*
Y281666D01*
X592077Y281791D01*
X592117Y281916D01*
X592177Y282026D01*
X592257Y282126D01*
X592357Y282206D01*
X592467Y282266D01*
X592592Y282306D01*
X592717Y282316D01*
G37*
G36*
G01X597441D02*
X597566Y282306D01*
X597691Y282266D01*
X597801Y282206D01*
X597901Y282126D01*
X597981Y282026D01*
X598041Y281916D01*
X598081Y281791D01*
X598091Y281666D01*
Y278236D01*
X598121Y278206D01*
X598221Y278066D01*
X598241Y278026D01*
X598256Y277991D01*
X598276Y277951D01*
X598291Y277911D01*
X598301Y277871D01*
X598316Y277826D01*
X598321Y277786D01*
X598331Y277746D01*
X598336Y277701D01*
Y277661D01*
X598341Y277616D01*
X598336Y277571D01*
Y277531D01*
X598331Y277486D01*
X598321Y277446D01*
X598316Y277406D01*
X598301Y277361D01*
X598291Y277321D01*
X598276Y277281D01*
X598256Y277241D01*
X598241Y277206D01*
X598221Y277166D01*
X598121Y277026D01*
X598091Y276996D01*
Y275866D01*
X598081Y275741D01*
X598041Y275616D01*
X597981Y275506D01*
X597901Y275406D01*
X597801Y275326D01*
X597691Y275266D01*
X597566Y275226D01*
X597441Y275216D01*
X597316Y275226D01*
X597191Y275266D01*
X597081Y275326D01*
X596981Y275406D01*
X596901Y275506D01*
X596841Y275616D01*
X596801Y275741D01*
X596791Y275866D01*
Y276996D01*
X596761Y277026D01*
X596661Y277166D01*
X596641Y277206D01*
X596626Y277241D01*
X596606Y277281D01*
X596591Y277321D01*
X596581Y277361D01*
X596566Y277406D01*
X596561Y277446D01*
X596551Y277486D01*
X596546Y277531D01*
Y277571D01*
X596541Y277616D01*
X596546Y277661D01*
Y277701D01*
X596551Y277746D01*
X596561Y277786D01*
X596566Y277826D01*
X596581Y277871D01*
X596591Y277911D01*
X596606Y277951D01*
X596626Y277991D01*
X596641Y278026D01*
X596661Y278066D01*
X596761Y278206D01*
X596791Y278236D01*
Y281666D01*
X596801Y281791D01*
X596841Y281916D01*
X596901Y282026D01*
X596981Y282126D01*
X597081Y282206D01*
X597191Y282266D01*
X597316Y282306D01*
X597441Y282316D01*
G37*
G36*
G01X602166D02*
X602291Y282306D01*
X602416Y282266D01*
X602526Y282206D01*
X602626Y282126D01*
X602706Y282026D01*
X602766Y281916D01*
X602806Y281791D01*
X602816Y281666D01*
Y278236D01*
X602846Y278206D01*
X602946Y278066D01*
X602966Y278026D01*
X602981Y277991D01*
X603001Y277951D01*
X603016Y277911D01*
X603026Y277871D01*
X603041Y277826D01*
X603046Y277786D01*
X603056Y277746D01*
X603061Y277701D01*
Y277661D01*
X603066Y277616D01*
X603061Y277571D01*
Y277531D01*
X603056Y277486D01*
X603046Y277446D01*
X603041Y277406D01*
X603026Y277361D01*
X603016Y277321D01*
X603001Y277281D01*
X602981Y277241D01*
X602966Y277206D01*
X602946Y277166D01*
X602846Y277026D01*
X602816Y276996D01*
Y275866D01*
X602806Y275741D01*
X602766Y275616D01*
X602706Y275506D01*
X602626Y275406D01*
X602526Y275326D01*
X602416Y275266D01*
X602291Y275226D01*
X602166Y275216D01*
X602041Y275226D01*
X601916Y275266D01*
X601806Y275326D01*
X601706Y275406D01*
X601626Y275506D01*
X601566Y275616D01*
X601526Y275741D01*
X601516Y275866D01*
Y276996D01*
X601486Y277026D01*
X601386Y277166D01*
X601366Y277206D01*
X601351Y277241D01*
X601331Y277281D01*
X601316Y277321D01*
X601306Y277361D01*
X601291Y277406D01*
X601286Y277446D01*
X601276Y277486D01*
X601271Y277531D01*
Y277571D01*
X601266Y277616D01*
X601271Y277661D01*
Y277701D01*
X601276Y277746D01*
X601286Y277786D01*
X601291Y277826D01*
X601306Y277871D01*
X601316Y277911D01*
X601331Y277951D01*
X601351Y277991D01*
X601366Y278026D01*
X601386Y278066D01*
X601486Y278206D01*
X601516Y278236D01*
Y281666D01*
X601526Y281791D01*
X601566Y281916D01*
X601626Y282026D01*
X601706Y282126D01*
X601806Y282206D01*
X601916Y282266D01*
X602041Y282306D01*
X602166Y282316D01*
G37*
G36*
G01X606890D02*
X607015Y282306D01*
X607140Y282266D01*
X607250Y282206D01*
X607350Y282126D01*
X607430Y282026D01*
X607490Y281916D01*
X607530Y281791D01*
X607540Y281666D01*
Y278236D01*
X607570Y278206D01*
X607670Y278066D01*
X607690Y278026D01*
X607705Y277991D01*
X607725Y277951D01*
X607740Y277911D01*
X607750Y277871D01*
X607765Y277826D01*
X607770Y277786D01*
X607780Y277746D01*
X607785Y277701D01*
Y277661D01*
X607790Y277616D01*
X607785Y277571D01*
Y277531D01*
X607780Y277486D01*
X607770Y277446D01*
X607765Y277406D01*
X607750Y277361D01*
X607740Y277321D01*
X607725Y277281D01*
X607705Y277241D01*
X607690Y277206D01*
X607670Y277166D01*
X607570Y277026D01*
X607540Y276996D01*
Y275866D01*
X607530Y275741D01*
X607490Y275616D01*
X607430Y275506D01*
X607350Y275406D01*
X607250Y275326D01*
X607140Y275266D01*
X607015Y275226D01*
X606890Y275216D01*
X606765Y275226D01*
X606640Y275266D01*
X606530Y275326D01*
X606430Y275406D01*
X606350Y275506D01*
X606290Y275616D01*
X606250Y275741D01*
X606240Y275866D01*
Y276996D01*
X606210Y277026D01*
X606110Y277166D01*
X606090Y277206D01*
X606075Y277241D01*
X606055Y277281D01*
X606040Y277321D01*
X606030Y277361D01*
X606015Y277406D01*
X606010Y277446D01*
X606000Y277486D01*
X605995Y277531D01*
Y277571D01*
X605990Y277616D01*
X605995Y277661D01*
Y277701D01*
X606000Y277746D01*
X606010Y277786D01*
X606015Y277826D01*
X606030Y277871D01*
X606040Y277911D01*
X606055Y277951D01*
X606075Y277991D01*
X606090Y278026D01*
X606110Y278066D01*
X606210Y278206D01*
X606240Y278236D01*
Y281666D01*
X606250Y281791D01*
X606290Y281916D01*
X606350Y282026D01*
X606430Y282126D01*
X606530Y282206D01*
X606640Y282266D01*
X606765Y282306D01*
X606890Y282316D01*
G37*
G36*
G01X611614D02*
X611739Y282306D01*
X611864Y282266D01*
X611974Y282206D01*
X612074Y282126D01*
X612154Y282026D01*
X612214Y281916D01*
X612254Y281791D01*
X612264Y281666D01*
Y278236D01*
X612294Y278206D01*
X612394Y278066D01*
X612414Y278026D01*
X612429Y277991D01*
X612449Y277951D01*
X612464Y277911D01*
X612474Y277871D01*
X612489Y277826D01*
X612494Y277786D01*
X612504Y277746D01*
X612509Y277701D01*
Y277661D01*
X612514Y277616D01*
X612509Y277571D01*
Y277531D01*
X612504Y277486D01*
X612494Y277446D01*
X612489Y277406D01*
X612474Y277361D01*
X612464Y277321D01*
X612449Y277281D01*
X612429Y277241D01*
X612414Y277206D01*
X612394Y277166D01*
X612294Y277026D01*
X612264Y276996D01*
Y275866D01*
X612254Y275741D01*
X612214Y275616D01*
X612154Y275506D01*
X612074Y275406D01*
X611974Y275326D01*
X611864Y275266D01*
X611739Y275226D01*
X611614Y275216D01*
X611489Y275226D01*
X611364Y275266D01*
X611254Y275326D01*
X611154Y275406D01*
X611074Y275506D01*
X611014Y275616D01*
X610974Y275741D01*
X610964Y275866D01*
Y276996D01*
X610934Y277026D01*
X610834Y277166D01*
X610814Y277206D01*
X610799Y277241D01*
X610779Y277281D01*
X610764Y277321D01*
X610754Y277361D01*
X610739Y277406D01*
X610734Y277446D01*
X610724Y277486D01*
X610719Y277531D01*
Y277571D01*
X610714Y277616D01*
X610719Y277661D01*
Y277701D01*
X610724Y277746D01*
X610734Y277786D01*
X610739Y277826D01*
X610754Y277871D01*
X610764Y277911D01*
X610779Y277951D01*
X610799Y277991D01*
X610814Y278026D01*
X610834Y278066D01*
X610934Y278206D01*
X610964Y278236D01*
Y281666D01*
X610974Y281791D01*
X611014Y281916D01*
X611074Y282026D01*
X611154Y282126D01*
X611254Y282206D01*
X611364Y282266D01*
X611489Y282306D01*
X611614Y282316D01*
G37*
G36*
G01X616339D02*
X616464Y282306D01*
X616589Y282266D01*
X616699Y282206D01*
X616799Y282126D01*
X616879Y282026D01*
X616939Y281916D01*
X616979Y281791D01*
X616989Y281666D01*
Y278236D01*
X617019Y278206D01*
X617119Y278066D01*
X617139Y278026D01*
X617154Y277991D01*
X617174Y277951D01*
X617189Y277911D01*
X617199Y277871D01*
X617214Y277826D01*
X617219Y277786D01*
X617229Y277746D01*
X617234Y277701D01*
Y277661D01*
X617239Y277616D01*
X617234Y277571D01*
Y277531D01*
X617229Y277486D01*
X617219Y277446D01*
X617214Y277406D01*
X617199Y277361D01*
X617189Y277321D01*
X617174Y277281D01*
X617154Y277241D01*
X617139Y277206D01*
X617119Y277166D01*
X617019Y277026D01*
X616989Y276996D01*
Y275866D01*
X616979Y275741D01*
X616939Y275616D01*
X616879Y275506D01*
X616799Y275406D01*
X616699Y275326D01*
X616589Y275266D01*
X616464Y275226D01*
X616339Y275216D01*
X616214Y275226D01*
X616089Y275266D01*
X615979Y275326D01*
X615879Y275406D01*
X615799Y275506D01*
X615739Y275616D01*
X615699Y275741D01*
X615689Y275866D01*
Y276996D01*
X615659Y277026D01*
X615559Y277166D01*
X615539Y277206D01*
X615524Y277241D01*
X615504Y277281D01*
X615489Y277321D01*
X615479Y277361D01*
X615464Y277406D01*
X615459Y277446D01*
X615449Y277486D01*
X615444Y277531D01*
Y277571D01*
X615439Y277616D01*
X615444Y277661D01*
Y277701D01*
X615449Y277746D01*
X615459Y277786D01*
X615464Y277826D01*
X615479Y277871D01*
X615489Y277911D01*
X615504Y277951D01*
X615524Y277991D01*
X615539Y278026D01*
X615559Y278066D01*
X615659Y278206D01*
X615689Y278236D01*
Y281666D01*
X615699Y281791D01*
X615739Y281916D01*
X615799Y282026D01*
X615879Y282126D01*
X615979Y282206D01*
X616089Y282266D01*
X616214Y282306D01*
X616339Y282316D01*
G37*
G36*
G01X621063D02*
X621188Y282306D01*
X621313Y282266D01*
X621423Y282206D01*
X621523Y282126D01*
X621603Y282026D01*
X621663Y281916D01*
X621703Y281791D01*
X621713Y281666D01*
Y278236D01*
X621743Y278206D01*
X621843Y278066D01*
X621863Y278026D01*
X621878Y277991D01*
X621898Y277951D01*
X621913Y277911D01*
X621923Y277871D01*
X621938Y277826D01*
X621943Y277786D01*
X621953Y277746D01*
X621958Y277701D01*
Y277661D01*
X621963Y277616D01*
X621958Y277571D01*
Y277531D01*
X621953Y277486D01*
X621943Y277446D01*
X621938Y277406D01*
X621923Y277361D01*
X621913Y277321D01*
X621898Y277281D01*
X621878Y277241D01*
X621863Y277206D01*
X621843Y277166D01*
X621743Y277026D01*
X621713Y276996D01*
Y275866D01*
X621703Y275741D01*
X621663Y275616D01*
X621603Y275506D01*
X621523Y275406D01*
X621423Y275326D01*
X621313Y275266D01*
X621188Y275226D01*
X621063Y275216D01*
X620938Y275226D01*
X620813Y275266D01*
X620703Y275326D01*
X620603Y275406D01*
X620523Y275506D01*
X620463Y275616D01*
X620423Y275741D01*
X620413Y275866D01*
Y276996D01*
X620383Y277026D01*
X620283Y277166D01*
X620263Y277206D01*
X620248Y277241D01*
X620228Y277281D01*
X620213Y277321D01*
X620203Y277361D01*
X620188Y277406D01*
X620183Y277446D01*
X620173Y277486D01*
X620168Y277531D01*
Y277571D01*
X620163Y277616D01*
X620168Y277661D01*
Y277701D01*
X620173Y277746D01*
X620183Y277786D01*
X620188Y277826D01*
X620203Y277871D01*
X620213Y277911D01*
X620228Y277951D01*
X620248Y277991D01*
X620263Y278026D01*
X620283Y278066D01*
X620383Y278206D01*
X620413Y278236D01*
Y281666D01*
X620423Y281791D01*
X620463Y281916D01*
X620523Y282026D01*
X620603Y282126D01*
X620703Y282206D01*
X620813Y282266D01*
X620938Y282306D01*
X621063Y282316D01*
G37*
G36*
G01X625788D02*
X625913Y282306D01*
X626038Y282266D01*
X626148Y282206D01*
X626248Y282126D01*
X626328Y282026D01*
X626388Y281916D01*
X626428Y281791D01*
X626438Y281666D01*
Y278236D01*
X626468Y278206D01*
X626568Y278066D01*
X626588Y278026D01*
X626603Y277991D01*
X626623Y277951D01*
X626638Y277911D01*
X626648Y277871D01*
X626663Y277826D01*
X626668Y277786D01*
X626678Y277746D01*
X626683Y277701D01*
Y277661D01*
X626688Y277616D01*
X626683Y277571D01*
Y277531D01*
X626678Y277486D01*
X626668Y277446D01*
X626663Y277406D01*
X626648Y277361D01*
X626638Y277321D01*
X626623Y277281D01*
X626603Y277241D01*
X626588Y277206D01*
X626568Y277166D01*
X626468Y277026D01*
X626438Y276996D01*
Y275866D01*
X626428Y275741D01*
X626388Y275616D01*
X626328Y275506D01*
X626248Y275406D01*
X626148Y275326D01*
X626038Y275266D01*
X625913Y275226D01*
X625788Y275216D01*
X625663Y275226D01*
X625538Y275266D01*
X625428Y275326D01*
X625328Y275406D01*
X625248Y275506D01*
X625188Y275616D01*
X625148Y275741D01*
X625138Y275866D01*
Y276996D01*
X625108Y277026D01*
X625008Y277166D01*
X624988Y277206D01*
X624973Y277241D01*
X624953Y277281D01*
X624938Y277321D01*
X624928Y277361D01*
X624913Y277406D01*
X624908Y277446D01*
X624898Y277486D01*
X624893Y277531D01*
Y277571D01*
X624888Y277616D01*
X624893Y277661D01*
Y277701D01*
X624898Y277746D01*
X624908Y277786D01*
X624913Y277826D01*
X624928Y277871D01*
X624938Y277911D01*
X624953Y277951D01*
X624973Y277991D01*
X624988Y278026D01*
X625008Y278066D01*
X625108Y278206D01*
X625138Y278236D01*
Y281666D01*
X625148Y281791D01*
X625188Y281916D01*
X625248Y282026D01*
X625328Y282126D01*
X625428Y282206D01*
X625538Y282266D01*
X625663Y282306D01*
X625788Y282316D01*
G37*
G36*
G01X630512D02*
X630637Y282306D01*
X630762Y282266D01*
X630872Y282206D01*
X630972Y282126D01*
X631052Y282026D01*
X631112Y281916D01*
X631152Y281791D01*
X631162Y281666D01*
Y278236D01*
X631192Y278206D01*
X631292Y278066D01*
X631312Y278026D01*
X631327Y277991D01*
X631347Y277951D01*
X631362Y277911D01*
X631372Y277871D01*
X631387Y277826D01*
X631392Y277786D01*
X631402Y277746D01*
X631407Y277701D01*
Y277661D01*
X631412Y277616D01*
X631407Y277571D01*
Y277531D01*
X631402Y277486D01*
X631392Y277446D01*
X631387Y277406D01*
X631372Y277361D01*
X631362Y277321D01*
X631347Y277281D01*
X631327Y277241D01*
X631312Y277206D01*
X631292Y277166D01*
X631192Y277026D01*
X631162Y276996D01*
Y275866D01*
X631152Y275741D01*
X631112Y275616D01*
X631052Y275506D01*
X630972Y275406D01*
X630872Y275326D01*
X630762Y275266D01*
X630637Y275226D01*
X630512Y275216D01*
X630387Y275226D01*
X630262Y275266D01*
X630152Y275326D01*
X630052Y275406D01*
X629972Y275506D01*
X629912Y275616D01*
X629872Y275741D01*
X629862Y275866D01*
Y276996D01*
X629832Y277026D01*
X629732Y277166D01*
X629712Y277206D01*
X629697Y277241D01*
X629677Y277281D01*
X629662Y277321D01*
X629652Y277361D01*
X629637Y277406D01*
X629632Y277446D01*
X629622Y277486D01*
X629617Y277531D01*
Y277571D01*
X629612Y277616D01*
X629617Y277661D01*
Y277701D01*
X629622Y277746D01*
X629632Y277786D01*
X629637Y277826D01*
X629652Y277871D01*
X629662Y277911D01*
X629677Y277951D01*
X629697Y277991D01*
X629712Y278026D01*
X629732Y278066D01*
X629832Y278206D01*
X629862Y278236D01*
Y281666D01*
X629872Y281791D01*
X629912Y281916D01*
X629972Y282026D01*
X630052Y282126D01*
X630152Y282206D01*
X630262Y282266D01*
X630387Y282306D01*
X630512Y282316D01*
G37*
G36*
G01X635236D02*
X635361Y282306D01*
X635486Y282266D01*
X635596Y282206D01*
X635696Y282126D01*
X635776Y282026D01*
X635836Y281916D01*
X635876Y281791D01*
X635886Y281666D01*
Y278236D01*
X635916Y278206D01*
X636016Y278066D01*
X636036Y278026D01*
X636051Y277991D01*
X636071Y277951D01*
X636086Y277911D01*
X636096Y277871D01*
X636111Y277826D01*
X636116Y277786D01*
X636126Y277746D01*
X636131Y277701D01*
Y277661D01*
X636136Y277616D01*
X636131Y277571D01*
Y277531D01*
X636126Y277486D01*
X636116Y277446D01*
X636111Y277406D01*
X636096Y277361D01*
X636086Y277321D01*
X636071Y277281D01*
X636051Y277241D01*
X636036Y277206D01*
X636016Y277166D01*
X635916Y277026D01*
X635886Y276996D01*
Y275866D01*
X635876Y275741D01*
X635836Y275616D01*
X635776Y275506D01*
X635696Y275406D01*
X635596Y275326D01*
X635486Y275266D01*
X635361Y275226D01*
X635236Y275216D01*
X635111Y275226D01*
X634986Y275266D01*
X634876Y275326D01*
X634776Y275406D01*
X634696Y275506D01*
X634636Y275616D01*
X634596Y275741D01*
X634586Y275866D01*
Y276996D01*
X634556Y277026D01*
X634456Y277166D01*
X634436Y277206D01*
X634421Y277241D01*
X634401Y277281D01*
X634386Y277321D01*
X634376Y277361D01*
X634361Y277406D01*
X634356Y277446D01*
X634346Y277486D01*
X634341Y277531D01*
Y277571D01*
X634336Y277616D01*
X634341Y277661D01*
Y277701D01*
X634346Y277746D01*
X634356Y277786D01*
X634361Y277826D01*
X634376Y277871D01*
X634386Y277911D01*
X634401Y277951D01*
X634421Y277991D01*
X634436Y278026D01*
X634456Y278066D01*
X634556Y278206D01*
X634586Y278236D01*
Y281666D01*
X634596Y281791D01*
X634636Y281916D01*
X634696Y282026D01*
X634776Y282126D01*
X634876Y282206D01*
X634986Y282266D01*
X635111Y282306D01*
X635236Y282316D01*
G37*
G36*
G01X639961D02*
X640086Y282306D01*
X640211Y282266D01*
X640321Y282206D01*
X640421Y282126D01*
X640501Y282026D01*
X640561Y281916D01*
X640601Y281791D01*
X640611Y281666D01*
Y278236D01*
X640641Y278206D01*
X640741Y278066D01*
X640761Y278026D01*
X640776Y277991D01*
X640796Y277951D01*
X640811Y277911D01*
X640821Y277871D01*
X640836Y277826D01*
X640841Y277786D01*
X640851Y277746D01*
X640856Y277701D01*
Y277661D01*
X640861Y277616D01*
X640856Y277571D01*
Y277531D01*
X640851Y277486D01*
X640841Y277446D01*
X640836Y277406D01*
X640821Y277361D01*
X640811Y277321D01*
X640796Y277281D01*
X640776Y277241D01*
X640761Y277206D01*
X640741Y277166D01*
X640641Y277026D01*
X640611Y276996D01*
Y275866D01*
X640601Y275741D01*
X640561Y275616D01*
X640501Y275506D01*
X640421Y275406D01*
X640321Y275326D01*
X640211Y275266D01*
X640086Y275226D01*
X639961Y275216D01*
X639836Y275226D01*
X639711Y275266D01*
X639601Y275326D01*
X639501Y275406D01*
X639421Y275506D01*
X639361Y275616D01*
X639321Y275741D01*
X639311Y275866D01*
Y276996D01*
X639281Y277026D01*
X639181Y277166D01*
X639161Y277206D01*
X639146Y277241D01*
X639126Y277281D01*
X639111Y277321D01*
X639101Y277361D01*
X639086Y277406D01*
X639081Y277446D01*
X639071Y277486D01*
X639066Y277531D01*
Y277571D01*
X639061Y277616D01*
X639066Y277661D01*
Y277701D01*
X639071Y277746D01*
X639081Y277786D01*
X639086Y277826D01*
X639101Y277871D01*
X639111Y277911D01*
X639126Y277951D01*
X639146Y277991D01*
X639161Y278026D01*
X639181Y278066D01*
X639281Y278206D01*
X639311Y278236D01*
Y281666D01*
X639321Y281791D01*
X639361Y281916D01*
X639421Y282026D01*
X639501Y282126D01*
X639601Y282206D01*
X639711Y282266D01*
X639836Y282306D01*
X639961Y282316D01*
G37*
G36*
G01X644685D02*
X644810Y282306D01*
X644935Y282266D01*
X645045Y282206D01*
X645145Y282126D01*
X645225Y282026D01*
X645285Y281916D01*
X645325Y281791D01*
X645335Y281666D01*
Y278236D01*
X645365Y278206D01*
X645465Y278066D01*
X645485Y278026D01*
X645500Y277991D01*
X645520Y277951D01*
X645535Y277911D01*
X645545Y277871D01*
X645560Y277826D01*
X645565Y277786D01*
X645575Y277746D01*
X645580Y277701D01*
Y277661D01*
X645585Y277616D01*
X645580Y277571D01*
Y277531D01*
X645575Y277486D01*
X645565Y277446D01*
X645560Y277406D01*
X645545Y277361D01*
X645535Y277321D01*
X645520Y277281D01*
X645500Y277241D01*
X645485Y277206D01*
X645465Y277166D01*
X645365Y277026D01*
X645335Y276996D01*
Y275866D01*
X645325Y275741D01*
X645285Y275616D01*
X645225Y275506D01*
X645145Y275406D01*
X645045Y275326D01*
X644935Y275266D01*
X644810Y275226D01*
X644685Y275216D01*
X644560Y275226D01*
X644435Y275266D01*
X644325Y275326D01*
X644225Y275406D01*
X644145Y275506D01*
X644085Y275616D01*
X644045Y275741D01*
X644035Y275866D01*
Y276996D01*
X644005Y277026D01*
X643905Y277166D01*
X643885Y277206D01*
X643870Y277241D01*
X643850Y277281D01*
X643835Y277321D01*
X643825Y277361D01*
X643810Y277406D01*
X643805Y277446D01*
X643795Y277486D01*
X643790Y277531D01*
Y277571D01*
X643785Y277616D01*
X643790Y277661D01*
Y277701D01*
X643795Y277746D01*
X643805Y277786D01*
X643810Y277826D01*
X643825Y277871D01*
X643835Y277911D01*
X643850Y277951D01*
X643870Y277991D01*
X643885Y278026D01*
X643905Y278066D01*
X644005Y278206D01*
X644035Y278236D01*
Y281666D01*
X644045Y281791D01*
X644085Y281916D01*
X644145Y282026D01*
X644225Y282126D01*
X644325Y282206D01*
X644435Y282266D01*
X644560Y282306D01*
X644685Y282316D01*
G37*
G36*
G01X649410D02*
X649535Y282306D01*
X649660Y282266D01*
X649770Y282206D01*
X649870Y282126D01*
X649950Y282026D01*
X650010Y281916D01*
X650050Y281791D01*
X650060Y281666D01*
Y278236D01*
X650090Y278206D01*
X650190Y278066D01*
X650210Y278026D01*
X650225Y277991D01*
X650245Y277951D01*
X650260Y277911D01*
X650270Y277871D01*
X650285Y277826D01*
X650290Y277786D01*
X650300Y277746D01*
X650305Y277701D01*
Y277661D01*
X650310Y277616D01*
X650305Y277571D01*
Y277531D01*
X650300Y277486D01*
X650290Y277446D01*
X650285Y277406D01*
X650270Y277361D01*
X650260Y277321D01*
X650245Y277281D01*
X650225Y277241D01*
X650210Y277206D01*
X650190Y277166D01*
X650090Y277026D01*
X650060Y276996D01*
Y275866D01*
X650050Y275741D01*
X650010Y275616D01*
X649950Y275506D01*
X649870Y275406D01*
X649770Y275326D01*
X649660Y275266D01*
X649535Y275226D01*
X649410Y275216D01*
X649285Y275226D01*
X649160Y275266D01*
X649050Y275326D01*
X648950Y275406D01*
X648870Y275506D01*
X648810Y275616D01*
X648770Y275741D01*
X648760Y275866D01*
Y276996D01*
X648730Y277026D01*
X648630Y277166D01*
X648610Y277206D01*
X648595Y277241D01*
X648575Y277281D01*
X648560Y277321D01*
X648550Y277361D01*
X648535Y277406D01*
X648530Y277446D01*
X648520Y277486D01*
X648515Y277531D01*
Y277571D01*
X648510Y277616D01*
X648515Y277661D01*
Y277701D01*
X648520Y277746D01*
X648530Y277786D01*
X648535Y277826D01*
X648550Y277871D01*
X648560Y277911D01*
X648575Y277951D01*
X648595Y277991D01*
X648610Y278026D01*
X648630Y278066D01*
X648730Y278206D01*
X648760Y278236D01*
Y281666D01*
X648770Y281791D01*
X648810Y281916D01*
X648870Y282026D01*
X648950Y282126D01*
X649050Y282206D01*
X649160Y282266D01*
X649285Y282306D01*
X649410Y282316D01*
G37*
G36*
G01X654134D02*
X654259Y282306D01*
X654384Y282266D01*
X654494Y282206D01*
X654594Y282126D01*
X654674Y282026D01*
X654734Y281916D01*
X654774Y281791D01*
X654784Y281666D01*
Y278236D01*
X654814Y278206D01*
X654914Y278066D01*
X654934Y278026D01*
X654949Y277991D01*
X654969Y277951D01*
X654984Y277911D01*
X654994Y277871D01*
X655009Y277826D01*
X655014Y277786D01*
X655024Y277746D01*
X655029Y277701D01*
Y277661D01*
X655034Y277616D01*
X655029Y277571D01*
Y277531D01*
X655024Y277486D01*
X655014Y277446D01*
X655009Y277406D01*
X654994Y277361D01*
X654984Y277321D01*
X654969Y277281D01*
X654949Y277241D01*
X654934Y277206D01*
X654914Y277166D01*
X654814Y277026D01*
X654784Y276996D01*
Y275866D01*
X654774Y275741D01*
X654734Y275616D01*
X654674Y275506D01*
X654594Y275406D01*
X654494Y275326D01*
X654384Y275266D01*
X654259Y275226D01*
X654134Y275216D01*
X654009Y275226D01*
X653884Y275266D01*
X653774Y275326D01*
X653674Y275406D01*
X653594Y275506D01*
X653534Y275616D01*
X653494Y275741D01*
X653484Y275866D01*
Y276996D01*
X653454Y277026D01*
X653354Y277166D01*
X653334Y277206D01*
X653319Y277241D01*
X653299Y277281D01*
X653284Y277321D01*
X653274Y277361D01*
X653259Y277406D01*
X653254Y277446D01*
X653244Y277486D01*
X653239Y277531D01*
Y277571D01*
X653234Y277616D01*
X653239Y277661D01*
Y277701D01*
X653244Y277746D01*
X653254Y277786D01*
X653259Y277826D01*
X653274Y277871D01*
X653284Y277911D01*
X653299Y277951D01*
X653319Y277991D01*
X653334Y278026D01*
X653354Y278066D01*
X653454Y278206D01*
X653484Y278236D01*
Y281666D01*
X653494Y281791D01*
X653534Y281916D01*
X653594Y282026D01*
X653674Y282126D01*
X653774Y282206D01*
X653884Y282266D01*
X654009Y282306D01*
X654134Y282316D01*
G37*
G36*
G01X668307D02*
X668432Y282306D01*
X668557Y282266D01*
X668667Y282206D01*
X668767Y282126D01*
X668847Y282026D01*
X668907Y281916D01*
X668947Y281791D01*
X668957Y281666D01*
Y278236D01*
X668987Y278206D01*
X669087Y278066D01*
X669107Y278026D01*
X669122Y277991D01*
X669142Y277951D01*
X669157Y277911D01*
X669167Y277871D01*
X669182Y277826D01*
X669187Y277786D01*
X669197Y277746D01*
X669202Y277701D01*
Y277661D01*
X669207Y277616D01*
X669202Y277571D01*
Y277531D01*
X669197Y277486D01*
X669187Y277446D01*
X669182Y277406D01*
X669167Y277361D01*
X669157Y277321D01*
X669142Y277281D01*
X669122Y277241D01*
X669107Y277206D01*
X669087Y277166D01*
X668987Y277026D01*
X668957Y276996D01*
Y275866D01*
X668947Y275741D01*
X668907Y275616D01*
X668847Y275506D01*
X668767Y275406D01*
X668667Y275326D01*
X668557Y275266D01*
X668432Y275226D01*
X668307Y275216D01*
X668182Y275226D01*
X668057Y275266D01*
X667947Y275326D01*
X667847Y275406D01*
X667767Y275506D01*
X667707Y275616D01*
X667667Y275741D01*
X667657Y275866D01*
Y276996D01*
X667627Y277026D01*
X667527Y277166D01*
X667507Y277206D01*
X667492Y277241D01*
X667472Y277281D01*
X667457Y277321D01*
X667447Y277361D01*
X667432Y277406D01*
X667427Y277446D01*
X667417Y277486D01*
X667412Y277531D01*
Y277571D01*
X667407Y277616D01*
X667412Y277661D01*
Y277701D01*
X667417Y277746D01*
X667427Y277786D01*
X667432Y277826D01*
X667447Y277871D01*
X667457Y277911D01*
X667472Y277951D01*
X667492Y277991D01*
X667507Y278026D01*
X667527Y278066D01*
X667627Y278206D01*
X667657Y278236D01*
Y281666D01*
X667667Y281791D01*
X667707Y281916D01*
X667767Y282026D01*
X667847Y282126D01*
X667947Y282206D01*
X668057Y282266D01*
X668182Y282306D01*
X668307Y282316D01*
G37*
G36*
G01X673032D02*
X673157Y282306D01*
X673282Y282266D01*
X673392Y282206D01*
X673492Y282126D01*
X673572Y282026D01*
X673632Y281916D01*
X673672Y281791D01*
X673682Y281666D01*
Y278236D01*
X673712Y278206D01*
X673812Y278066D01*
X673832Y278026D01*
X673847Y277991D01*
X673867Y277951D01*
X673882Y277911D01*
X673892Y277871D01*
X673907Y277826D01*
X673912Y277786D01*
X673922Y277746D01*
X673927Y277701D01*
Y277661D01*
X673932Y277616D01*
X673927Y277571D01*
Y277531D01*
X673922Y277486D01*
X673912Y277446D01*
X673907Y277406D01*
X673892Y277361D01*
X673882Y277321D01*
X673867Y277281D01*
X673847Y277241D01*
X673832Y277206D01*
X673812Y277166D01*
X673712Y277026D01*
X673682Y276996D01*
Y275866D01*
X673672Y275741D01*
X673632Y275616D01*
X673572Y275506D01*
X673492Y275406D01*
X673392Y275326D01*
X673282Y275266D01*
X673157Y275226D01*
X673032Y275216D01*
X672907Y275226D01*
X672782Y275266D01*
X672672Y275326D01*
X672572Y275406D01*
X672492Y275506D01*
X672432Y275616D01*
X672392Y275741D01*
X672382Y275866D01*
Y276996D01*
X672352Y277026D01*
X672252Y277166D01*
X672232Y277206D01*
X672217Y277241D01*
X672197Y277281D01*
X672182Y277321D01*
X672172Y277361D01*
X672157Y277406D01*
X672152Y277446D01*
X672142Y277486D01*
X672137Y277531D01*
Y277571D01*
X672132Y277616D01*
X672137Y277661D01*
Y277701D01*
X672142Y277746D01*
X672152Y277786D01*
X672157Y277826D01*
X672172Y277871D01*
X672182Y277911D01*
X672197Y277951D01*
X672217Y277991D01*
X672232Y278026D01*
X672252Y278066D01*
X672352Y278206D01*
X672382Y278236D01*
Y281666D01*
X672392Y281791D01*
X672432Y281916D01*
X672492Y282026D01*
X672572Y282126D01*
X672672Y282206D01*
X672782Y282266D01*
X672907Y282306D01*
X673032Y282316D01*
G37*
G36*
G01X677756D02*
X677881Y282306D01*
X678006Y282266D01*
X678116Y282206D01*
X678216Y282126D01*
X678296Y282026D01*
X678356Y281916D01*
X678396Y281791D01*
X678406Y281666D01*
Y278236D01*
X678436Y278206D01*
X678536Y278066D01*
X678556Y278026D01*
X678571Y277991D01*
X678591Y277951D01*
X678606Y277911D01*
X678616Y277871D01*
X678631Y277826D01*
X678636Y277786D01*
X678646Y277746D01*
X678651Y277701D01*
Y277661D01*
X678656Y277616D01*
X678651Y277571D01*
Y277531D01*
X678646Y277486D01*
X678636Y277446D01*
X678631Y277406D01*
X678616Y277361D01*
X678606Y277321D01*
X678591Y277281D01*
X678571Y277241D01*
X678556Y277206D01*
X678536Y277166D01*
X678436Y277026D01*
X678406Y276996D01*
Y275866D01*
X678396Y275741D01*
X678356Y275616D01*
X678296Y275506D01*
X678216Y275406D01*
X678116Y275326D01*
X678006Y275266D01*
X677881Y275226D01*
X677756Y275216D01*
X677631Y275226D01*
X677506Y275266D01*
X677396Y275326D01*
X677296Y275406D01*
X677216Y275506D01*
X677156Y275616D01*
X677116Y275741D01*
X677106Y275866D01*
Y276996D01*
X677076Y277026D01*
X676976Y277166D01*
X676956Y277206D01*
X676941Y277241D01*
X676921Y277281D01*
X676906Y277321D01*
X676896Y277361D01*
X676881Y277406D01*
X676876Y277446D01*
X676866Y277486D01*
X676861Y277531D01*
Y277571D01*
X676856Y277616D01*
X676861Y277661D01*
Y277701D01*
X676866Y277746D01*
X676876Y277786D01*
X676881Y277826D01*
X676896Y277871D01*
X676906Y277911D01*
X676921Y277951D01*
X676941Y277991D01*
X676956Y278026D01*
X676976Y278066D01*
X677076Y278206D01*
X677106Y278236D01*
Y281666D01*
X677116Y281791D01*
X677156Y281916D01*
X677216Y282026D01*
X677296Y282126D01*
X677396Y282206D01*
X677506Y282266D01*
X677631Y282306D01*
X677756Y282316D01*
G37*
G36*
G01X682481D02*
X682606Y282306D01*
X682731Y282266D01*
X682841Y282206D01*
X682941Y282126D01*
X683021Y282026D01*
X683081Y281916D01*
X683121Y281791D01*
X683131Y281666D01*
Y278236D01*
X683161Y278206D01*
X683261Y278066D01*
X683281Y278026D01*
X683296Y277991D01*
X683316Y277951D01*
X683331Y277911D01*
X683341Y277871D01*
X683356Y277826D01*
X683361Y277786D01*
X683371Y277746D01*
X683376Y277701D01*
Y277661D01*
X683381Y277616D01*
X683376Y277571D01*
Y277531D01*
X683371Y277486D01*
X683361Y277446D01*
X683356Y277406D01*
X683341Y277361D01*
X683331Y277321D01*
X683316Y277281D01*
X683296Y277241D01*
X683281Y277206D01*
X683261Y277166D01*
X683161Y277026D01*
X683131Y276996D01*
Y275866D01*
X683121Y275741D01*
X683081Y275616D01*
X683021Y275506D01*
X682941Y275406D01*
X682841Y275326D01*
X682731Y275266D01*
X682606Y275226D01*
X682481Y275216D01*
X682356Y275226D01*
X682231Y275266D01*
X682121Y275326D01*
X682021Y275406D01*
X681941Y275506D01*
X681881Y275616D01*
X681841Y275741D01*
X681831Y275866D01*
Y276996D01*
X681801Y277026D01*
X681701Y277166D01*
X681681Y277206D01*
X681666Y277241D01*
X681646Y277281D01*
X681631Y277321D01*
X681621Y277361D01*
X681606Y277406D01*
X681601Y277446D01*
X681591Y277486D01*
X681586Y277531D01*
Y277571D01*
X681581Y277616D01*
X681586Y277661D01*
Y277701D01*
X681591Y277746D01*
X681601Y277786D01*
X681606Y277826D01*
X681621Y277871D01*
X681631Y277911D01*
X681646Y277951D01*
X681666Y277991D01*
X681681Y278026D01*
X681701Y278066D01*
X681801Y278206D01*
X681831Y278236D01*
Y281666D01*
X681841Y281791D01*
X681881Y281916D01*
X681941Y282026D01*
X682021Y282126D01*
X682121Y282206D01*
X682231Y282266D01*
X682356Y282306D01*
X682481Y282316D01*
G37*
G36*
G01X687205D02*
X687330Y282306D01*
X687455Y282266D01*
X687565Y282206D01*
X687665Y282126D01*
X687745Y282026D01*
X687805Y281916D01*
X687845Y281791D01*
X687855Y281666D01*
Y278236D01*
X687885Y278206D01*
X687985Y278066D01*
X688005Y278026D01*
X688020Y277991D01*
X688040Y277951D01*
X688055Y277911D01*
X688065Y277871D01*
X688080Y277826D01*
X688085Y277786D01*
X688095Y277746D01*
X688100Y277701D01*
Y277661D01*
X688105Y277616D01*
X688100Y277571D01*
Y277531D01*
X688095Y277486D01*
X688085Y277446D01*
X688080Y277406D01*
X688065Y277361D01*
X688055Y277321D01*
X688040Y277281D01*
X688020Y277241D01*
X688005Y277206D01*
X687985Y277166D01*
X687885Y277026D01*
X687855Y276996D01*
Y275866D01*
X687845Y275741D01*
X687805Y275616D01*
X687745Y275506D01*
X687665Y275406D01*
X687565Y275326D01*
X687455Y275266D01*
X687330Y275226D01*
X687205Y275216D01*
X687080Y275226D01*
X686955Y275266D01*
X686845Y275326D01*
X686745Y275406D01*
X686665Y275506D01*
X686605Y275616D01*
X686565Y275741D01*
X686555Y275866D01*
Y276996D01*
X686525Y277026D01*
X686425Y277166D01*
X686405Y277206D01*
X686390Y277241D01*
X686370Y277281D01*
X686355Y277321D01*
X686345Y277361D01*
X686330Y277406D01*
X686325Y277446D01*
X686315Y277486D01*
X686310Y277531D01*
Y277571D01*
X686305Y277616D01*
X686310Y277661D01*
Y277701D01*
X686315Y277746D01*
X686325Y277786D01*
X686330Y277826D01*
X686345Y277871D01*
X686355Y277911D01*
X686370Y277951D01*
X686390Y277991D01*
X686405Y278026D01*
X686425Y278066D01*
X686525Y278206D01*
X686555Y278236D01*
Y281666D01*
X686565Y281791D01*
X686605Y281916D01*
X686665Y282026D01*
X686745Y282126D01*
X686845Y282206D01*
X686955Y282266D01*
X687080Y282306D01*
X687205Y282316D01*
G37*
G36*
G01X691929D02*
X692054Y282306D01*
X692179Y282266D01*
X692289Y282206D01*
X692389Y282126D01*
X692469Y282026D01*
X692529Y281916D01*
X692569Y281791D01*
X692579Y281666D01*
Y278236D01*
X692609Y278206D01*
X692709Y278066D01*
X692729Y278026D01*
X692744Y277991D01*
X692764Y277951D01*
X692779Y277911D01*
X692789Y277871D01*
X692804Y277826D01*
X692809Y277786D01*
X692819Y277746D01*
X692824Y277701D01*
Y277661D01*
X692829Y277616D01*
X692824Y277571D01*
Y277531D01*
X692819Y277486D01*
X692809Y277446D01*
X692804Y277406D01*
X692789Y277361D01*
X692779Y277321D01*
X692764Y277281D01*
X692744Y277241D01*
X692729Y277206D01*
X692709Y277166D01*
X692609Y277026D01*
X692579Y276996D01*
Y275866D01*
X692569Y275741D01*
X692529Y275616D01*
X692469Y275506D01*
X692389Y275406D01*
X692289Y275326D01*
X692179Y275266D01*
X692054Y275226D01*
X691929Y275216D01*
X691804Y275226D01*
X691679Y275266D01*
X691569Y275326D01*
X691469Y275406D01*
X691389Y275506D01*
X691329Y275616D01*
X691289Y275741D01*
X691279Y275866D01*
Y276996D01*
X691249Y277026D01*
X691149Y277166D01*
X691129Y277206D01*
X691114Y277241D01*
X691094Y277281D01*
X691079Y277321D01*
X691069Y277361D01*
X691054Y277406D01*
X691049Y277446D01*
X691039Y277486D01*
X691034Y277531D01*
Y277571D01*
X691029Y277616D01*
X691034Y277661D01*
Y277701D01*
X691039Y277746D01*
X691049Y277786D01*
X691054Y277826D01*
X691069Y277871D01*
X691079Y277911D01*
X691094Y277951D01*
X691114Y277991D01*
X691129Y278026D01*
X691149Y278066D01*
X691249Y278206D01*
X691279Y278236D01*
Y281666D01*
X691289Y281791D01*
X691329Y281916D01*
X691389Y282026D01*
X691469Y282126D01*
X691569Y282206D01*
X691679Y282266D01*
X691804Y282306D01*
X691929Y282316D01*
G37*
G36*
G01X696654D02*
X696779Y282306D01*
X696904Y282266D01*
X697014Y282206D01*
X697114Y282126D01*
X697194Y282026D01*
X697254Y281916D01*
X697294Y281791D01*
X697304Y281666D01*
Y278236D01*
X697334Y278206D01*
X697434Y278066D01*
X697454Y278026D01*
X697469Y277991D01*
X697489Y277951D01*
X697504Y277911D01*
X697514Y277871D01*
X697529Y277826D01*
X697534Y277786D01*
X697544Y277746D01*
X697549Y277701D01*
Y277661D01*
X697554Y277616D01*
X697549Y277571D01*
Y277531D01*
X697544Y277486D01*
X697534Y277446D01*
X697529Y277406D01*
X697514Y277361D01*
X697504Y277321D01*
X697489Y277281D01*
X697469Y277241D01*
X697454Y277206D01*
X697434Y277166D01*
X697334Y277026D01*
X697304Y276996D01*
Y275866D01*
X697294Y275741D01*
X697254Y275616D01*
X697194Y275506D01*
X697114Y275406D01*
X697014Y275326D01*
X696904Y275266D01*
X696779Y275226D01*
X696654Y275216D01*
X696529Y275226D01*
X696404Y275266D01*
X696294Y275326D01*
X696194Y275406D01*
X696114Y275506D01*
X696054Y275616D01*
X696014Y275741D01*
X696004Y275866D01*
Y276996D01*
X695974Y277026D01*
X695874Y277166D01*
X695854Y277206D01*
X695839Y277241D01*
X695819Y277281D01*
X695804Y277321D01*
X695794Y277361D01*
X695779Y277406D01*
X695774Y277446D01*
X695764Y277486D01*
X695759Y277531D01*
Y277571D01*
X695754Y277616D01*
X695759Y277661D01*
Y277701D01*
X695764Y277746D01*
X695774Y277786D01*
X695779Y277826D01*
X695794Y277871D01*
X695804Y277911D01*
X695819Y277951D01*
X695839Y277991D01*
X695854Y278026D01*
X695874Y278066D01*
X695974Y278206D01*
X696004Y278236D01*
Y281666D01*
X696014Y281791D01*
X696054Y281916D01*
X696114Y282026D01*
X696194Y282126D01*
X696294Y282206D01*
X696404Y282266D01*
X696529Y282306D01*
X696654Y282316D01*
G37*
G36*
G01X701378D02*
X701503Y282306D01*
X701628Y282266D01*
X701738Y282206D01*
X701838Y282126D01*
X701918Y282026D01*
X701978Y281916D01*
X702018Y281791D01*
X702028Y281666D01*
Y278236D01*
X702058Y278206D01*
X702158Y278066D01*
X702178Y278026D01*
X702193Y277991D01*
X702213Y277951D01*
X702228Y277911D01*
X702238Y277871D01*
X702253Y277826D01*
X702258Y277786D01*
X702268Y277746D01*
X702273Y277701D01*
Y277661D01*
X702278Y277616D01*
X702273Y277571D01*
Y277531D01*
X702268Y277486D01*
X702258Y277446D01*
X702253Y277406D01*
X702238Y277361D01*
X702228Y277321D01*
X702213Y277281D01*
X702193Y277241D01*
X702178Y277206D01*
X702158Y277166D01*
X702058Y277026D01*
X702028Y276996D01*
Y275866D01*
X702018Y275741D01*
X701978Y275616D01*
X701918Y275506D01*
X701838Y275406D01*
X701738Y275326D01*
X701628Y275266D01*
X701503Y275226D01*
X701378Y275216D01*
X701253Y275226D01*
X701128Y275266D01*
X701018Y275326D01*
X700918Y275406D01*
X700838Y275506D01*
X700778Y275616D01*
X700738Y275741D01*
X700728Y275866D01*
Y276996D01*
X700698Y277026D01*
X700598Y277166D01*
X700578Y277206D01*
X700563Y277241D01*
X700543Y277281D01*
X700528Y277321D01*
X700518Y277361D01*
X700503Y277406D01*
X700498Y277446D01*
X700488Y277486D01*
X700483Y277531D01*
Y277571D01*
X700478Y277616D01*
X700483Y277661D01*
Y277701D01*
X700488Y277746D01*
X700498Y277786D01*
X700503Y277826D01*
X700518Y277871D01*
X700528Y277911D01*
X700543Y277951D01*
X700563Y277991D01*
X700578Y278026D01*
X700598Y278066D01*
X700698Y278206D01*
X700728Y278236D01*
Y281666D01*
X700738Y281791D01*
X700778Y281916D01*
X700838Y282026D01*
X700918Y282126D01*
X701018Y282206D01*
X701128Y282266D01*
X701253Y282306D01*
X701378Y282316D01*
G37*
G36*
G01X706103D02*
X706228Y282306D01*
X706353Y282266D01*
X706463Y282206D01*
X706563Y282126D01*
X706643Y282026D01*
X706703Y281916D01*
X706743Y281791D01*
X706753Y281666D01*
Y278236D01*
X706783Y278206D01*
X706883Y278066D01*
X706903Y278026D01*
X706918Y277991D01*
X706938Y277951D01*
X706953Y277911D01*
X706963Y277871D01*
X706978Y277826D01*
X706983Y277786D01*
X706993Y277746D01*
X706998Y277701D01*
Y277661D01*
X707003Y277616D01*
X706998Y277571D01*
Y277531D01*
X706993Y277486D01*
X706983Y277446D01*
X706978Y277406D01*
X706963Y277361D01*
X706953Y277321D01*
X706938Y277281D01*
X706918Y277241D01*
X706903Y277206D01*
X706883Y277166D01*
X706783Y277026D01*
X706753Y276996D01*
Y275866D01*
X706743Y275741D01*
X706703Y275616D01*
X706643Y275506D01*
X706563Y275406D01*
X706463Y275326D01*
X706353Y275266D01*
X706228Y275226D01*
X706103Y275216D01*
X705978Y275226D01*
X705853Y275266D01*
X705743Y275326D01*
X705643Y275406D01*
X705563Y275506D01*
X705503Y275616D01*
X705463Y275741D01*
X705453Y275866D01*
Y276996D01*
X705423Y277026D01*
X705323Y277166D01*
X705303Y277206D01*
X705288Y277241D01*
X705268Y277281D01*
X705253Y277321D01*
X705243Y277361D01*
X705228Y277406D01*
X705223Y277446D01*
X705213Y277486D01*
X705208Y277531D01*
Y277571D01*
X705203Y277616D01*
X705208Y277661D01*
Y277701D01*
X705213Y277746D01*
X705223Y277786D01*
X705228Y277826D01*
X705243Y277871D01*
X705253Y277911D01*
X705268Y277951D01*
X705288Y277991D01*
X705303Y278026D01*
X705323Y278066D01*
X705423Y278206D01*
X705453Y278236D01*
Y281666D01*
X705463Y281791D01*
X705503Y281916D01*
X705563Y282026D01*
X705643Y282126D01*
X705743Y282206D01*
X705853Y282266D01*
X705978Y282306D01*
X706103Y282316D01*
G37*
G36*
G01X710827D02*
X710952Y282306D01*
X711077Y282266D01*
X711187Y282206D01*
X711287Y282126D01*
X711367Y282026D01*
X711427Y281916D01*
X711467Y281791D01*
X711477Y281666D01*
Y278236D01*
X711507Y278206D01*
X711607Y278066D01*
X711627Y278026D01*
X711642Y277991D01*
X711662Y277951D01*
X711677Y277911D01*
X711687Y277871D01*
X711702Y277826D01*
X711707Y277786D01*
X711717Y277746D01*
X711722Y277701D01*
Y277661D01*
X711727Y277616D01*
X711722Y277571D01*
Y277531D01*
X711717Y277486D01*
X711707Y277446D01*
X711702Y277406D01*
X711687Y277361D01*
X711677Y277321D01*
X711662Y277281D01*
X711642Y277241D01*
X711627Y277206D01*
X711607Y277166D01*
X711507Y277026D01*
X711477Y276996D01*
Y275866D01*
X711467Y275741D01*
X711427Y275616D01*
X711367Y275506D01*
X711287Y275406D01*
X711187Y275326D01*
X711077Y275266D01*
X710952Y275226D01*
X710827Y275216D01*
X710702Y275226D01*
X710577Y275266D01*
X710467Y275326D01*
X710367Y275406D01*
X710287Y275506D01*
X710227Y275616D01*
X710187Y275741D01*
X710177Y275866D01*
Y276996D01*
X710147Y277026D01*
X710047Y277166D01*
X710027Y277206D01*
X710012Y277241D01*
X709992Y277281D01*
X709977Y277321D01*
X709967Y277361D01*
X709952Y277406D01*
X709947Y277446D01*
X709937Y277486D01*
X709932Y277531D01*
Y277571D01*
X709927Y277616D01*
X709932Y277661D01*
Y277701D01*
X709937Y277746D01*
X709947Y277786D01*
X709952Y277826D01*
X709967Y277871D01*
X709977Y277911D01*
X709992Y277951D01*
X710012Y277991D01*
X710027Y278026D01*
X710047Y278066D01*
X710147Y278206D01*
X710177Y278236D01*
Y281666D01*
X710187Y281791D01*
X710227Y281916D01*
X710287Y282026D01*
X710367Y282126D01*
X710467Y282206D01*
X710577Y282266D01*
X710702Y282306D01*
X710827Y282316D01*
G37*
G36*
G01X715551D02*
X715676Y282306D01*
X715801Y282266D01*
X715911Y282206D01*
X716011Y282126D01*
X716091Y282026D01*
X716151Y281916D01*
X716191Y281791D01*
X716201Y281666D01*
Y278236D01*
X716231Y278206D01*
X716331Y278066D01*
X716351Y278026D01*
X716366Y277991D01*
X716386Y277951D01*
X716401Y277911D01*
X716411Y277871D01*
X716426Y277826D01*
X716431Y277786D01*
X716441Y277746D01*
X716446Y277701D01*
Y277661D01*
X716451Y277616D01*
X716446Y277571D01*
Y277531D01*
X716441Y277486D01*
X716431Y277446D01*
X716426Y277406D01*
X716411Y277361D01*
X716401Y277321D01*
X716386Y277281D01*
X716366Y277241D01*
X716351Y277206D01*
X716331Y277166D01*
X716231Y277026D01*
X716201Y276996D01*
Y275866D01*
X716191Y275741D01*
X716151Y275616D01*
X716091Y275506D01*
X716011Y275406D01*
X715911Y275326D01*
X715801Y275266D01*
X715676Y275226D01*
X715551Y275216D01*
X715426Y275226D01*
X715301Y275266D01*
X715191Y275326D01*
X715091Y275406D01*
X715011Y275506D01*
X714951Y275616D01*
X714911Y275741D01*
X714901Y275866D01*
Y276996D01*
X714871Y277026D01*
X714771Y277166D01*
X714751Y277206D01*
X714736Y277241D01*
X714716Y277281D01*
X714701Y277321D01*
X714691Y277361D01*
X714676Y277406D01*
X714671Y277446D01*
X714661Y277486D01*
X714656Y277531D01*
Y277571D01*
X714651Y277616D01*
X714656Y277661D01*
Y277701D01*
X714661Y277746D01*
X714671Y277786D01*
X714676Y277826D01*
X714691Y277871D01*
X714701Y277911D01*
X714716Y277951D01*
X714736Y277991D01*
X714751Y278026D01*
X714771Y278066D01*
X714871Y278206D01*
X714901Y278236D01*
Y281666D01*
X714911Y281791D01*
X714951Y281916D01*
X715011Y282026D01*
X715091Y282126D01*
X715191Y282206D01*
X715301Y282266D01*
X715426Y282306D01*
X715551Y282316D01*
G37*
G36*
G01X720276D02*
X720401Y282306D01*
X720526Y282266D01*
X720636Y282206D01*
X720736Y282126D01*
X720816Y282026D01*
X720876Y281916D01*
X720916Y281791D01*
X720926Y281666D01*
Y278236D01*
X720956Y278206D01*
X721056Y278066D01*
X721076Y278026D01*
X721091Y277991D01*
X721111Y277951D01*
X721126Y277911D01*
X721136Y277871D01*
X721151Y277826D01*
X721156Y277786D01*
X721166Y277746D01*
X721171Y277701D01*
Y277661D01*
X721176Y277616D01*
X721171Y277571D01*
Y277531D01*
X721166Y277486D01*
X721156Y277446D01*
X721151Y277406D01*
X721136Y277361D01*
X721126Y277321D01*
X721111Y277281D01*
X721091Y277241D01*
X721076Y277206D01*
X721056Y277166D01*
X720956Y277026D01*
X720926Y276996D01*
Y275866D01*
X720916Y275741D01*
X720876Y275616D01*
X720816Y275506D01*
X720736Y275406D01*
X720636Y275326D01*
X720526Y275266D01*
X720401Y275226D01*
X720276Y275216D01*
X720151Y275226D01*
X720026Y275266D01*
X719916Y275326D01*
X719816Y275406D01*
X719736Y275506D01*
X719676Y275616D01*
X719636Y275741D01*
X719626Y275866D01*
Y276996D01*
X719596Y277026D01*
X719496Y277166D01*
X719476Y277206D01*
X719461Y277241D01*
X719441Y277281D01*
X719426Y277321D01*
X719416Y277361D01*
X719401Y277406D01*
X719396Y277446D01*
X719386Y277486D01*
X719381Y277531D01*
Y277571D01*
X719376Y277616D01*
X719381Y277661D01*
Y277701D01*
X719386Y277746D01*
X719396Y277786D01*
X719401Y277826D01*
X719416Y277871D01*
X719426Y277911D01*
X719441Y277951D01*
X719461Y277991D01*
X719476Y278026D01*
X719496Y278066D01*
X719596Y278206D01*
X719626Y278236D01*
Y281666D01*
X719636Y281791D01*
X719676Y281916D01*
X719736Y282026D01*
X719816Y282126D01*
X719916Y282206D01*
X720026Y282266D01*
X720151Y282306D01*
X720276Y282316D01*
G37*
G36*
G01X725000D02*
X725125Y282306D01*
X725250Y282266D01*
X725360Y282206D01*
X725460Y282126D01*
X725540Y282026D01*
X725600Y281916D01*
X725640Y281791D01*
X725650Y281666D01*
Y278236D01*
X725680Y278206D01*
X725780Y278066D01*
X725800Y278026D01*
X725815Y277991D01*
X725835Y277951D01*
X725850Y277911D01*
X725860Y277871D01*
X725875Y277826D01*
X725880Y277786D01*
X725890Y277746D01*
X725895Y277701D01*
Y277661D01*
X725900Y277616D01*
X725895Y277571D01*
Y277531D01*
X725890Y277486D01*
X725880Y277446D01*
X725875Y277406D01*
X725860Y277361D01*
X725850Y277321D01*
X725835Y277281D01*
X725815Y277241D01*
X725800Y277206D01*
X725780Y277166D01*
X725680Y277026D01*
X725650Y276996D01*
Y275866D01*
X725640Y275741D01*
X725600Y275616D01*
X725540Y275506D01*
X725460Y275406D01*
X725360Y275326D01*
X725250Y275266D01*
X725125Y275226D01*
X725000Y275216D01*
X724875Y275226D01*
X724750Y275266D01*
X724640Y275326D01*
X724540Y275406D01*
X724460Y275506D01*
X724400Y275616D01*
X724360Y275741D01*
X724350Y275866D01*
Y276996D01*
X724320Y277026D01*
X724220Y277166D01*
X724200Y277206D01*
X724185Y277241D01*
X724165Y277281D01*
X724150Y277321D01*
X724140Y277361D01*
X724125Y277406D01*
X724120Y277446D01*
X724110Y277486D01*
X724105Y277531D01*
Y277571D01*
X724100Y277616D01*
X724105Y277661D01*
Y277701D01*
X724110Y277746D01*
X724120Y277786D01*
X724125Y277826D01*
X724140Y277871D01*
X724150Y277911D01*
X724165Y277951D01*
X724185Y277991D01*
X724200Y278026D01*
X724220Y278066D01*
X724320Y278206D01*
X724350Y278236D01*
Y281666D01*
X724360Y281791D01*
X724400Y281916D01*
X724460Y282026D01*
X724540Y282126D01*
X724640Y282206D01*
X724750Y282266D01*
X724875Y282306D01*
X725000Y282316D01*
G37*
G36*
G01X729725D02*
X729850Y282306D01*
X729975Y282266D01*
X730085Y282206D01*
X730185Y282126D01*
X730265Y282026D01*
X730325Y281916D01*
X730365Y281791D01*
X730375Y281666D01*
Y278236D01*
X730405Y278206D01*
X730505Y278066D01*
X730525Y278026D01*
X730540Y277991D01*
X730560Y277951D01*
X730575Y277911D01*
X730585Y277871D01*
X730600Y277826D01*
X730605Y277786D01*
X730615Y277746D01*
X730620Y277701D01*
Y277661D01*
X730625Y277616D01*
X730620Y277571D01*
Y277531D01*
X730615Y277486D01*
X730605Y277446D01*
X730600Y277406D01*
X730585Y277361D01*
X730575Y277321D01*
X730560Y277281D01*
X730540Y277241D01*
X730525Y277206D01*
X730505Y277166D01*
X730405Y277026D01*
X730375Y276996D01*
Y275866D01*
X730365Y275741D01*
X730325Y275616D01*
X730265Y275506D01*
X730185Y275406D01*
X730085Y275326D01*
X729975Y275266D01*
X729850Y275226D01*
X729725Y275216D01*
X729600Y275226D01*
X729475Y275266D01*
X729365Y275326D01*
X729265Y275406D01*
X729185Y275506D01*
X729125Y275616D01*
X729085Y275741D01*
X729075Y275866D01*
Y276996D01*
X729045Y277026D01*
X728945Y277166D01*
X728925Y277206D01*
X728910Y277241D01*
X728890Y277281D01*
X728875Y277321D01*
X728865Y277361D01*
X728850Y277406D01*
X728845Y277446D01*
X728835Y277486D01*
X728830Y277531D01*
Y277571D01*
X728825Y277616D01*
X728830Y277661D01*
Y277701D01*
X728835Y277746D01*
X728845Y277786D01*
X728850Y277826D01*
X728865Y277871D01*
X728875Y277911D01*
X728890Y277951D01*
X728910Y277991D01*
X728925Y278026D01*
X728945Y278066D01*
X729045Y278206D01*
X729075Y278236D01*
Y281666D01*
X729085Y281791D01*
X729125Y281916D01*
X729185Y282026D01*
X729265Y282126D01*
X729365Y282206D01*
X729475Y282266D01*
X729600Y282306D01*
X729725Y282316D01*
G37*
G36*
G01X734449D02*
X734574Y282306D01*
X734699Y282266D01*
X734809Y282206D01*
X734909Y282126D01*
X734989Y282026D01*
X735049Y281916D01*
X735089Y281791D01*
X735099Y281666D01*
Y278236D01*
X735129Y278206D01*
X735229Y278066D01*
X735249Y278026D01*
X735264Y277991D01*
X735284Y277951D01*
X735299Y277911D01*
X735309Y277871D01*
X735324Y277826D01*
X735329Y277786D01*
X735339Y277746D01*
X735344Y277701D01*
Y277661D01*
X735349Y277616D01*
X735344Y277571D01*
Y277531D01*
X735339Y277486D01*
X735329Y277446D01*
X735324Y277406D01*
X735309Y277361D01*
X735299Y277321D01*
X735284Y277281D01*
X735264Y277241D01*
X735249Y277206D01*
X735229Y277166D01*
X735129Y277026D01*
X735099Y276996D01*
Y275866D01*
X735089Y275741D01*
X735049Y275616D01*
X734989Y275506D01*
X734909Y275406D01*
X734809Y275326D01*
X734699Y275266D01*
X734574Y275226D01*
X734449Y275216D01*
X734324Y275226D01*
X734199Y275266D01*
X734089Y275326D01*
X733989Y275406D01*
X733909Y275506D01*
X733849Y275616D01*
X733809Y275741D01*
X733799Y275866D01*
Y276996D01*
X733769Y277026D01*
X733669Y277166D01*
X733649Y277206D01*
X733634Y277241D01*
X733614Y277281D01*
X733599Y277321D01*
X733589Y277361D01*
X733574Y277406D01*
X733569Y277446D01*
X733559Y277486D01*
X733554Y277531D01*
Y277571D01*
X733549Y277616D01*
X733554Y277661D01*
Y277701D01*
X733559Y277746D01*
X733569Y277786D01*
X733574Y277826D01*
X733589Y277871D01*
X733599Y277911D01*
X733614Y277951D01*
X733634Y277991D01*
X733649Y278026D01*
X733669Y278066D01*
X733769Y278206D01*
X733799Y278236D01*
Y281666D01*
X733809Y281791D01*
X733849Y281916D01*
X733909Y282026D01*
X733989Y282126D01*
X734089Y282206D01*
X734199Y282266D01*
X734324Y282306D01*
X734449Y282316D01*
G37*
G36*
G01X739173D02*
X739298Y282306D01*
X739423Y282266D01*
X739533Y282206D01*
X739633Y282126D01*
X739713Y282026D01*
X739773Y281916D01*
X739813Y281791D01*
X739823Y281666D01*
Y278236D01*
X739853Y278206D01*
X739953Y278066D01*
X739973Y278026D01*
X739988Y277991D01*
X740008Y277951D01*
X740023Y277911D01*
X740033Y277871D01*
X740048Y277826D01*
X740053Y277786D01*
X740063Y277746D01*
X740068Y277701D01*
Y277661D01*
X740073Y277616D01*
X740068Y277571D01*
Y277531D01*
X740063Y277486D01*
X740053Y277446D01*
X740048Y277406D01*
X740033Y277361D01*
X740023Y277321D01*
X740008Y277281D01*
X739988Y277241D01*
X739973Y277206D01*
X739953Y277166D01*
X739853Y277026D01*
X739823Y276996D01*
Y275866D01*
X739813Y275741D01*
X739773Y275616D01*
X739713Y275506D01*
X739633Y275406D01*
X739533Y275326D01*
X739423Y275266D01*
X739298Y275226D01*
X739173Y275216D01*
X739048Y275226D01*
X738923Y275266D01*
X738813Y275326D01*
X738713Y275406D01*
X738633Y275506D01*
X738573Y275616D01*
X738533Y275741D01*
X738523Y275866D01*
Y276996D01*
X738493Y277026D01*
X738393Y277166D01*
X738373Y277206D01*
X738358Y277241D01*
X738338Y277281D01*
X738323Y277321D01*
X738313Y277361D01*
X738298Y277406D01*
X738293Y277446D01*
X738283Y277486D01*
X738278Y277531D01*
Y277571D01*
X738273Y277616D01*
X738278Y277661D01*
Y277701D01*
X738283Y277746D01*
X738293Y277786D01*
X738298Y277826D01*
X738313Y277871D01*
X738323Y277911D01*
X738338Y277951D01*
X738358Y277991D01*
X738373Y278026D01*
X738393Y278066D01*
X738493Y278206D01*
X738523Y278236D01*
Y281666D01*
X738533Y281791D01*
X738573Y281916D01*
X738633Y282026D01*
X738713Y282126D01*
X738813Y282206D01*
X738923Y282266D01*
X739048Y282306D01*
X739173Y282316D01*
G37*
G36*
G01X743898D02*
X744023Y282306D01*
X744148Y282266D01*
X744258Y282206D01*
X744358Y282126D01*
X744438Y282026D01*
X744498Y281916D01*
X744538Y281791D01*
X744548Y281666D01*
Y278236D01*
X744578Y278206D01*
X744678Y278066D01*
X744698Y278026D01*
X744713Y277991D01*
X744733Y277951D01*
X744748Y277911D01*
X744758Y277871D01*
X744773Y277826D01*
X744778Y277786D01*
X744788Y277746D01*
X744793Y277701D01*
Y277661D01*
X744798Y277616D01*
X744793Y277571D01*
Y277531D01*
X744788Y277486D01*
X744778Y277446D01*
X744773Y277406D01*
X744758Y277361D01*
X744748Y277321D01*
X744733Y277281D01*
X744713Y277241D01*
X744698Y277206D01*
X744678Y277166D01*
X744578Y277026D01*
X744548Y276996D01*
Y275866D01*
X744538Y275741D01*
X744498Y275616D01*
X744438Y275506D01*
X744358Y275406D01*
X744258Y275326D01*
X744148Y275266D01*
X744023Y275226D01*
X743898Y275216D01*
X743773Y275226D01*
X743648Y275266D01*
X743538Y275326D01*
X743438Y275406D01*
X743358Y275506D01*
X743298Y275616D01*
X743258Y275741D01*
X743248Y275866D01*
Y276996D01*
X743218Y277026D01*
X743118Y277166D01*
X743098Y277206D01*
X743083Y277241D01*
X743063Y277281D01*
X743048Y277321D01*
X743038Y277361D01*
X743023Y277406D01*
X743018Y277446D01*
X743008Y277486D01*
X743003Y277531D01*
Y277571D01*
X742998Y277616D01*
X743003Y277661D01*
Y277701D01*
X743008Y277746D01*
X743018Y277786D01*
X743023Y277826D01*
X743038Y277871D01*
X743048Y277911D01*
X743063Y277951D01*
X743083Y277991D01*
X743098Y278026D01*
X743118Y278066D01*
X743218Y278206D01*
X743248Y278236D01*
Y281666D01*
X743258Y281791D01*
X743298Y281916D01*
X743358Y282026D01*
X743438Y282126D01*
X743538Y282206D01*
X743648Y282266D01*
X743773Y282306D01*
X743898Y282316D01*
G37*
G36*
G01X748622D02*
X748747Y282306D01*
X748872Y282266D01*
X748982Y282206D01*
X749082Y282126D01*
X749162Y282026D01*
X749222Y281916D01*
X749262Y281791D01*
X749272Y281666D01*
Y278236D01*
X749302Y278206D01*
X749402Y278066D01*
X749422Y278026D01*
X749437Y277991D01*
X749457Y277951D01*
X749472Y277911D01*
X749482Y277871D01*
X749497Y277826D01*
X749502Y277786D01*
X749512Y277746D01*
X749517Y277701D01*
Y277661D01*
X749522Y277616D01*
X749517Y277571D01*
Y277531D01*
X749512Y277486D01*
X749502Y277446D01*
X749497Y277406D01*
X749482Y277361D01*
X749472Y277321D01*
X749457Y277281D01*
X749437Y277241D01*
X749422Y277206D01*
X749402Y277166D01*
X749302Y277026D01*
X749272Y276996D01*
Y275866D01*
X749262Y275741D01*
X749222Y275616D01*
X749162Y275506D01*
X749082Y275406D01*
X748982Y275326D01*
X748872Y275266D01*
X748747Y275226D01*
X748622Y275216D01*
X748497Y275226D01*
X748372Y275266D01*
X748262Y275326D01*
X748162Y275406D01*
X748082Y275506D01*
X748022Y275616D01*
X747982Y275741D01*
X747972Y275866D01*
Y276996D01*
X747942Y277026D01*
X747842Y277166D01*
X747822Y277206D01*
X747807Y277241D01*
X747787Y277281D01*
X747772Y277321D01*
X747762Y277361D01*
X747747Y277406D01*
X747742Y277446D01*
X747732Y277486D01*
X747727Y277531D01*
Y277571D01*
X747722Y277616D01*
X747727Y277661D01*
Y277701D01*
X747732Y277746D01*
X747742Y277786D01*
X747747Y277826D01*
X747762Y277871D01*
X747772Y277911D01*
X747787Y277951D01*
X747807Y277991D01*
X747822Y278026D01*
X747842Y278066D01*
X747942Y278206D01*
X747972Y278236D01*
Y281666D01*
X747982Y281791D01*
X748022Y281916D01*
X748082Y282026D01*
X748162Y282126D01*
X748262Y282206D01*
X748372Y282266D01*
X748497Y282306D01*
X748622Y282316D01*
G37*
G54D40*
X52500Y116000D03*
X51000Y217500D03*
X77200Y194000D03*
X74100Y252600D03*
X82400Y139200D03*
X105500Y197000D03*
Y194000D03*
X182100Y127700D03*
X183100Y176000D03*
X192500Y193500D03*
X265000Y49500D03*
X285500Y219000D03*
X426000Y260500D03*
X474200Y245500D03*
X506500Y155000D03*
X514500Y176000D03*
Y179000D03*
X523500Y215500D03*
X568000Y227000D03*
X604000Y46000D03*
X620500Y208000D03*
X670500Y161000D03*
Y171500D03*
G54D41*
X54000Y127000D03*
X60600Y208500D03*
X73000Y132000D03*
X70200Y265800D03*
X86400Y206600D03*
X98900Y203700D03*
X118500Y131500D03*
X153200Y216000D03*
X150200D03*
X167400Y155600D03*
X182500Y91000D03*
X187600Y149200D03*
X184500D03*
X183500Y188500D03*
X178800Y203600D03*
X181800D03*
X197700Y51500D03*
X194700D03*
X188400Y206250D03*
X216000Y167500D03*
X217700Y191500D03*
X253500Y55000D03*
X250500D03*
X277000Y228300D03*
X274000D03*
X293300Y157500D03*
X314500Y244000D03*
X448000Y254500D03*
X537500Y61000D03*
X538500Y84500D03*
X534500Y210000D03*
X555300Y211100D03*
X585500Y83000D03*
X591500D03*
X594500D03*
X597500Y235000D03*
X616000Y109000D03*
X613000D03*
X609400Y235000D03*
X612500D03*
X619500D03*
X724700Y126400D03*
X721000Y143500D03*
X717000Y193500D03*
X718500Y209900D03*
X733500Y172000D03*
X744500Y192500D03*
Y239000D03*
G54D50*
X99331Y70650D03*
X115669D03*
X531331Y195500D03*
X547669D03*
G54D23*
X19200Y156200D03*
X25800D03*
G54D116*
X617931Y133000D03*
X623069D03*
X634431Y167500D03*
X639569D03*
G54D107*
X520200Y105490D03*
Y103520D03*
Y101550D03*
Y121235D03*
Y119270D03*
Y117300D03*
Y115330D03*
Y113360D03*
Y111395D03*
Y109425D03*
Y107455D03*
Y135015D03*
Y133045D03*
Y131080D03*
Y129110D03*
Y127140D03*
Y125175D03*
Y123205D03*
Y150765D03*
Y148795D03*
Y146825D03*
Y144860D03*
Y142890D03*
Y140920D03*
Y138955D03*
Y136985D03*
Y166510D03*
Y164545D03*
Y162575D03*
Y160605D03*
Y158640D03*
Y156670D03*
Y154700D03*
Y152730D03*
Y170450D03*
Y168480D03*
X603800Y101550D03*
Y103520D03*
Y105490D03*
Y107455D03*
Y109425D03*
Y111395D03*
Y113360D03*
Y115330D03*
Y117300D03*
Y119270D03*
Y121235D03*
Y123205D03*
Y125175D03*
Y127140D03*
Y129110D03*
Y131080D03*
Y133045D03*
Y135015D03*
Y136985D03*
Y138955D03*
Y140920D03*
Y142890D03*
Y144860D03*
Y146825D03*
Y148795D03*
Y150765D03*
Y152730D03*
Y154700D03*
Y156670D03*
Y158640D03*
Y160605D03*
Y162575D03*
Y164545D03*
Y166510D03*
Y168480D03*
Y170450D03*
G54D14*
X18000Y197000D03*
X54700Y269600D03*
X76000Y129000D03*
X67400Y249800D03*
X77100Y262900D03*
X73600Y262809D03*
X96500Y169000D03*
X98500Y192500D03*
X121500Y128500D03*
X164500Y193500D03*
X181000Y81500D03*
X174500Y99800D03*
X182200Y134000D03*
X205600Y49000D03*
X208600D03*
X218500Y212500D03*
X248500Y116500D03*
X242000Y174500D03*
X293300Y160500D03*
X310500Y234500D03*
X423500Y251500D03*
X465500Y147063D03*
X511500Y170000D03*
X633500Y49007D03*
X636800D03*
X645300D03*
X648500Y165500D03*
X650800Y49007D03*
X657500Y219000D03*
X686400Y173300D03*
X717000Y68000D03*
Y200000D03*
X741500Y87000D03*
X737000Y155500D03*
X744700Y70000D03*
X766500Y129500D03*
X805500Y138500D03*
G54D134*
X792515Y146060D03*
G54D32*
G01X10636Y-27865D02*
G02I-12000J0D01*
G01X14636D02*
X-17364D01*
G01X5486D02*
G02I-6850J0D01*
G01X-1364Y-43865D02*
Y-11865D01*
G01X14636Y-43865D02*
Y-123865D01*
G01D02*
X1309236D01*
G01X14636Y-79365D02*
X1309236D01*
G01X14636Y-43865D02*
X1309236D01*
G01X521736D02*
Y-123865D01*
G01X659236Y-43865D02*
Y-123865D01*
G01X774236Y-43865D02*
Y-123865D01*
G01X941736Y-43865D02*
Y-123865D01*
G01X1111736Y-43865D02*
Y-123865D01*
G01X1309236Y-43865D02*
Y-123865D01*
G01X1341236Y-27865D02*
X1309236D01*
G01X1337236D02*
G02I-12000J0D01*
G01X1332086D02*
G02I-6850J0D01*
G01X1325236Y-43865D02*
Y-11865D01*
X38500Y148000D03*
X48500D03*
X41000Y152300D03*
Y143300D03*
X46000D03*
Y152300D03*
X43500Y148000D03*
Y138500D03*
X48500D03*
X38500D03*
X52500Y96500D03*
Y106500D03*
X57500Y96500D03*
X60000Y101500D03*
X50000D03*
X55000D03*
X57500Y106500D03*
X60000Y111300D03*
X50000D03*
X55000D03*
X79500Y230000D03*
X84500D03*
X89500D03*
X84500Y225000D03*
Y235000D03*
X162000Y226000D03*
X167000D03*
Y221500D03*
X162000D03*
Y230500D03*
X167000D03*
X162000Y235000D03*
X741104Y133763D03*
X745104Y129763D03*
X749104Y133763D03*
X745104D03*
Y137763D03*
X788515Y144060D03*
X784515D03*
X796515D03*
X792515D03*
X800515D03*
Y148060D03*
X796515D03*
X792515D03*
G54D125*
X731340Y73615D03*
G54D42*
X54000Y124000D03*
X60600Y205500D03*
X73000Y129000D03*
X70200Y262800D03*
X86400Y203600D03*
X98900Y200700D03*
X118500Y128500D03*
X153200Y213000D03*
X150200D03*
X167400Y152600D03*
X182500Y88000D03*
X187600Y146200D03*
X184500D03*
X183500Y185500D03*
X178800Y200600D03*
X181800D03*
X197700Y48500D03*
X194700D03*
X188400Y203250D03*
X216000Y164500D03*
X217700Y188500D03*
X253500Y52000D03*
X250500D03*
X277000Y225300D03*
X274000D03*
X293300Y154500D03*
X314500Y241000D03*
X448000Y251500D03*
X537500Y58000D03*
X538500Y81500D03*
X534500Y207000D03*
X555300Y208100D03*
X585500Y80000D03*
X591500D03*
X594500D03*
X597500Y232000D03*
X616000Y106000D03*
X613000D03*
X609400Y232000D03*
X612500D03*
X619500D03*
X724700Y123400D03*
X721000Y140500D03*
X717000Y190500D03*
X718500Y206900D03*
X733500Y169000D03*
X744500Y189500D03*
Y236000D03*
G54D33*
X39000Y158000D03*
X46300Y212700D03*
Y207800D03*
X43500Y198800D03*
Y203700D03*
X46500D03*
Y198800D03*
X35000Y222500D03*
Y219000D03*
Y229500D03*
Y226000D03*
Y236500D03*
Y233000D03*
Y243500D03*
Y240000D03*
Y250500D03*
Y247000D03*
Y257500D03*
Y254000D03*
X49300Y212700D03*
Y207800D03*
X64700Y198300D03*
Y201800D03*
X73900Y207200D03*
X80000Y85000D03*
X92300Y207100D03*
X80500Y249800D03*
X89500Y261500D03*
X183000Y75500D03*
X225800Y89900D03*
X440000Y278000D03*
X538500Y234100D03*
X611500Y96000D03*
Y93000D03*
X705000Y192500D03*
X721700Y119700D03*
Y116400D03*
X739200Y111100D03*
X745800Y108100D03*
X748000Y155500D03*
X779500Y16000D03*
G54D51*
X111500Y89850D03*
Y113150D03*
G54D117*
X631500Y83177D03*
Y117823D03*
G54D60*
X136800Y260189D03*
G54D135*
X785015Y152121D03*
G54D24*
X28209Y175152D03*
X30769D03*
X25649D03*
X23089D03*
Y190832D03*
X25649D03*
X28209D03*
X30769D03*
G54D126*
X735277Y67865D03*
X733309D03*
X731340D03*
X729371D03*
X727403D03*
Y79365D03*
X729371D03*
X731340D03*
X733309D03*
X735277D03*
G54D108*
X527550Y94200D03*
X529520D03*
X531490D03*
X533455D03*
X535425D03*
X537395D03*
X539360D03*
X541330D03*
Y177800D03*
X539360D03*
X537395D03*
X535425D03*
X533455D03*
X531490D03*
X529520D03*
X527550D03*
X543300Y94200D03*
X545270D03*
X547235D03*
X549205D03*
X551175D03*
X553140D03*
X555110D03*
Y177800D03*
X553140D03*
X551175D03*
X549205D03*
X547235D03*
X545270D03*
X543300D03*
X557080Y94200D03*
X559045D03*
X561015D03*
X562985D03*
X564955D03*
X566920D03*
X568890D03*
X570860D03*
Y177800D03*
X568890D03*
X566920D03*
X564955D03*
X562985D03*
X561015D03*
X559045D03*
X557080D03*
X572825Y94200D03*
X574795D03*
X576765D03*
X578730D03*
X580700D03*
X582670D03*
X584640D03*
X586605D03*
Y177800D03*
X584640D03*
X582670D03*
X580700D03*
X578730D03*
X576765D03*
X574795D03*
X572825D03*
X588575Y94200D03*
X590545D03*
X592510D03*
X594480D03*
X596450D03*
Y177800D03*
X594480D03*
X592510D03*
X590545D03*
X588575D03*
G54D15*
X18000Y200000D03*
X54700Y272600D03*
X76000Y132000D03*
X67400Y252800D03*
X77100Y265900D03*
X73600Y265809D03*
X96500Y172000D03*
X98500Y195500D03*
X121500Y131500D03*
X164500Y196500D03*
X181000Y84500D03*
X174500Y102800D03*
X182200Y137000D03*
X205600Y52000D03*
X208600D03*
X218500Y215500D03*
X248500Y119500D03*
X242000Y177500D03*
X293300Y163500D03*
X310500Y237500D03*
X423500Y254500D03*
X465500Y150063D03*
X511500Y173000D03*
X633500Y52007D03*
X636800D03*
X645300D03*
X648500Y168500D03*
X650800Y52007D03*
X657500Y222000D03*
X686400Y176300D03*
X717000Y71000D03*
Y203000D03*
X741500Y90000D03*
X737000Y158500D03*
X744700Y73000D03*
X766500Y132500D03*
X805500Y141500D03*
G54D136*
X778850Y243000D03*
X802150D03*
G54D61*
X136800Y255861D03*
G54D118*
X638000Y215500D03*
G54D52*
X108550Y153000D03*
X109200Y165500D03*
X119150Y153000D03*
X119800Y165500D03*
G54D70*
X172811Y226000D03*
Y221000D03*
Y231000D03*
G54D34*
X42717Y191732D03*
G54D16*
X17300Y208100D03*
X29651Y131448D03*
X20300Y133700D03*
X33900Y127200D03*
X24800Y131700D03*
X19800Y161400D03*
X28400Y200100D03*
X34900Y86300D03*
X38464Y98248D03*
X39142Y93495D03*
X42500Y159500D03*
X43000Y220000D03*
X43500Y242000D03*
X44000Y234000D03*
X49500Y120000D03*
X55600Y158700D03*
X51000Y229500D03*
X60127Y217067D03*
X50500Y221500D03*
X73100Y86700D03*
X72000Y82000D03*
X75000Y135700D03*
X67200Y177500D03*
X79000Y190400D03*
X66900Y192500D03*
X74544Y213236D03*
X68652Y212848D03*
X78623Y210704D03*
X67400Y205500D03*
X67813Y227987D03*
X64768Y215669D03*
X67892Y233192D03*
X67988Y239488D03*
X74100Y256200D03*
X64800Y246073D03*
X70100Y259300D03*
X85500Y75000D03*
X85906Y85094D03*
X88000Y186500D03*
X94002Y210600D03*
X83447Y210471D03*
X81960Y199734D03*
X86600Y249500D03*
X93800Y246400D03*
X82000Y254500D03*
X88500Y265000D03*
X81700Y272600D03*
X96000Y161500D03*
X103300Y206800D03*
X107462Y209526D03*
X99900Y216100D03*
X105000Y229213D03*
X99900Y239450D03*
X100700Y231800D03*
X101400Y272600D03*
X116089Y47089D03*
X126000Y72500D03*
X140026Y46584D03*
X133500Y74200D03*
X140500Y182000D03*
X127500Y197000D03*
X137757Y200557D03*
X134500Y226000D03*
X139000Y247500D03*
X131500Y272500D03*
X141000D03*
X156070Y158720D03*
X153100Y170900D03*
X149400Y177700D03*
X154000Y196000D03*
X155900Y200500D03*
X164300Y158700D03*
X161026Y191750D03*
X158600Y208400D03*
X173000Y56423D03*
X186900Y68900D03*
X173524Y65754D03*
X186500Y82700D03*
X178994Y90247D03*
X174700Y88100D03*
X187500Y76100D03*
X175600Y94500D03*
X176100Y106100D03*
X181466Y142065D03*
X187600Y188800D03*
X182100Y207900D03*
X196000Y77125D03*
X196518Y182800D03*
X193000Y189900D03*
X190000Y184000D03*
X212201Y44539D03*
X218500Y49500D03*
X205500Y59000D03*
X212268Y166850D03*
X206300Y192900D03*
X211202Y186727D03*
X229098Y70092D03*
X230000Y74900D03*
X226400Y64609D03*
X229832Y154168D03*
X229500Y160900D03*
X227000Y183300D03*
Y178500D03*
X226292Y173752D03*
X231500Y211500D03*
X234100Y215700D03*
X243736Y66438D03*
X241496Y71328D03*
X241741Y105300D03*
X248700Y96100D03*
X249100Y135836D03*
X244500Y122500D03*
X247500Y127000D03*
X247600Y147327D03*
X249000Y157810D03*
X241500Y168500D03*
X235211Y190389D03*
X246000Y186100D03*
X243000Y214000D03*
X236900Y231300D03*
X253520Y89664D03*
X258000Y79550D03*
X253100Y116000D03*
X258500Y130000D03*
X259000Y145652D03*
X262000Y157500D03*
X264600Y169900D03*
X259779Y173043D03*
X257383Y190111D03*
X257000Y201600D03*
X258400Y229800D03*
X263000Y221500D03*
X257000Y242500D03*
X267121Y70348D03*
X270150Y77000D03*
X276654Y131454D03*
X270977Y182073D03*
X271701Y174800D03*
X273074Y186392D03*
X265400Y187500D03*
X269500Y194400D03*
X270336Y206467D03*
X272700Y214900D03*
X268600Y219059D03*
X274162Y243180D03*
X271200Y235733D03*
X284262Y52009D03*
X295500Y99500D03*
X282000Y146000D03*
X295290Y177645D03*
X290600Y181900D03*
X280700Y186000D03*
X286500Y201500D03*
X292685Y221445D03*
X303400Y73700D03*
X296000Y75940D03*
Y84125D03*
X303900Y80475D03*
X298800Y95400D03*
X299000Y112500D03*
X298500Y130000D03*
X301000Y134500D03*
X297200Y146000D03*
X304300Y141400D03*
X298997Y139003D03*
X304400Y146500D03*
X300276Y162090D03*
X303261Y156952D03*
X298717Y155403D03*
X304303Y164703D03*
X303000Y177200D03*
X297500Y181907D03*
X297000Y192000D03*
X309700Y245800D03*
X314000Y54000D03*
X317500Y45700D03*
X315000Y66500D03*
X314800Y88500D03*
X314100Y233700D03*
X318700Y250400D03*
X320300Y245800D03*
X313000Y250000D03*
X340800Y83900D03*
X331600Y82200D03*
X354141Y87158D03*
X379500Y270000D03*
X387000D03*
X394300Y269900D03*
X413200Y64450D03*
X418600Y85000D03*
X434000Y18500D03*
X428875Y42975D03*
X431990Y49271D03*
X422825Y74925D03*
X431900Y83200D03*
X428500Y224000D03*
X433500Y224400D03*
X443644Y22233D03*
X439892Y42508D03*
X440666Y36034D03*
X440700Y87000D03*
X437300Y83100D03*
X440400Y224000D03*
X435500Y219000D03*
X442500Y258600D03*
X439400Y281600D03*
X465000Y12049D03*
X452500Y26125D03*
X457863Y140000D03*
X450800Y145400D03*
X453900Y149150D03*
X461500Y244500D03*
X465000Y248000D03*
X457300Y271400D03*
X457029Y266505D03*
X456000Y281700D03*
X466100Y23900D03*
X469000Y133000D03*
X510000Y135400D03*
X509900Y142000D03*
Y148855D03*
X498875Y154600D03*
X521500Y70700D03*
X527000Y69500D03*
X525500Y83500D03*
X514000Y103500D03*
X513479Y132021D03*
X513800Y138955D03*
X513500Y145500D03*
X523000Y198000D03*
X522400Y184500D03*
X518000Y198000D03*
X514000Y205200D03*
X532000Y67500D03*
X537300Y65036D03*
X532986Y85675D03*
X534800Y81100D03*
X529698Y222802D03*
X529000Y215500D03*
X535200Y230400D03*
X550000Y85500D03*
X544000Y81000D03*
X543274Y212774D03*
X550860Y226200D03*
X550915Y219430D03*
X547700Y230982D03*
X570500Y85000D03*
X566000Y194000D03*
X568500Y211560D03*
X560500Y202200D03*
X565729Y203031D03*
X570500Y202500D03*
X562300Y217600D03*
X568000Y217500D03*
X582000Y74000D03*
X574500D03*
X573300Y80100D03*
X593000Y73500D03*
X597916Y186411D03*
X601000Y195800D03*
X598900Y200500D03*
X603047Y217747D03*
X615469Y73969D03*
X617000Y79500D03*
Y87000D03*
X609600Y117800D03*
X615500Y119500D03*
X611255Y133045D03*
X617500Y152650D03*
X610955Y138955D03*
X613590Y162596D03*
X612500Y157150D03*
X618500Y162800D03*
X615000Y182500D03*
X612000Y212000D03*
X617949Y223800D03*
X630000Y72000D03*
X623500Y74500D03*
X620000Y101500D03*
Y94000D03*
X623000Y121000D03*
X630000Y136600D03*
X625800Y128500D03*
X623500Y150000D03*
X623700Y162399D03*
X626500Y154900D03*
X624900Y167047D03*
X633000Y162500D03*
X626186Y194451D03*
X644000Y77000D03*
X635225Y125500D03*
X645000Y161000D03*
X642375Y173100D03*
X638524Y178140D03*
X650100Y176700D03*
X636300Y191800D03*
X643800Y232600D03*
X660500Y151289D03*
X662800Y179500D03*
X655500Y173100D03*
X652146Y194648D03*
X663155Y186000D03*
X658479Y202400D03*
X657900Y208000D03*
X662000Y222500D03*
X667800Y90100D03*
X666800Y118400D03*
X674750Y151700D03*
X671100Y166000D03*
X673900Y173600D03*
X695500Y94500D03*
X696500Y123000D03*
X685500Y152000D03*
X681500Y187300D03*
X690400Y188600D03*
X695300Y188650D03*
X691500Y219500D03*
X682544Y219456D03*
X707500Y78000D03*
X705580Y157480D03*
X709879Y165479D03*
X710000Y210000D03*
X697200Y219600D03*
X721000Y69500D03*
X725000Y64000D03*
X722600Y80500D03*
X724200Y104300D03*
X718400Y112800D03*
X724400Y112700D03*
X724900Y133600D03*
X724600Y142800D03*
X719087Y167143D03*
X714842Y173742D03*
X719200Y184100D03*
X718400Y213500D03*
X723500Y224500D03*
X740300Y70200D03*
X739911Y83589D03*
X728200Y84800D03*
X734200Y85300D03*
X729500Y111500D03*
X728440Y125224D03*
X731636Y138979D03*
X734000Y150850D03*
X728589Y150527D03*
X738500Y148500D03*
X730784Y145184D03*
X741167Y153000D03*
X741000Y158500D03*
X736500Y174500D03*
X730400Y179400D03*
X731900Y184000D03*
X733000Y197525D03*
X728740Y206500D03*
X733000Y215000D03*
X730000Y223900D03*
X743500Y100500D03*
X745100Y114900D03*
X752500Y151500D03*
X746782Y149282D03*
X762100Y135000D03*
X769400Y136800D03*
X762800Y129200D03*
X759700Y141100D03*
Y145900D03*
X775665Y146865D03*
X778000Y138000D03*
X791000Y254500D03*
G54D43*
X62246Y154500D03*
X84754D03*
G54D127*
X738017Y124213D03*
Y143313D03*
X752191Y124213D03*
Y143313D03*
G54D25*
X18500Y173300D03*
Y176700D03*
Y180300D03*
X21900Y197300D03*
X18500Y183700D03*
X21900Y200700D03*
X51000Y123800D03*
Y127200D03*
X60000Y123800D03*
Y127200D03*
X63800Y205300D03*
Y208700D03*
X54000Y220900D03*
Y224300D03*
Y214300D03*
Y217700D03*
X67000Y82800D03*
Y86200D03*
X77100Y269000D03*
Y272400D03*
X92600Y197200D03*
X89600D03*
X92600Y200600D03*
X83400Y203400D03*
Y206800D03*
X89600Y200600D03*
X86400Y254900D03*
Y258300D03*
X83200Y262800D03*
Y266200D03*
X93900Y261700D03*
Y265100D03*
X95900Y200500D03*
Y203900D03*
X97000Y261700D03*
Y265100D03*
X113500Y50800D03*
Y54200D03*
X125000Y60300D03*
Y63700D03*
X124500Y128300D03*
Y131700D03*
X123700Y140900D03*
Y144300D03*
X115450Y137800D03*
Y141200D03*
X125000Y215300D03*
Y218700D03*
X113100Y234500D03*
Y237900D03*
X135000Y49800D03*
Y53200D03*
X131500Y49800D03*
Y53200D03*
X129500Y70800D03*
Y74200D03*
X142000Y152300D03*
X148000D03*
X151000D03*
X145000D03*
X153000Y163800D03*
Y167200D03*
X142000Y155700D03*
X148000D03*
X151000D03*
X145000D03*
X167000Y167300D03*
Y170700D03*
X190000Y80800D03*
Y84200D03*
X200000Y180800D03*
Y184200D03*
X212000Y48800D03*
Y52200D03*
X210800Y192300D03*
Y195700D03*
X215500Y212300D03*
Y215700D03*
X222500Y173800D03*
Y177200D03*
X219500Y173800D03*
Y177200D03*
X226000Y212300D03*
Y215700D03*
X239000Y98800D03*
Y102200D03*
X259000Y49300D03*
Y52700D03*
X261000Y165800D03*
Y169200D03*
X263000Y225300D03*
Y228700D03*
X275300Y170200D03*
Y173600D03*
X266000Y225300D03*
Y228700D03*
X271000Y225500D03*
Y228900D03*
X290500Y78300D03*
Y81700D03*
X291800Y97200D03*
Y100600D03*
X284500Y167300D03*
Y170700D03*
X290000Y192300D03*
Y195700D03*
X308000Y257800D03*
Y261200D03*
X319000Y257800D03*
X314500D03*
X319000Y261200D03*
X314500D03*
X368000Y50300D03*
Y53700D03*
X365000Y50300D03*
Y53700D03*
X362000Y50300D03*
Y53700D03*
X359000Y50300D03*
Y53700D03*
X382500Y53800D03*
Y57200D03*
X397900Y269400D03*
Y272800D03*
X444600Y251400D03*
Y254800D03*
X443000Y278300D03*
Y281700D03*
X452000Y278300D03*
Y281700D03*
X526500Y74800D03*
Y78200D03*
X522500Y201800D03*
Y205200D03*
X518500Y201800D03*
Y205200D03*
X530000Y72300D03*
X536500D03*
X533500D03*
X530000Y75700D03*
X536500D03*
X533500D03*
X566500Y74300D03*
Y77700D03*
X577000Y79800D03*
Y83200D03*
X612500Y204800D03*
Y208200D03*
Y216300D03*
Y219700D03*
X622500Y78300D03*
Y81700D03*
X634000Y129300D03*
Y132700D03*
X645000Y165300D03*
Y168700D03*
X643500Y178800D03*
Y182200D03*
X639800Y189500D03*
Y192900D03*
X694900Y181400D03*
X691900D03*
X694900Y184800D03*
X691900D03*
X688500Y223300D03*
Y226700D03*
X685500Y223300D03*
Y226700D03*
X697500Y223300D03*
Y226700D03*
X721300Y130200D03*
Y133600D03*
X718000Y130200D03*
Y133600D03*
X721700Y123200D03*
Y126600D03*
X715000Y140300D03*
Y143700D03*
X728000Y88400D03*
X731000D03*
X736500Y104600D03*
X728000Y91800D03*
X731000D03*
X736500Y108000D03*
X734000Y155300D03*
Y158700D03*
X731000Y155300D03*
Y158700D03*
X741500Y179300D03*
Y182700D03*
X738500Y179300D03*
Y182700D03*
X737000Y197800D03*
X728000Y210300D03*
Y213700D03*
X737000Y201200D03*
X751500Y155300D03*
Y158700D03*
X766500Y122800D03*
Y126200D03*
X779500Y34807D03*
Y38207D03*
X782500Y34807D03*
Y38207D03*
X805500Y131300D03*
Y134700D03*
G54D109*
X540960Y222285D03*
G54D26*
X32000Y222500D03*
Y219000D03*
Y229500D03*
Y226000D03*
Y236500D03*
Y233000D03*
Y243500D03*
Y240000D03*
Y250500D03*
Y247000D03*
Y257500D03*
Y254000D03*
X36000Y158000D03*
X43300Y212700D03*
Y207800D03*
X40500Y198800D03*
Y203700D03*
X43500D03*
Y198800D03*
X46300Y212700D03*
Y207800D03*
X61700Y198300D03*
Y201800D03*
X77000Y85000D03*
X70900Y207200D03*
X77500Y249800D03*
X89300Y207100D03*
X86500Y261500D03*
X180000Y75500D03*
X222800Y89900D03*
X437000Y278000D03*
X535500Y234100D03*
X608500Y96000D03*
Y93000D03*
X702000Y192500D03*
X718700Y119700D03*
Y116400D03*
X736200Y111100D03*
X742800Y108100D03*
X745000Y155500D03*
X776500Y16000D03*
G54D71*
X164500Y228500D03*
G54D62*
X140639Y252500D03*
X138080D03*
X135520D03*
X132961D03*
Y264500D03*
X135520D03*
X138080D03*
X140639D03*
G54D119*
X626889Y208000D03*
Y213000D03*
Y218000D03*
Y223000D03*
X649111Y213000D03*
Y208000D03*
Y223000D03*
Y218000D03*
G54D35*
X48000Y217500D03*
X49500Y116000D03*
X79400Y139200D03*
X74200Y194000D03*
X71100Y252600D03*
X102500Y197000D03*
Y194000D03*
X179100Y127700D03*
X180100Y176000D03*
X189500Y193500D03*
X262000Y49500D03*
X282500Y219000D03*
X423000Y260500D03*
X471200Y245500D03*
X503500Y155000D03*
X511500Y176000D03*
Y179000D03*
X520500Y215500D03*
X565000Y227000D03*
X601000Y46000D03*
X617500Y208000D03*
X667500Y161000D03*
Y171500D03*
G54D44*
X73057Y113500D03*
X93943D03*
G54D80*
X235630Y174016D03*
X498425Y22798D03*
D03*
X755512Y262598D03*
D03*
G54D53*
X104000Y214100D03*
X109200D03*
X104000Y224200D03*
X109200D03*
X104000Y219100D03*
X109200D03*
X104000Y235400D03*
X109200D03*
X144400Y196000D03*
X149600D03*
X427100Y75500D03*
X432300D03*
X427396Y232063D03*
X432596D03*
X436896D03*
X442096D03*
X520400Y231000D03*
X525600D03*
X520400Y236000D03*
X525600D03*
X551900D03*
X557100D03*
X658400Y111500D03*
X663600D03*
X658400Y139500D03*
X663600D03*
X675400Y156500D03*
X680600D03*
X725900Y59000D03*
Y54000D03*
X718900Y90000D03*
X724100D03*
X731100Y59000D03*
Y54000D03*
X775900Y12000D03*
X781100D03*
X775900Y7000D03*
X781100D03*
X774100Y133000D03*
X779300D03*
X773900Y154500D03*
X779100D03*
X800400Y260600D03*
Y265600D03*
Y270600D03*
X805600Y260600D03*
Y265600D03*
Y270600D03*
G54D128*
X735554Y126676D03*
Y140850D03*
X754654Y126676D03*
Y140850D03*
G54D137*
X804032Y27032D03*
X794032D03*
X804032Y37032D03*
Y47032D03*
X794032Y37032D03*
Y47032D03*
X804032Y57032D03*
X794032D03*
X804032Y67032D03*
X794032D03*
G54D17*
X31300Y87500D03*
X27900D03*
X22000Y169300D03*
X18600D03*
X24400Y210100D03*
X21000D03*
X28400Y206900D03*
X25000D03*
X38900Y184000D03*
X35500D03*
X52600Y244400D03*
X49200D03*
X52600Y241400D03*
X49200D03*
X64100Y232800D03*
X60700D03*
X52600Y250400D03*
X49200D03*
X64200Y269500D03*
X60800D03*
X61200Y272500D03*
X57800D03*
X76400Y139200D03*
X73000D03*
X95200Y192500D03*
X91800D03*
X83700Y194000D03*
X80300D03*
X83700Y186500D03*
X80300D03*
X108300Y188500D03*
X99000Y207100D03*
X95600D03*
X123800Y134800D03*
Y147500D03*
X111700Y188500D03*
X127200Y134800D03*
Y147500D03*
X136200Y269000D03*
X132800D03*
X156300Y152200D03*
X159700D03*
X164300Y155200D03*
X160900D03*
X183200Y72500D03*
X179800D03*
X197200D03*
X193800D03*
X200800Y92500D03*
X204200D03*
X211200D03*
X207800D03*
X212200Y216000D03*
X208800D03*
X233800Y70000D03*
Y67000D03*
X237200Y70000D03*
Y67000D03*
X262300Y53000D03*
X254700Y130000D03*
X251300D03*
X264600Y166300D03*
X278800Y59000D03*
X265700Y53000D03*
X278800Y62000D03*
X275700Y124000D03*
X272300D03*
X278200Y145500D03*
X274800D03*
X268000Y166300D03*
X273700Y178400D03*
X270300D03*
X271700Y170000D03*
X268300D03*
X275700Y219000D03*
X272300D03*
X270900Y232100D03*
X267500D03*
X282200Y59000D03*
Y62000D03*
X293200Y118000D03*
X289800D03*
X293200Y121000D03*
X289800D03*
X293200Y135500D03*
X289800D03*
X293200Y132500D03*
X289800D03*
X291700Y147500D03*
X288300D03*
X291700Y144000D03*
X288300D03*
X293700Y167000D03*
X290300D03*
X293700Y173500D03*
X290300D03*
X293700Y170500D03*
X290300D03*
X293300Y188800D03*
X289900D03*
X284700Y225000D03*
X281300D03*
X284700Y222000D03*
X281300D03*
X308700Y54000D03*
X305300D03*
X397800Y263100D03*
X394400D03*
X418600Y81500D03*
X415200D03*
X431900Y79500D03*
X428500D03*
X425200Y81500D03*
X421800D03*
X433200Y228000D03*
X429800D03*
X433700Y278000D03*
X430300D03*
X441200Y228000D03*
X437800D03*
X462200Y143563D03*
X458800D03*
X462200Y147063D03*
X458800D03*
X506200Y132000D03*
X502800D03*
X506200Y135000D03*
X502800D03*
X538700Y237100D03*
X535300D03*
X546600Y204600D03*
X543200D03*
X611700Y49007D03*
X608300D03*
X611700Y52007D03*
X608300D03*
X617300Y128500D03*
X615800Y178500D03*
X630200Y133000D03*
X626800D03*
X620700Y128500D03*
X619200Y178500D03*
X625800D03*
X622400D03*
X640200Y163000D03*
X636800D03*
X646500Y189400D03*
X643100D03*
X647200Y237500D03*
X643800D03*
X664200Y189500D03*
X660800D03*
X680800Y183000D03*
X669900Y184000D03*
X666500D03*
X684200Y183000D03*
X711300Y150000D03*
X724700Y147000D03*
X721300D03*
X714700Y150000D03*
X739900Y101500D03*
X736500D03*
X742200Y111100D03*
X745600D03*
X748200Y158500D03*
X744800D03*
X761700Y122000D03*
X758300D03*
X781700Y19000D03*
X778300D03*
X781700Y28000D03*
X778300D03*
X779700Y128600D03*
X776300D03*
G54D45*
X84500Y230000D03*
G54D72*
X170561Y236000D03*
G54D138*
X794500Y77800D03*
Y93200D03*
G54D54*
X104700Y259800D03*
Y263800D03*
X109900Y261800D03*
G54D27*
X45669Y77185D03*
Y172460D03*
G54D18*
X27900Y84500D03*
X31300D03*
X25000Y203800D03*
X28400D03*
X35500Y187000D03*
X38900D03*
X60700Y211800D03*
X64100D03*
X60700Y226800D03*
X64100D03*
X60700Y220800D03*
X64100D03*
X60700Y223800D03*
X64100D03*
X60700Y235800D03*
X64100D03*
X60700Y229800D03*
X64100D03*
X60700Y238800D03*
X64100D03*
X49200Y247400D03*
X52600D03*
X76800Y82000D03*
X76900Y207200D03*
X71067Y249509D03*
X74467D03*
X80200Y82000D03*
X80300Y207200D03*
X101300Y188500D03*
X104700D03*
X102300Y200000D03*
X105700D03*
X108800Y228400D03*
X103600Y239500D03*
X107000D03*
X123800Y137800D03*
X113400Y214600D03*
X116800D03*
X112200Y228400D03*
X113500Y217800D03*
X116900D03*
X127200Y137800D03*
X148800Y205000D03*
X152200D03*
X167600Y193600D03*
X171000D03*
X167600Y196600D03*
X171000D03*
X170300Y241000D03*
X172800Y72500D03*
X176200D03*
X186800D03*
X174300Y84500D03*
X177700D03*
X174300Y81500D03*
X177700D03*
X174800Y109600D03*
X178200D03*
X180300Y131000D03*
X183700D03*
X173700Y241000D03*
X190200Y72500D03*
X216300Y92500D03*
X215800Y157000D03*
X217300Y180500D03*
Y183500D03*
X232300Y102000D03*
Y99000D03*
X219700Y92500D03*
X218800Y136000D03*
X222200D03*
X218800Y148000D03*
X222200D03*
X218800Y142000D03*
X222200D03*
X218800Y145000D03*
X222200D03*
X218800Y139000D03*
X222200D03*
X219200Y157000D03*
X229800Y164500D03*
X233200D03*
X220700Y180500D03*
Y183500D03*
X236000Y54400D03*
X239400D03*
X245300Y88500D03*
X248700D03*
X235700Y102000D03*
Y99000D03*
X245300Y91500D03*
X248700D03*
X251300Y127000D03*
X254700D03*
X253300Y186500D03*
X256700D03*
X279300Y121000D03*
X272300D03*
X275700D03*
X271200Y166300D03*
X274600D03*
X276900Y178400D03*
X266300Y198000D03*
X269700D03*
X266300Y201000D03*
X269700D03*
X281300Y72000D03*
X284700D03*
X288300Y104000D03*
X291700D03*
X288300Y107000D03*
X291700D03*
X282700Y121000D03*
X289800Y126500D03*
X293200D03*
X289800Y129500D03*
X293200D03*
X293400Y151500D03*
X286800Y164000D03*
X290200D03*
X280300Y178400D03*
X289800Y185500D03*
X293200D03*
X305300Y50500D03*
X308700D03*
X305300Y47500D03*
X308700D03*
X296800Y151500D03*
X322800Y251000D03*
X326200D03*
X394400Y266100D03*
X397800D03*
X419800Y78500D03*
X423200D03*
X437300Y79500D03*
X440700D03*
X502800Y142000D03*
X506200D03*
X502800Y145000D03*
X506200D03*
X502800Y148000D03*
X506200D03*
X502800Y139000D03*
X506200D03*
X539800Y72500D03*
Y75500D03*
X543200Y72500D03*
Y75500D03*
X556800Y190000D03*
Y186800D03*
X551800Y199200D03*
X555200D03*
X551800Y202200D03*
X555200D03*
X551800Y205200D03*
X555200D03*
X554500Y223700D03*
Y220700D03*
Y226700D03*
X560200Y190000D03*
Y186800D03*
X557900Y223700D03*
Y220700D03*
Y226700D03*
X600800Y49000D03*
X604200D03*
X608300Y46000D03*
X611700D03*
X629300Y192000D03*
X632700D03*
X647300Y173000D03*
X643100Y192500D03*
X646500D03*
X650700Y173000D03*
X660800Y192500D03*
X664200D03*
X653300Y189000D03*
X656700D03*
X661500Y205000D03*
X664900D03*
X661500Y208000D03*
X664900D03*
X667300Y158000D03*
X670700D03*
X666500Y180500D03*
X669900D03*
X711300Y147000D03*
Y153000D03*
X717800Y137000D03*
X721200D03*
X721300Y150000D03*
X724700D03*
X714700Y147000D03*
Y153000D03*
X721300D03*
X724700D03*
X726800Y169000D03*
Y172000D03*
X730200Y169000D03*
Y172000D03*
X763300Y145900D03*
X766700D03*
X763300Y142900D03*
X766700D03*
X778300Y22000D03*
X781700D03*
X778300Y25000D03*
X781700D03*
G54D81*
X224984Y196795D03*
X223016D03*
Y207205D03*
X224984D03*
G54D129*
X741167Y124313D03*
X739592D03*
Y143213D03*
X741167D03*
X750616Y124313D03*
X749041D03*
X747466D03*
X745891D03*
X744317D03*
X742742D03*
Y143213D03*
X744317D03*
X745891D03*
X747466D03*
X749041D03*
X750616D03*
G54D36*
X42717Y270472D03*
X235630Y75590D03*
X492520Y262598D03*
D03*
X761417Y22798D03*
D03*
G54D90*
X317132Y102711D03*
X313932Y105911D03*
Y102711D03*
X317132Y105911D03*
X320332Y102711D03*
Y105911D03*
X323532Y102711D03*
X313932Y109111D03*
X317132D03*
X320332D03*
X313932Y112311D03*
Y115511D03*
Y196351D03*
Y193151D03*
Y202751D03*
X317132Y205951D03*
X313932D03*
X323532D03*
X320332D03*
X317132Y199551D03*
X313932D03*
X317132Y202751D03*
X320332Y199551D03*
Y202751D03*
X326732Y102711D03*
Y205951D03*
X431192Y102711D03*
X427992D03*
Y205951D03*
X431192D03*
X437592Y105911D03*
X434392Y102711D03*
Y105911D03*
X440792Y109111D03*
X437592D03*
X434392D03*
X440792Y112311D03*
Y115511D03*
Y196351D03*
Y193151D03*
Y202751D03*
Y205951D03*
X437592D03*
X434392D03*
X437592Y199551D03*
X434392Y202751D03*
Y199551D03*
X440792D03*
X437592Y202751D03*
G54D63*
X144000Y67875D03*
Y147125D03*
G54D19*
X26100Y97900D03*
Y103100D03*
X39300Y111500D03*
Y116700D03*
X68800Y133400D03*
Y138600D03*
X71800Y170400D03*
Y175600D03*
X92000Y167900D03*
Y173100D03*
X94420Y252800D03*
Y258000D03*
X109000Y124900D03*
Y130100D03*
X103500Y124900D03*
Y130100D03*
X101000Y243500D03*
Y248700D03*
X99420Y252800D03*
Y258000D03*
X114500Y124900D03*
Y130100D03*
X121000Y214900D03*
Y220100D03*
X135500Y150100D03*
Y155300D03*
X160500Y195900D03*
Y201100D03*
X187200Y137500D03*
Y142700D03*
X214000Y171000D03*
Y176200D03*
X209800Y199400D03*
Y204600D03*
X513500Y188400D03*
Y193600D03*
X512500Y219400D03*
Y224600D03*
X517500Y219400D03*
Y224600D03*
X674200Y47407D03*
Y52607D03*
X720500Y55900D03*
X715500D03*
X720500Y61100D03*
X715500D03*
X742500Y60900D03*
Y66100D03*
X732300Y102100D03*
Y107300D03*
X747500Y60900D03*
Y66100D03*
X764500Y149900D03*
Y155100D03*
G54D55*
X109600Y268500D03*
X104400D03*
X126100Y121000D03*
X120900D03*
X171100Y61000D03*
X165900D03*
X171900Y213500D03*
X170000Y203300D03*
X180600Y61000D03*
X175400D03*
X177100Y213500D03*
X175200Y203300D03*
X183600Y215150D03*
X195600Y177000D03*
X190400D03*
X193600Y197500D03*
X188400D03*
X195851Y210150D03*
X190651D03*
X188800Y215150D03*
X198300D03*
X193100D03*
X249400Y207000D03*
X254600D03*
X441600Y75500D03*
X436400D03*
X474300Y254500D03*
X469100D03*
X474300Y249500D03*
X469100D03*
X557080Y230982D03*
X551880D03*
X663600Y91000D03*
X658400D03*
X662600Y119100D03*
X657400D03*
X665400Y153500D03*
X670600D03*
X724100Y85000D03*
X718900D03*
G54D73*
X183840Y117340D03*
X176360D03*
X183840Y119900D03*
X176360D03*
X183840Y122460D03*
X176360D03*
X269260Y53060D03*
X276740D03*
X269260Y50500D03*
Y47940D03*
X276740D03*
Y50500D03*
X721260Y187440D03*
Y190000D03*
Y192560D03*
X728740D03*
Y190000D03*
Y187440D03*
G54D139*
X790015Y154371D03*
X795015D03*
X800015D03*
G54D28*
X45857Y91657D03*
Y93626D03*
Y95594D03*
Y97563D03*
Y99531D03*
Y101500D03*
Y103469D03*
Y105437D03*
Y107406D03*
Y109374D03*
Y111343D03*
X34357Y133657D03*
Y135626D03*
Y137594D03*
Y139563D03*
Y141531D03*
Y143500D03*
Y145469D03*
Y147437D03*
Y149406D03*
Y151374D03*
Y153343D03*
X64143Y105437D03*
Y103469D03*
Y101500D03*
Y99531D03*
Y97563D03*
Y95594D03*
Y93626D03*
Y91657D03*
Y111343D03*
Y109374D03*
Y107406D03*
X52643Y135626D03*
Y133657D03*
Y151374D03*
Y149406D03*
Y147437D03*
Y145469D03*
Y143500D03*
Y141531D03*
Y139563D03*
Y137594D03*
Y153343D03*
X218795Y197079D03*
Y199047D03*
Y201016D03*
Y202984D03*
Y204953D03*
Y206921D03*
X229205Y197079D03*
Y206921D03*
Y204953D03*
Y202984D03*
Y201016D03*
Y199047D03*
G54D64*
X155740Y180020D03*
Y187380D03*
X163060Y165320D03*
X157940D03*
X163060Y172680D03*
X157940D03*
X160500D03*
X160860Y180020D03*
Y187380D03*
X158300D03*
X447940Y262820D03*
Y270180D03*
X453060D03*
Y262820D03*
X450500D03*
G54D91*
X313392Y118471D03*
Y136191D03*
Y130531D03*
Y124131D03*
Y148261D03*
Y141861D03*
Y165991D03*
Y153921D03*
Y159591D03*
Y177311D03*
Y171651D03*
Y189381D03*
Y183711D03*
X441332Y119281D03*
Y131351D03*
Y124951D03*
Y149071D03*
Y137011D03*
Y142671D03*
Y166801D03*
Y160401D03*
Y154741D03*
Y172471D03*
Y178131D03*
Y190191D03*
Y184531D03*
G54D82*
X236100Y114300D03*
X244100Y110560D03*
Y118040D03*
G54D37*
X60433Y24392D03*
X64370D03*
X68307D03*
X72244D03*
X76181D03*
X80118D03*
X84055D03*
X87992D03*
X91929D03*
X95866D03*
X99803D03*
X103740D03*
X107677D03*
X111614D03*
X115551D03*
X119488D03*
X123425D03*
X127362D03*
X131299D03*
X135236D03*
X139173D03*
X143110D03*
X147047D03*
X150984D03*
X154921D03*
X158858D03*
X162795D03*
X166732D03*
X170669D03*
X174606D03*
X178543D03*
X182480D03*
X186417D03*
X190354D03*
X194291D03*
X198228D03*
X202165D03*
X206102D03*
X210039D03*
X213976D03*
X217913D03*
X221850D03*
X225787D03*
X229724D03*
X233661D03*
X237598D03*
X241535D03*
X245472D03*
X249409D03*
X253346D03*
X257283D03*
X261220D03*
X265157D03*
X269094D03*
X273031D03*
X276968D03*
X280905D03*
X284842D03*
X288779D03*
X292716D03*
X296653D03*
X300590D03*
X304527D03*
X308464D03*
X312401D03*
X316338D03*
X320275D03*
X324212D03*
X328149D03*
X332086D03*
X336023D03*
X347835D03*
X351772D03*
X355709D03*
X359646D03*
X363583D03*
X367520D03*
X371457D03*
X375394D03*
X379331D03*
X383268D03*
G54D46*
X78988Y218689D03*
X77413D03*
X75839D03*
Y241311D03*
X77413D03*
X78988D03*
X93161Y218689D03*
X91587D03*
X90012D03*
X88437D03*
X86862D03*
X85287D03*
X83713D03*
X82138D03*
X80563D03*
Y241311D03*
X82138D03*
X83713D03*
X85287D03*
X86862D03*
X88437D03*
X90012D03*
X91587D03*
X93161D03*
G54D38*
X59750Y84300D03*
G54D83*
X237000Y128600D03*
X241000D03*
X239000Y123400D03*
X518500Y193600D03*
X522500D03*
X520500Y188400D03*
G54D56*
X125000Y49250D03*
X122440D03*
X125000Y55750D03*
X122440D03*
X127560Y49250D03*
Y55750D03*
X209060Y175750D03*
X206500D03*
X203940D03*
X209060Y182250D03*
X206500D03*
X203940D03*
X231260Y50950D03*
X228700D03*
X226140D03*
X231260Y57450D03*
X228700D03*
X226140D03*
X219940Y168750D03*
X222500D03*
X225060D03*
X219940Y162250D03*
X222500D03*
X225060D03*
X437940Y269750D03*
X440500D03*
X443060D03*
X437940Y263250D03*
X440500D03*
X443060D03*
G54D74*
X187250Y164000D03*
Y159000D03*
Y154000D03*
Y169000D03*
X203850Y74900D03*
Y69900D03*
Y84900D03*
Y79900D03*
X194197Y105871D03*
Y120871D03*
Y115871D03*
Y110871D03*
X206750Y154000D03*
Y159000D03*
Y164000D03*
Y169000D03*
X223350Y69900D03*
Y74900D03*
Y79900D03*
Y84900D03*
X221299Y105871D03*
Y110871D03*
Y115871D03*
Y120871D03*
G54D29*
X46750Y126000D03*
X211250Y210500D03*
G54D65*
X155720Y228500D03*
G54D92*
X318702Y111401D03*
X317132Y113711D03*
X319282Y115791D03*
X320112Y118471D03*
X317112Y118671D03*
X319112Y121101D03*
X324582Y108891D03*
X322572Y110771D03*
X322192Y113691D03*
X324822Y121201D03*
X321992Y116451D03*
Y120481D03*
X324582Y105891D03*
X318702Y129131D03*
X315782Y129151D03*
X317332Y131541D03*
X317112Y136391D03*
X320112Y136191D03*
X319282Y133521D03*
X315132Y133201D03*
X321442Y128751D03*
X322192Y131421D03*
X321992Y134181D03*
X315342Y121311D03*
X315792Y125511D03*
X318702Y125631D03*
X317352Y123221D03*
X324822Y123961D03*
X321442Y125991D03*
X321922Y123261D03*
X317332Y149271D03*
X318702Y146861D03*
X315782Y146881D03*
X319282Y151251D03*
X315132Y150931D03*
X321442Y146481D03*
X322192Y149151D03*
X321992Y151911D03*
X319112Y138831D03*
X315342Y139031D03*
X317352Y140951D03*
X318702Y143361D03*
X315792Y143231D03*
X321992Y138211D03*
X324822Y139601D03*
Y136841D03*
X321442Y143721D03*
X321922Y140991D03*
X317332Y166991D03*
X322192Y166871D03*
X317112Y154121D03*
X318702Y161091D03*
X317352Y158681D03*
X319112Y156551D03*
X315792Y160961D03*
X315342Y156761D03*
X318702Y164591D03*
X315782Y164611D03*
X320112Y153921D03*
X321442Y161451D03*
X321992Y155931D03*
X321922Y158721D03*
X324822Y152481D03*
Y155241D03*
X321442Y164201D03*
X319282Y168971D03*
X315132Y168661D03*
X317352Y176411D03*
X319112Y174281D03*
X315342Y174491D03*
X317112Y171851D03*
X318702Y178811D03*
X315792Y178691D03*
X318702Y182311D03*
X315782Y182341D03*
X320112Y171651D03*
X324822Y168121D03*
X321992Y169641D03*
X324822Y170881D03*
X321922Y176451D03*
X321992Y173661D03*
X321442Y179181D03*
Y181931D03*
X317332Y184721D03*
X315132Y186391D03*
X319282Y186701D03*
X317112Y189581D03*
X319282Y192051D03*
X317132Y194131D03*
X318702Y196441D03*
X320112Y189381D03*
X324822Y186521D03*
X322192Y184601D03*
X321992Y187371D03*
Y191391D03*
X325782Y197891D03*
X321442Y196901D03*
X321922Y194171D03*
X324822Y194341D03*
Y183761D03*
X323772Y199771D03*
Y202771D03*
X331622Y104561D03*
X335272Y104571D03*
X339472Y104121D03*
X334782Y110221D03*
X332032D03*
X332292Y113601D03*
Y116601D03*
X337522Y110711D03*
X340302Y110771D03*
X340112Y115101D03*
X337352D03*
X340112Y118101D03*
X337352D03*
Y121101D03*
X340112D03*
X330822Y121201D03*
X335152Y107481D03*
X331652D03*
X339682Y107891D03*
X337552Y106131D03*
X327262Y108061D03*
X329362Y110971D03*
X326592Y110771D03*
X327822Y113601D03*
X329322Y116141D03*
X326322D03*
X327822Y121201D03*
X329242Y106111D03*
X336822Y123961D03*
X332322Y129021D03*
X335322D03*
X332322Y131781D03*
X335322D03*
X338322Y129021D03*
Y131781D03*
X333822Y123961D03*
X340112Y124101D03*
X330822Y123961D03*
X329322Y129021D03*
X326322D03*
X329322Y131781D03*
X326322D03*
X327822Y123961D03*
X332322Y147421D03*
X335322D03*
X338322D03*
X329322D03*
X333822Y139601D03*
Y136841D03*
X332322Y144661D03*
X335322D03*
X336822Y139601D03*
X339822D03*
X336822Y136841D03*
X339822D03*
X338322Y144661D03*
X330822Y139601D03*
Y136841D03*
X329322Y144661D03*
X326322Y147421D03*
X327822Y139601D03*
Y136841D03*
X326322Y144661D03*
X332322Y160301D03*
X333822Y152481D03*
Y155241D03*
X335322Y160301D03*
X332322Y163061D03*
X335322D03*
X338322Y160301D03*
X339822Y152481D03*
X336822D03*
X339822Y155241D03*
X336822D03*
X338322Y163061D03*
X329322Y160301D03*
X330822Y152481D03*
Y155241D03*
X329322Y163061D03*
X326322Y160301D03*
X327822Y152481D03*
Y155241D03*
X326322Y163061D03*
X333822Y168121D03*
Y170881D03*
X332322Y175941D03*
X335322D03*
X332322Y178701D03*
X335322D03*
X336822Y168121D03*
X339822D03*
X336822Y170881D03*
X339822D03*
X338322Y175941D03*
Y178701D03*
X330822Y168121D03*
Y170881D03*
X329322Y175941D03*
Y178701D03*
X327822Y168121D03*
Y170881D03*
X326322Y175941D03*
Y178701D03*
X331352Y189061D03*
Y192061D03*
Y195061D03*
X336412Y190561D03*
Y187561D03*
X339172Y190561D03*
Y187561D03*
X336722Y197691D03*
X339492Y197891D03*
X336412Y193561D03*
X339172D03*
X333822Y183761D03*
X339822D03*
X336822D03*
X330822D03*
X328592Y192061D03*
X327822Y186521D03*
X328562Y197951D03*
X328592Y195061D03*
X327822Y183761D03*
X334462Y204101D03*
X338512Y204751D03*
X330812Y204091D03*
X331302Y198441D03*
X334052D03*
X334432Y201181D03*
X338822Y200601D03*
X336842Y202551D03*
X330932Y201181D03*
X326442Y200601D03*
X328532Y202531D03*
X353002Y104571D03*
X349352Y104561D03*
X345302Y103911D03*
X352512Y110221D03*
X355242Y110711D03*
X352992Y115101D03*
Y121101D03*
Y118101D03*
X355752Y115101D03*
Y121101D03*
Y118101D03*
X349762Y110221D03*
X352882Y107481D03*
X355282Y106131D03*
X349382Y107481D03*
X344992Y108061D03*
X342312Y108891D03*
X347092Y110971D03*
X344322Y110771D03*
X347932Y113601D03*
X345172D03*
X347932Y116601D03*
Y119601D03*
X345172Y116601D03*
Y119601D03*
X346972Y106111D03*
X342112Y105891D03*
X350582Y132671D03*
X352992Y130101D03*
Y127101D03*
X355752D03*
Y130101D03*
X354132Y132671D03*
X352992Y124101D03*
X355752D03*
X347932Y128601D03*
X345172D03*
X341322Y129021D03*
X347932Y131601D03*
X345172D03*
X341322Y131781D03*
X347932Y122601D03*
Y125601D03*
X345172Y122601D03*
Y125601D03*
X350082Y147421D03*
X350422Y150171D03*
X350082Y144661D03*
X350422Y141901D03*
X348822Y136841D03*
Y139601D03*
X347322Y147421D03*
X341322D03*
X344322D03*
X345822Y139601D03*
X342822D03*
X345822Y136841D03*
X342822D03*
X347322Y144661D03*
X341322D03*
X344322D03*
X350422Y165811D03*
X350082Y160301D03*
X350422Y157541D03*
X350082Y163061D03*
X348822Y155241D03*
Y152481D03*
X347322Y160301D03*
X345822Y152481D03*
Y155241D03*
X341322Y160301D03*
X342822Y155241D03*
Y152481D03*
X344322Y160301D03*
X347322Y163061D03*
X341322D03*
X344322D03*
X350982Y175991D03*
X350882Y173231D03*
X353742Y175991D03*
X354812Y181561D03*
X352052D03*
Y178561D03*
X354812D03*
X348822Y168121D03*
Y170881D03*
X345822Y168121D03*
X342822D03*
X346992Y177061D03*
X344232D03*
X345822Y170881D03*
X342822D03*
X341322Y175941D03*
X346992Y180061D03*
X344232D03*
X341322Y178701D03*
X352052Y190561D03*
Y187561D03*
X354812Y190561D03*
Y187561D03*
X352052Y184561D03*
X354812D03*
X354452Y197691D03*
X354812Y193561D03*
X352052D03*
X346992Y192061D03*
Y189061D03*
Y186061D03*
X344232D03*
Y189061D03*
Y192061D03*
X343512Y197891D03*
X346292Y197951D03*
X346992Y195061D03*
X344232D03*
X346992Y183061D03*
X344232D03*
X356242Y204751D03*
X352182Y204101D03*
X348542Y204091D03*
X351782Y198441D03*
X356552Y200601D03*
X352162Y201181D03*
X354572Y202551D03*
X349022Y198441D03*
X348662Y201181D03*
X344342Y204541D03*
X341502Y199771D03*
X344132Y200771D03*
X341702Y202771D03*
X346252Y202531D03*
X370732Y104571D03*
X357202Y104121D03*
X363032Y103911D03*
X367082Y104561D03*
X370242Y110221D03*
X371392Y118101D03*
Y121101D03*
Y115101D03*
X368632Y118101D03*
Y121101D03*
Y115101D03*
X370602Y107481D03*
X367482Y110221D03*
X360042Y108891D03*
X362722Y108061D03*
X363572Y113601D03*
X360812D03*
X358032Y110771D03*
X364822Y110971D03*
X362052Y110771D03*
X363572Y119601D03*
Y116601D03*
X360812Y119601D03*
Y116601D03*
X357412Y107891D03*
X364702Y106111D03*
X367102Y107481D03*
X359842Y105891D03*
X371392Y127101D03*
Y130101D03*
X368632Y127101D03*
Y130101D03*
X371392Y124101D03*
X368632D03*
X363572Y128601D03*
X360812D03*
X363572Y131601D03*
X360812D03*
X363572Y125601D03*
Y122601D03*
X360812Y125601D03*
Y122601D03*
X370452Y178561D03*
Y181561D03*
X367692Y178561D03*
Y181561D03*
X362632Y177061D03*
X359872D03*
Y180061D03*
X362632D03*
X370452Y187561D03*
Y190561D03*
Y184561D03*
Y193561D03*
X367692Y187561D03*
Y190561D03*
Y184561D03*
Y193561D03*
X359872Y186061D03*
Y189061D03*
Y192061D03*
X362632Y186061D03*
Y189061D03*
Y192061D03*
X361242Y197891D03*
X364022Y197931D03*
X359872Y195061D03*
X362632D03*
X357212Y197891D03*
X359872Y183061D03*
X362632D03*
X369912Y204101D03*
X369512Y198441D03*
X369892Y201181D03*
X362062Y204541D03*
X366262Y204091D03*
X366752Y198441D03*
X359222Y199771D03*
X359422Y202771D03*
X361862Y200771D03*
X363982Y202531D03*
X366392Y201181D03*
X374932Y104121D03*
X380762Y103911D03*
X384812Y104561D03*
X387032Y115101D03*
Y121101D03*
Y118101D03*
X377772Y108891D03*
X380442Y108061D03*
X376452Y113601D03*
X379212D03*
X372972Y110731D03*
X375762Y110771D03*
X379782D03*
X382542Y110971D03*
X376452Y116601D03*
Y119601D03*
X379212Y116601D03*
Y119601D03*
X385212Y110221D03*
X384272Y115101D03*
Y121101D03*
Y118101D03*
X373012Y106131D03*
X375142Y107891D03*
X377572Y105891D03*
X382422Y106111D03*
X384832Y107481D03*
X387032Y127101D03*
Y130101D03*
Y124101D03*
X376452Y128601D03*
X379212D03*
X376452Y131601D03*
X379212D03*
X384272Y130101D03*
Y127101D03*
X376452Y122601D03*
Y125601D03*
X379212Y122601D03*
Y125601D03*
X384272Y124101D03*
X386092Y181561D03*
Y178561D03*
X378272Y177061D03*
X375512D03*
X378272Y180061D03*
X375512D03*
X383332Y181561D03*
Y178561D03*
X386092Y190561D03*
Y187561D03*
Y184561D03*
Y193561D03*
X378272Y192061D03*
Y189061D03*
Y186061D03*
X375512Y192061D03*
Y189061D03*
Y186061D03*
X378962Y197891D03*
X378272Y195061D03*
X374942Y197891D03*
X372182Y197691D03*
X375512Y195061D03*
X381752Y197931D03*
X383332Y190561D03*
Y187561D03*
Y184561D03*
Y193561D03*
X378272Y183061D03*
X375512D03*
X387242Y198441D03*
X379792Y204541D03*
X373962Y204751D03*
X383992Y204091D03*
X376952Y199771D03*
X374282Y200601D03*
X379582Y200771D03*
X377152Y202771D03*
X372302Y202551D03*
X381712Y202531D03*
X384482Y198441D03*
X384122Y201181D03*
X388462Y104571D03*
X392662Y104121D03*
X398482Y103911D03*
X402542Y104561D03*
X395502Y108891D03*
X398172Y108061D03*
X392092Y113601D03*
X394852D03*
X393482Y110771D03*
X390702Y110711D03*
X397512Y110771D03*
X392092Y119601D03*
Y116601D03*
X394852Y119601D03*
Y116601D03*
X400272Y110971D03*
X402672Y118101D03*
Y121101D03*
X399912Y118101D03*
Y121101D03*
Y115101D03*
X402672D03*
X387972Y110221D03*
X395302Y105891D03*
X390742Y106131D03*
X388332Y107481D03*
X392862Y107891D03*
X402562Y107481D03*
X400152Y106111D03*
X392092Y128601D03*
X394852D03*
X392092Y131601D03*
X394852D03*
X399912Y127101D03*
X402672D03*
X399912Y130101D03*
X402672D03*
X400982Y132671D03*
X392092Y125601D03*
Y122601D03*
X394852Y125601D03*
Y122601D03*
X402672Y124101D03*
X399912D03*
X391152Y177061D03*
X393912D03*
X398972Y178561D03*
Y181561D03*
X393912Y180061D03*
X391152D03*
X400592Y175991D03*
X401732Y178561D03*
Y181561D03*
X398972Y187561D03*
Y190561D03*
Y184561D03*
X393912Y186061D03*
Y189061D03*
Y192061D03*
X391152Y186061D03*
Y189061D03*
Y192061D03*
X396692Y197891D03*
X398972Y193561D03*
X389902Y197691D03*
X392672Y197891D03*
X393912Y195061D03*
X391152D03*
X401732Y187561D03*
Y190561D03*
Y184561D03*
X399482Y197931D03*
X401732Y193561D03*
X393912Y183061D03*
X391152D03*
X397522Y204541D03*
X391692Y204751D03*
X401722Y204091D03*
X387642Y204101D03*
X392002Y200601D03*
X394682Y199771D03*
X397312Y200771D03*
X390022Y202551D03*
X394882Y202771D03*
X402212Y198441D03*
X401842Y201181D03*
X399442Y202531D03*
X387622Y201181D03*
X410382Y104121D03*
X416212Y103911D03*
X406182Y104571D03*
X407732Y113601D03*
X410492D03*
X408432Y110711D03*
X413222Y108891D03*
X411212Y110771D03*
X415232D03*
X407732Y116601D03*
Y119601D03*
X410492Y116601D03*
Y119601D03*
X415902Y108061D03*
X418002Y110971D03*
X418312Y115101D03*
X415552D03*
Y121101D03*
Y118101D03*
X418312Y121101D03*
Y118101D03*
X410592Y107891D03*
X408472Y106131D03*
X413022Y105891D03*
X417882Y106111D03*
X406062Y107481D03*
X402942Y110221D03*
X405702D03*
X403842Y135431D03*
X407732Y128601D03*
X410492D03*
X413402Y129961D03*
X410492Y131601D03*
X407732D03*
X413402Y132721D03*
X416402Y129961D03*
Y132721D03*
X407732Y122601D03*
Y125601D03*
X410492Y122601D03*
Y125601D03*
X414902Y124901D03*
X417902D03*
X403742Y132671D03*
X407402Y148361D03*
X413402D03*
X410402D03*
X416402D03*
X408902Y137781D03*
Y140541D03*
X407402Y145601D03*
X411902Y137781D03*
Y140541D03*
X414902Y137781D03*
Y140541D03*
X413402Y145601D03*
X410402D03*
X417902Y137781D03*
Y140541D03*
X416402Y145601D03*
X405902Y137781D03*
Y140541D03*
X404642Y148361D03*
X404302Y151121D03*
Y142851D03*
X404642Y145601D03*
X408902Y153421D03*
Y156181D03*
X407402Y161241D03*
X411902Y156181D03*
Y153421D03*
X413402Y161241D03*
X410402D03*
X407402Y164001D03*
X413402D03*
X410402D03*
X417902Y153421D03*
X414902D03*
X417902Y156181D03*
X414902D03*
X416402Y161241D03*
Y164001D03*
X405902Y153421D03*
Y156181D03*
X404302Y166761D03*
Y158491D03*
X404642Y161241D03*
Y164001D03*
X408902Y169061D03*
X409552Y177061D03*
X408902Y171821D03*
X411902Y169061D03*
Y171821D03*
X413402Y176881D03*
X409552Y180061D03*
X413402Y179641D03*
X414902Y169061D03*
X417902D03*
X414902Y171821D03*
X417902D03*
X416402Y176881D03*
Y179641D03*
X405902Y169061D03*
X406792Y177061D03*
X405902Y171821D03*
X406792Y180061D03*
X404142Y175991D03*
X409552Y192061D03*
Y189061D03*
Y186061D03*
X414612Y190561D03*
Y187561D03*
Y184561D03*
X407632Y197691D03*
X409552Y195061D03*
X414612Y193561D03*
X414422Y197891D03*
X410402D03*
X417372Y190561D03*
Y187561D03*
X417902Y184701D03*
X417202Y197931D03*
X417372Y193561D03*
X406792Y192061D03*
Y189061D03*
Y186061D03*
Y195061D03*
X409552Y183061D03*
X406792D03*
X409422Y204751D03*
X415252Y204541D03*
X405372Y204101D03*
X409732Y200601D03*
X407752Y202551D03*
X412412Y199771D03*
X412612Y202771D03*
X415042Y200771D03*
X417172Y202531D03*
X405342Y201181D03*
X404962Y198441D03*
X423912Y104571D03*
X420262Y104561D03*
X428282Y108061D03*
X430952Y108891D03*
X426132Y113601D03*
X428942Y110771D03*
X426162Y110711D03*
X426132Y116601D03*
X429902Y114321D03*
X433282Y111761D03*
X432802Y114491D03*
X432732Y117271D03*
X430952Y105891D03*
X426192Y106131D03*
X420672Y110221D03*
X423422D03*
X423372Y113601D03*
Y116601D03*
Y119601D03*
X420292Y107481D03*
X423792D03*
X428402Y129961D03*
Y132721D03*
X433282Y129481D03*
X432732Y135001D03*
X432802Y132211D03*
X426902Y124901D03*
X429902D03*
X426902Y122141D03*
X429902D03*
X432732Y121291D03*
X433282Y126731D03*
X432532Y124061D03*
X425402Y129961D03*
X419402D03*
X422402D03*
X425402Y132721D03*
X419402D03*
X422402D03*
X420902Y124901D03*
X423902D03*
X428402Y148361D03*
X433282Y147211D03*
X432802Y149941D03*
X425402Y148361D03*
X429902Y137781D03*
X426902D03*
X429902Y140541D03*
X426902D03*
X428402Y145601D03*
X432732Y139021D03*
X432532Y141791D03*
X433282Y144461D03*
X425402Y145601D03*
X422402Y148361D03*
X419402D03*
X420902Y137781D03*
Y140541D03*
X423902Y137781D03*
Y140541D03*
X422402Y145601D03*
X419402D03*
X426902Y153421D03*
X429902D03*
X426902Y156181D03*
X429902D03*
X428402Y161241D03*
Y164001D03*
X432732Y156751D03*
Y152731D03*
X432532Y159511D03*
X433282Y162181D03*
Y164941D03*
X425402Y161241D03*
Y164001D03*
X420902Y153421D03*
Y156181D03*
X423902Y153421D03*
Y156181D03*
X419402Y161241D03*
X422402D03*
X419402Y164001D03*
X422402D03*
X429902Y169061D03*
X426902D03*
X429902Y171821D03*
X426902D03*
X428402Y176881D03*
Y179641D03*
X432732Y170451D03*
X432802Y167671D03*
X432732Y174481D03*
X432532Y177241D03*
X433282Y179911D03*
Y182671D03*
X425402Y176881D03*
Y179641D03*
X420902Y169061D03*
X423902D03*
X420902Y171821D03*
X423902D03*
X422402Y176881D03*
X419402D03*
X422402Y179641D03*
X419402D03*
X426902Y184701D03*
X429902D03*
X426902Y187461D03*
X429902D03*
X428402Y192521D03*
X428132Y197891D03*
X426902Y195061D03*
X432802Y185401D03*
X432732Y188181D03*
Y192211D03*
X432152Y197891D03*
X432532Y194971D03*
X425402Y192521D03*
X425362Y197691D03*
X422432Y192061D03*
X423902Y184701D03*
Y187461D03*
X420902Y184701D03*
X422432Y195061D03*
X427462Y200601D03*
X430142Y199771D03*
Y202771D03*
X425482Y202551D03*
X419452Y204091D03*
X423102Y204101D03*
X419942Y198441D03*
X422692D03*
X419572Y201181D03*
X423072D03*
X436022Y112221D03*
X437592Y114531D03*
X435442Y116611D03*
X437612Y119081D03*
X434612Y119281D03*
X438932Y129971D03*
X436022Y129851D03*
X439382Y134171D03*
X435612Y134381D03*
X437372Y132251D03*
X435442Y121961D03*
X437392Y123941D03*
X436022Y126351D03*
X439592Y122271D03*
X438942Y126321D03*
X438932Y147701D03*
X436022Y147571D03*
X439382Y151901D03*
X437372Y149981D03*
X434612Y137011D03*
X437612Y136811D03*
X439592Y140001D03*
X435442Y139691D03*
X436022Y144071D03*
X437392Y141671D03*
X438942Y144051D03*
X438932Y165431D03*
X436022Y165301D03*
X435612Y152111D03*
X434612Y154741D03*
X437612Y154541D03*
X439592Y157731D03*
X435442Y157411D03*
X437392Y159391D03*
X436022Y161801D03*
X438942Y161781D03*
X435612Y169831D03*
X439382Y169631D03*
X437372Y167711D03*
X434612Y172471D03*
X437612Y172271D03*
X439592Y175461D03*
X435442Y175141D03*
X437392Y177121D03*
X438942Y179511D03*
X436022Y179531D03*
X437372Y185441D03*
X435612Y187561D03*
X439382Y187351D03*
X437612Y189991D03*
X434612Y190191D03*
X435442Y192871D03*
X437592Y194951D03*
X436022Y197261D03*
Y183031D03*
X438932Y183151D03*
G54D47*
X73189Y221339D03*
Y222913D03*
Y224488D03*
Y226063D03*
Y227638D03*
Y229213D03*
Y230787D03*
Y232362D03*
Y233937D03*
Y235512D03*
Y237087D03*
Y238661D03*
X95811Y227638D03*
Y226063D03*
Y224488D03*
Y222913D03*
Y221339D03*
Y238661D03*
Y237087D03*
Y235512D03*
Y233937D03*
Y232362D03*
Y230787D03*
Y229213D03*
G54D66*
X150989Y221000D03*
Y226000D03*
Y231000D03*
Y236000D03*
G54D48*
X93200Y142200D03*
Y152800D03*
X101700Y142200D03*
Y152800D03*
X102500Y165700D03*
Y176300D03*
X107900Y243700D03*
Y254300D03*
G54D84*
X248430Y164600D03*
X246465D03*
Y180400D03*
X248430D03*
X254335Y164600D03*
X252370D03*
X250400D03*
Y180400D03*
X252370D03*
X254335D03*
G54D93*
X336652Y102171D03*
X330252D03*
X335832Y206491D03*
X329432D03*
X354382Y102171D03*
X342312D03*
X347982D03*
X353562Y206491D03*
X347162D03*
X341502D03*
X360042Y102171D03*
X365702D03*
X371292Y206491D03*
X364892D03*
X359222D03*
X372102Y102171D03*
X377772D03*
X383432D03*
X376952Y206491D03*
X382622D03*
X389832Y102171D03*
X395502D03*
X401162D03*
X394682Y206491D03*
X389022D03*
X400342D03*
X407562Y102171D03*
X413222D03*
X412412Y206491D03*
X418072D03*
X406742D03*
X418892Y102171D03*
X425292D03*
X424472Y206491D03*
G54D39*
X62250Y84300D03*
G54D75*
X184671Y234000D03*
X215329D03*
G54D57*
X117500Y228100D03*
X127300D03*
X117500Y239900D03*
X127300D03*
X784400Y103000D03*
X794200D03*
X804400Y212800D03*
X794600D03*
G54D58*
X121000Y254266D03*
Y267734D03*
G54D94*
X350197Y231103D03*
G54D76*
X194603Y105871D03*
Y120871D03*
Y115871D03*
Y110871D03*
X220893Y105871D03*
Y120871D03*
Y115871D03*
Y110871D03*
G54D85*
X259750Y177440D03*
Y180000D03*
Y182560D03*
X279750Y81060D03*
Y78500D03*
Y75940D03*
X266250Y177440D03*
Y180000D03*
Y182560D03*
X286250Y81060D03*
Y78500D03*
Y75940D03*
X526750Y57940D03*
Y60500D03*
Y63060D03*
X533250Y57940D03*
Y60500D03*
Y63060D03*
X628650Y182440D03*
X635150D03*
X628650Y185000D03*
Y187560D03*
X635150Y185000D03*
Y187560D03*
X651750Y179940D03*
Y182500D03*
X658250Y179940D03*
Y182500D03*
X651750Y185060D03*
X658250D03*
G54D49*
X87729Y270300D03*
X96391D03*
G54D67*
X148445Y257000D03*
X172555D03*
G54D86*
X281000Y152654D03*
Y162346D03*
G54D77*
X200197Y282677D03*
X298622D03*
G54D59*
X143220Y78955D03*
Y80925D03*
Y82895D03*
Y84860D03*
Y86830D03*
Y88800D03*
Y90770D03*
Y92735D03*
Y94705D03*
Y96675D03*
Y98640D03*
Y100610D03*
Y102580D03*
Y104545D03*
Y106515D03*
Y108485D03*
Y110455D03*
Y112420D03*
Y114390D03*
Y116360D03*
Y118325D03*
Y120295D03*
Y122265D03*
Y124230D03*
Y126200D03*
Y128170D03*
Y130140D03*
Y132105D03*
Y134075D03*
Y136045D03*
X165755Y78955D03*
Y80925D03*
Y82895D03*
Y84860D03*
Y86830D03*
Y88800D03*
Y90770D03*
Y92735D03*
Y94705D03*
Y96675D03*
Y98640D03*
Y100610D03*
Y102580D03*
Y104545D03*
Y106515D03*
Y108485D03*
Y110455D03*
Y112420D03*
Y114390D03*
Y116360D03*
Y118325D03*
Y120295D03*
Y122265D03*
Y124230D03*
Y126200D03*
Y128170D03*
Y130140D03*
Y132105D03*
Y134075D03*
Y136045D03*
G54D68*
X171320Y160560D03*
Y155440D03*
Y158000D03*
Y164940D03*
Y167500D03*
Y170060D03*
X173120Y151060D03*
X180480D03*
Y145940D03*
X173120D03*
Y148500D03*
X178680Y160560D03*
Y155440D03*
Y164940D03*
Y170060D03*
X427820Y251940D03*
Y257060D03*
X435180Y251940D03*
Y257060D03*
Y254500D03*
X721380Y197525D03*
Y202645D03*
X733320Y192560D03*
X740680D03*
Y187440D03*
X733320D03*
Y190000D03*
X728740Y197525D03*
Y202645D03*
Y200085D03*
G54D95*
X353742Y135431D03*
Y148031D03*
Y151181D03*
Y138581D03*
Y141731D03*
Y144881D03*
Y166931D03*
Y160631D03*
Y157481D03*
Y154331D03*
Y163781D03*
Y170081D03*
Y173231D03*
X369482Y135431D03*
X369882Y132671D03*
X356882Y135431D03*
X360042D03*
X366342D03*
X363182D03*
X356882Y132671D03*
X366342D03*
X369482Y148031D03*
Y151181D03*
Y138581D03*
Y144881D03*
Y141731D03*
X356882Y148031D03*
Y151181D03*
X360042Y148031D03*
X366342D03*
X363182D03*
X360042Y151181D03*
X366342D03*
X363182D03*
X356882Y138581D03*
X360042D03*
X366342D03*
X363182D03*
X356882Y144881D03*
Y141731D03*
X360042Y144881D03*
Y141731D03*
X366342Y144881D03*
Y141731D03*
X363182Y144881D03*
Y141731D03*
X369482Y166931D03*
Y154331D03*
Y157481D03*
Y160631D03*
Y163781D03*
X356882Y166931D03*
X360042D03*
X366342D03*
X363182D03*
X356882Y154331D03*
Y157481D03*
Y160631D03*
X360042Y154331D03*
Y157481D03*
Y160631D03*
X366342Y154331D03*
Y157481D03*
Y160631D03*
X363182Y154331D03*
Y157481D03*
Y160631D03*
X356882Y163781D03*
X360042D03*
X366342D03*
X363182D03*
X369482Y170081D03*
Y173231D03*
X369092Y175991D03*
X356882Y170081D03*
X360042D03*
X366342D03*
X363182D03*
X356882Y173231D03*
X360042D03*
X366342D03*
X363182D03*
X356882Y175991D03*
X366342D03*
X372642Y135431D03*
X375782D03*
X378942D03*
X382082D03*
Y132671D03*
X372642D03*
X385242Y135431D03*
X385632Y132671D03*
X372642Y148031D03*
X375782D03*
X372642Y151181D03*
X375782D03*
X378942Y148031D03*
Y151181D03*
X382082Y148031D03*
Y151181D03*
X385242Y148031D03*
Y151181D03*
X372642Y138581D03*
X375782D03*
X378942D03*
X372642Y144881D03*
Y141731D03*
X375782D03*
Y144881D03*
X378942Y141731D03*
Y144881D03*
X382082Y138581D03*
Y144881D03*
Y141731D03*
X385242Y138581D03*
Y144881D03*
Y141731D03*
X372642Y166931D03*
X375782D03*
X378942D03*
X382082D03*
X385242D03*
X372642Y154331D03*
Y157481D03*
Y160631D03*
X375782D03*
Y157481D03*
Y154331D03*
X378942Y160631D03*
Y157481D03*
Y154331D03*
X382082D03*
Y157481D03*
Y160631D03*
X372642Y163781D03*
X375782D03*
X378942D03*
X382082D03*
X385242Y154331D03*
Y157481D03*
Y160631D03*
Y163781D03*
X372642Y170081D03*
X375782D03*
X378942D03*
X372642Y173231D03*
X375782D03*
X378942D03*
X382082Y170081D03*
Y173231D03*
X372642Y175991D03*
X382082D03*
X385242Y170081D03*
Y173231D03*
X384842Y175991D03*
X394682Y135431D03*
X391542D03*
X388382D03*
X397842D03*
Y132671D03*
X388382D03*
X400982Y135431D03*
X394682Y148031D03*
X391542D03*
X388382D03*
X394682Y151181D03*
X391542D03*
X388382D03*
X397842Y148031D03*
Y151181D03*
X400982Y148031D03*
Y151181D03*
X394682Y138581D03*
X391542D03*
X388382D03*
X397842D03*
X394682Y144881D03*
Y141731D03*
X391542Y144881D03*
Y141731D03*
X388382Y144881D03*
Y141731D03*
X397842Y144881D03*
Y141731D03*
X400982Y138581D03*
Y144881D03*
Y141731D03*
X394682Y166931D03*
X391542D03*
X388382D03*
X397842D03*
X400982D03*
X394682Y154331D03*
Y157481D03*
Y160631D03*
X391542Y154331D03*
Y157481D03*
Y160631D03*
X388382Y154331D03*
Y157481D03*
Y160631D03*
X397842Y154331D03*
Y157481D03*
Y160631D03*
X394682Y163781D03*
X391542D03*
X388382D03*
X397842D03*
X400982Y154331D03*
Y157481D03*
Y160631D03*
Y163781D03*
X394682Y170081D03*
X391542D03*
X388382D03*
X397842D03*
X388382Y173231D03*
X394682D03*
X391542D03*
X397842D03*
X388382Y175991D03*
X397842D03*
X400982Y170081D03*
Y173231D03*
G54D78*
X214300Y56191D03*
X210560Y64609D03*
X218040D03*
G54D69*
X170760Y189000D03*
X174500Y181000D03*
X178240Y189000D03*
G54D87*
X273791Y210500D03*
X288291Y53000D03*
X282209Y214240D03*
Y206760D03*
X296709Y56740D03*
Y49260D03*
X615791Y187000D03*
X624209Y183260D03*
Y190740D03*
G54D96*
X387205Y26342D03*
G54D79*
X232791Y82260D03*
Y89740D03*
X241209Y86000D03*
X248591Y102060D03*
Y109540D03*
X257009Y105800D03*
X273791Y193260D03*
Y200740D03*
X282209Y197000D03*
G54D97*
X482874Y67286D03*
X476969Y218110D03*
X776968Y67286D03*
X771063Y218110D03*
G54D88*
X280950Y243180D03*
Y240620D03*
Y238060D03*
Y235500D03*
Y232945D03*
Y250855D03*
Y248300D03*
Y245740D03*
X302650Y232945D03*
Y235500D03*
Y238060D03*
Y240620D03*
Y243180D03*
Y245740D03*
Y248300D03*
Y250855D03*
X575150Y211560D03*
Y209000D03*
Y206445D03*
Y224355D03*
Y221800D03*
Y219240D03*
Y216680D03*
Y214120D03*
X596850Y206445D03*
Y209000D03*
Y211560D03*
Y214120D03*
Y216680D03*
Y219240D03*
Y221800D03*
Y224355D03*
G54D98*
X500787Y70042D03*
X494882Y215354D03*
X759055Y70042D03*
X753150Y215354D03*
G54D89*
X276811Y263386D03*
X296811D03*
X457913Y45276D03*
X477913D03*
G36*
G01X507677Y3080D02*
X507552Y3090D01*
X507427Y3130D01*
X507317Y3190D01*
X507217Y3270D01*
X507137Y3370D01*
X507077Y3480D01*
X507037Y3605D01*
X507027Y3730D01*
Y6160D01*
X506997Y6190D01*
X506897Y6330D01*
X506877Y6370D01*
X506862Y6405D01*
X506842Y6445D01*
X506827Y6485D01*
X506817Y6525D01*
X506802Y6570D01*
X506797Y6610D01*
X506787Y6650D01*
X506782Y6695D01*
Y6735D01*
X506777Y6780D01*
X506782Y6825D01*
Y6865D01*
X506787Y6910D01*
X506797Y6950D01*
X506802Y6990D01*
X506817Y7035D01*
X506827Y7075D01*
X506842Y7115D01*
X506862Y7155D01*
X506877Y7190D01*
X506897Y7230D01*
X506997Y7370D01*
X507027Y7400D01*
Y9530D01*
X507037Y9655D01*
X507077Y9780D01*
X507137Y9890D01*
X507217Y9990D01*
X507317Y10070D01*
X507427Y10130D01*
X507552Y10170D01*
X507677Y10180D01*
X507802Y10170D01*
X507927Y10130D01*
X508037Y10070D01*
X508137Y9990D01*
X508217Y9890D01*
X508277Y9780D01*
X508317Y9655D01*
X508327Y9530D01*
Y7405D01*
X508357Y7375D01*
X508382Y7340D01*
X508412Y7305D01*
X508432Y7270D01*
X508457Y7235D01*
X508497Y7155D01*
X508542Y7035D01*
X508552Y6995D01*
X508562Y6950D01*
X508567Y6910D01*
X508577Y6865D01*
Y6695D01*
X508567Y6650D01*
X508562Y6610D01*
X508552Y6565D01*
X508542Y6525D01*
X508497Y6405D01*
X508457Y6325D01*
X508432Y6290D01*
X508412Y6255D01*
X508382Y6220D01*
X508357Y6185D01*
X508327Y6155D01*
Y3730D01*
X508317Y3605D01*
X508277Y3480D01*
X508217Y3370D01*
X508137Y3270D01*
X508037Y3190D01*
X507927Y3130D01*
X507802Y3090D01*
X507677Y3080D01*
G37*
G36*
G01X521850D02*
X521725Y3090D01*
X521600Y3130D01*
X521490Y3190D01*
X521390Y3270D01*
X521310Y3370D01*
X521250Y3480D01*
X521210Y3605D01*
X521200Y3730D01*
Y6160D01*
X521170Y6190D01*
X521070Y6330D01*
X521050Y6370D01*
X521035Y6405D01*
X521015Y6445D01*
X521000Y6485D01*
X520990Y6525D01*
X520975Y6570D01*
X520970Y6610D01*
X520960Y6650D01*
X520955Y6695D01*
Y6735D01*
X520950Y6780D01*
X520955Y6825D01*
Y6865D01*
X520960Y6910D01*
X520970Y6950D01*
X520975Y6990D01*
X520990Y7035D01*
X521000Y7075D01*
X521015Y7115D01*
X521035Y7155D01*
X521050Y7190D01*
X521070Y7230D01*
X521170Y7370D01*
X521200Y7400D01*
Y9530D01*
X521210Y9655D01*
X521250Y9780D01*
X521310Y9890D01*
X521390Y9990D01*
X521490Y10070D01*
X521600Y10130D01*
X521725Y10170D01*
X521850Y10180D01*
X521975Y10170D01*
X522100Y10130D01*
X522210Y10070D01*
X522310Y9990D01*
X522390Y9890D01*
X522450Y9780D01*
X522490Y9655D01*
X522500Y9530D01*
Y7405D01*
X522530Y7375D01*
X522555Y7340D01*
X522585Y7305D01*
X522605Y7270D01*
X522630Y7235D01*
X522670Y7155D01*
X522715Y7035D01*
X522725Y6995D01*
X522735Y6950D01*
X522740Y6910D01*
X522750Y6865D01*
Y6695D01*
X522740Y6650D01*
X522735Y6610D01*
X522725Y6565D01*
X522715Y6525D01*
X522670Y6405D01*
X522630Y6325D01*
X522605Y6290D01*
X522585Y6255D01*
X522555Y6220D01*
X522530Y6185D01*
X522500Y6155D01*
Y3730D01*
X522490Y3605D01*
X522450Y3480D01*
X522390Y3370D01*
X522310Y3270D01*
X522210Y3190D01*
X522100Y3130D01*
X521975Y3090D01*
X521850Y3080D01*
G37*
G36*
G01X517126D02*
X517001Y3090D01*
X516876Y3130D01*
X516766Y3190D01*
X516666Y3270D01*
X516586Y3370D01*
X516526Y3480D01*
X516486Y3605D01*
X516476Y3730D01*
Y6160D01*
X516446Y6190D01*
X516346Y6330D01*
X516326Y6370D01*
X516311Y6405D01*
X516291Y6445D01*
X516276Y6485D01*
X516266Y6525D01*
X516251Y6570D01*
X516246Y6610D01*
X516236Y6650D01*
X516231Y6695D01*
Y6735D01*
X516226Y6780D01*
X516231Y6825D01*
Y6865D01*
X516236Y6910D01*
X516246Y6950D01*
X516251Y6990D01*
X516266Y7035D01*
X516276Y7075D01*
X516291Y7115D01*
X516311Y7155D01*
X516326Y7190D01*
X516346Y7230D01*
X516446Y7370D01*
X516476Y7400D01*
Y9530D01*
X516486Y9655D01*
X516526Y9780D01*
X516586Y9890D01*
X516666Y9990D01*
X516766Y10070D01*
X516876Y10130D01*
X517001Y10170D01*
X517126Y10180D01*
X517251Y10170D01*
X517376Y10130D01*
X517486Y10070D01*
X517586Y9990D01*
X517666Y9890D01*
X517726Y9780D01*
X517766Y9655D01*
X517776Y9530D01*
Y7405D01*
X517806Y7375D01*
X517831Y7340D01*
X517861Y7305D01*
X517881Y7270D01*
X517906Y7235D01*
X517946Y7155D01*
X517991Y7035D01*
X518001Y6995D01*
X518011Y6950D01*
X518016Y6910D01*
X518026Y6865D01*
Y6695D01*
X518016Y6650D01*
X518011Y6610D01*
X518001Y6565D01*
X517991Y6525D01*
X517946Y6405D01*
X517906Y6325D01*
X517881Y6290D01*
X517861Y6255D01*
X517831Y6220D01*
X517806Y6185D01*
X517776Y6155D01*
Y3730D01*
X517766Y3605D01*
X517726Y3480D01*
X517666Y3370D01*
X517586Y3270D01*
X517486Y3190D01*
X517376Y3130D01*
X517251Y3090D01*
X517126Y3080D01*
G37*
G36*
G01X512401D02*
X512276Y3090D01*
X512151Y3130D01*
X512041Y3190D01*
X511941Y3270D01*
X511861Y3370D01*
X511801Y3480D01*
X511761Y3605D01*
X511751Y3730D01*
Y6160D01*
X511721Y6190D01*
X511621Y6330D01*
X511601Y6370D01*
X511586Y6405D01*
X511566Y6445D01*
X511551Y6485D01*
X511541Y6525D01*
X511526Y6570D01*
X511521Y6610D01*
X511511Y6650D01*
X511506Y6695D01*
Y6735D01*
X511501Y6780D01*
X511506Y6825D01*
Y6865D01*
X511511Y6910D01*
X511521Y6950D01*
X511526Y6990D01*
X511541Y7035D01*
X511551Y7075D01*
X511566Y7115D01*
X511586Y7155D01*
X511601Y7190D01*
X511621Y7230D01*
X511721Y7370D01*
X511751Y7400D01*
Y9530D01*
X511761Y9655D01*
X511801Y9780D01*
X511861Y9890D01*
X511941Y9990D01*
X512041Y10070D01*
X512151Y10130D01*
X512276Y10170D01*
X512401Y10180D01*
X512526Y10170D01*
X512651Y10130D01*
X512761Y10070D01*
X512861Y9990D01*
X512941Y9890D01*
X513001Y9780D01*
X513041Y9655D01*
X513051Y9530D01*
Y7405D01*
X513081Y7375D01*
X513106Y7340D01*
X513136Y7305D01*
X513156Y7270D01*
X513181Y7235D01*
X513221Y7155D01*
X513266Y7035D01*
X513276Y6995D01*
X513286Y6950D01*
X513291Y6910D01*
X513301Y6865D01*
Y6695D01*
X513291Y6650D01*
X513286Y6610D01*
X513276Y6565D01*
X513266Y6525D01*
X513221Y6405D01*
X513181Y6325D01*
X513156Y6290D01*
X513136Y6255D01*
X513106Y6220D01*
X513081Y6185D01*
X513051Y6155D01*
Y3730D01*
X513041Y3605D01*
X513001Y3480D01*
X512941Y3370D01*
X512861Y3270D01*
X512761Y3190D01*
X512651Y3130D01*
X512526Y3090D01*
X512401Y3080D01*
G37*
G36*
G01X540748D02*
X540623Y3090D01*
X540498Y3130D01*
X540388Y3190D01*
X540288Y3270D01*
X540208Y3370D01*
X540148Y3480D01*
X540108Y3605D01*
X540098Y3730D01*
Y6160D01*
X540068Y6190D01*
X539968Y6330D01*
X539948Y6370D01*
X539933Y6405D01*
X539913Y6445D01*
X539898Y6485D01*
X539888Y6525D01*
X539873Y6570D01*
X539868Y6610D01*
X539858Y6650D01*
X539853Y6695D01*
Y6735D01*
X539848Y6780D01*
X539853Y6825D01*
Y6865D01*
X539858Y6910D01*
X539868Y6950D01*
X539873Y6990D01*
X539888Y7035D01*
X539898Y7075D01*
X539913Y7115D01*
X539933Y7155D01*
X539948Y7190D01*
X539968Y7230D01*
X540068Y7370D01*
X540098Y7400D01*
Y9530D01*
X540108Y9655D01*
X540148Y9780D01*
X540208Y9890D01*
X540288Y9990D01*
X540388Y10070D01*
X540498Y10130D01*
X540623Y10170D01*
X540748Y10180D01*
X540873Y10170D01*
X540998Y10130D01*
X541108Y10070D01*
X541208Y9990D01*
X541288Y9890D01*
X541348Y9780D01*
X541388Y9655D01*
X541398Y9530D01*
Y7405D01*
X541428Y7375D01*
X541453Y7340D01*
X541483Y7305D01*
X541503Y7270D01*
X541528Y7235D01*
X541568Y7155D01*
X541613Y7035D01*
X541623Y6995D01*
X541633Y6950D01*
X541638Y6910D01*
X541648Y6865D01*
Y6695D01*
X541638Y6650D01*
X541633Y6610D01*
X541623Y6565D01*
X541613Y6525D01*
X541568Y6405D01*
X541528Y6325D01*
X541503Y6290D01*
X541483Y6255D01*
X541453Y6220D01*
X541428Y6185D01*
X541398Y6155D01*
Y3730D01*
X541388Y3605D01*
X541348Y3480D01*
X541288Y3370D01*
X541208Y3270D01*
X541108Y3190D01*
X540998Y3130D01*
X540873Y3090D01*
X540748Y3080D01*
G37*
G36*
G01X536023D02*
X535898Y3090D01*
X535773Y3130D01*
X535663Y3190D01*
X535563Y3270D01*
X535483Y3370D01*
X535423Y3480D01*
X535383Y3605D01*
X535373Y3730D01*
Y6160D01*
X535343Y6190D01*
X535243Y6330D01*
X535223Y6370D01*
X535208Y6405D01*
X535188Y6445D01*
X535173Y6485D01*
X535163Y6525D01*
X535148Y6570D01*
X535143Y6610D01*
X535133Y6650D01*
X535128Y6695D01*
Y6735D01*
X535123Y6780D01*
X535128Y6825D01*
Y6865D01*
X535133Y6910D01*
X535143Y6950D01*
X535148Y6990D01*
X535163Y7035D01*
X535173Y7075D01*
X535188Y7115D01*
X535208Y7155D01*
X535223Y7190D01*
X535243Y7230D01*
X535343Y7370D01*
X535373Y7400D01*
Y9530D01*
X535383Y9655D01*
X535423Y9780D01*
X535483Y9890D01*
X535563Y9990D01*
X535663Y10070D01*
X535773Y10130D01*
X535898Y10170D01*
X536023Y10180D01*
X536148Y10170D01*
X536273Y10130D01*
X536383Y10070D01*
X536483Y9990D01*
X536563Y9890D01*
X536623Y9780D01*
X536663Y9655D01*
X536673Y9530D01*
Y7405D01*
X536703Y7375D01*
X536728Y7340D01*
X536758Y7305D01*
X536778Y7270D01*
X536803Y7235D01*
X536843Y7155D01*
X536888Y7035D01*
X536898Y6995D01*
X536908Y6950D01*
X536913Y6910D01*
X536923Y6865D01*
Y6695D01*
X536913Y6650D01*
X536908Y6610D01*
X536898Y6565D01*
X536888Y6525D01*
X536843Y6405D01*
X536803Y6325D01*
X536778Y6290D01*
X536758Y6255D01*
X536728Y6220D01*
X536703Y6185D01*
X536673Y6155D01*
Y3730D01*
X536663Y3605D01*
X536623Y3480D01*
X536563Y3370D01*
X536483Y3270D01*
X536383Y3190D01*
X536273Y3130D01*
X536148Y3090D01*
X536023Y3080D01*
G37*
G36*
G01X531299D02*
X531174Y3090D01*
X531049Y3130D01*
X530939Y3190D01*
X530839Y3270D01*
X530759Y3370D01*
X530699Y3480D01*
X530659Y3605D01*
X530649Y3730D01*
Y6160D01*
X530619Y6190D01*
X530519Y6330D01*
X530499Y6370D01*
X530484Y6405D01*
X530464Y6445D01*
X530449Y6485D01*
X530439Y6525D01*
X530424Y6570D01*
X530419Y6610D01*
X530409Y6650D01*
X530404Y6695D01*
Y6735D01*
X530399Y6780D01*
X530404Y6825D01*
Y6865D01*
X530409Y6910D01*
X530419Y6950D01*
X530424Y6990D01*
X530439Y7035D01*
X530449Y7075D01*
X530464Y7115D01*
X530484Y7155D01*
X530499Y7190D01*
X530519Y7230D01*
X530619Y7370D01*
X530649Y7400D01*
Y9530D01*
X530659Y9655D01*
X530699Y9780D01*
X530759Y9890D01*
X530839Y9990D01*
X530939Y10070D01*
X531049Y10130D01*
X531174Y10170D01*
X531299Y10180D01*
X531424Y10170D01*
X531549Y10130D01*
X531659Y10070D01*
X531759Y9990D01*
X531839Y9890D01*
X531899Y9780D01*
X531939Y9655D01*
X531949Y9530D01*
Y7405D01*
X531979Y7375D01*
X532004Y7340D01*
X532034Y7305D01*
X532054Y7270D01*
X532079Y7235D01*
X532119Y7155D01*
X532164Y7035D01*
X532174Y6995D01*
X532184Y6950D01*
X532189Y6910D01*
X532199Y6865D01*
Y6695D01*
X532189Y6650D01*
X532184Y6610D01*
X532174Y6565D01*
X532164Y6525D01*
X532119Y6405D01*
X532079Y6325D01*
X532054Y6290D01*
X532034Y6255D01*
X532004Y6220D01*
X531979Y6185D01*
X531949Y6155D01*
Y3730D01*
X531939Y3605D01*
X531899Y3480D01*
X531839Y3370D01*
X531759Y3270D01*
X531659Y3190D01*
X531549Y3130D01*
X531424Y3090D01*
X531299Y3080D01*
G37*
G36*
G01X526575D02*
X526450Y3090D01*
X526325Y3130D01*
X526215Y3190D01*
X526115Y3270D01*
X526035Y3370D01*
X525975Y3480D01*
X525935Y3605D01*
X525925Y3730D01*
Y6160D01*
X525895Y6190D01*
X525795Y6330D01*
X525775Y6370D01*
X525760Y6405D01*
X525740Y6445D01*
X525725Y6485D01*
X525715Y6525D01*
X525700Y6570D01*
X525695Y6610D01*
X525685Y6650D01*
X525680Y6695D01*
Y6735D01*
X525675Y6780D01*
X525680Y6825D01*
Y6865D01*
X525685Y6910D01*
X525695Y6950D01*
X525700Y6990D01*
X525715Y7035D01*
X525725Y7075D01*
X525740Y7115D01*
X525760Y7155D01*
X525775Y7190D01*
X525795Y7230D01*
X525895Y7370D01*
X525925Y7400D01*
Y9530D01*
X525935Y9655D01*
X525975Y9780D01*
X526035Y9890D01*
X526115Y9990D01*
X526215Y10070D01*
X526325Y10130D01*
X526450Y10170D01*
X526575Y10180D01*
X526700Y10170D01*
X526825Y10130D01*
X526935Y10070D01*
X527035Y9990D01*
X527115Y9890D01*
X527175Y9780D01*
X527215Y9655D01*
X527225Y9530D01*
Y7405D01*
X527255Y7375D01*
X527280Y7340D01*
X527310Y7305D01*
X527330Y7270D01*
X527355Y7235D01*
X527395Y7155D01*
X527440Y7035D01*
X527450Y6995D01*
X527460Y6950D01*
X527465Y6910D01*
X527475Y6865D01*
Y6695D01*
X527465Y6650D01*
X527460Y6610D01*
X527450Y6565D01*
X527440Y6525D01*
X527395Y6405D01*
X527355Y6325D01*
X527330Y6290D01*
X527310Y6255D01*
X527280Y6220D01*
X527255Y6185D01*
X527225Y6155D01*
Y3730D01*
X527215Y3605D01*
X527175Y3480D01*
X527115Y3370D01*
X527035Y3270D01*
X526935Y3190D01*
X526825Y3130D01*
X526700Y3090D01*
X526575Y3080D01*
G37*
G36*
G01X554921D02*
X554796Y3090D01*
X554671Y3130D01*
X554561Y3190D01*
X554461Y3270D01*
X554381Y3370D01*
X554321Y3480D01*
X554281Y3605D01*
X554271Y3730D01*
Y6160D01*
X554241Y6190D01*
X554141Y6330D01*
X554121Y6370D01*
X554106Y6405D01*
X554086Y6445D01*
X554071Y6485D01*
X554061Y6525D01*
X554046Y6570D01*
X554041Y6610D01*
X554031Y6650D01*
X554026Y6695D01*
Y6735D01*
X554021Y6780D01*
X554026Y6825D01*
Y6865D01*
X554031Y6910D01*
X554041Y6950D01*
X554046Y6990D01*
X554061Y7035D01*
X554071Y7075D01*
X554086Y7115D01*
X554106Y7155D01*
X554121Y7190D01*
X554141Y7230D01*
X554241Y7370D01*
X554271Y7400D01*
Y9530D01*
X554281Y9655D01*
X554321Y9780D01*
X554381Y9890D01*
X554461Y9990D01*
X554561Y10070D01*
X554671Y10130D01*
X554796Y10170D01*
X554921Y10180D01*
X555046Y10170D01*
X555171Y10130D01*
X555281Y10070D01*
X555381Y9990D01*
X555461Y9890D01*
X555521Y9780D01*
X555561Y9655D01*
X555571Y9530D01*
Y7405D01*
X555601Y7375D01*
X555626Y7340D01*
X555656Y7305D01*
X555676Y7270D01*
X555701Y7235D01*
X555741Y7155D01*
X555786Y7035D01*
X555796Y6995D01*
X555806Y6950D01*
X555811Y6910D01*
X555821Y6865D01*
Y6695D01*
X555811Y6650D01*
X555806Y6610D01*
X555796Y6565D01*
X555786Y6525D01*
X555741Y6405D01*
X555701Y6325D01*
X555676Y6290D01*
X555656Y6255D01*
X555626Y6220D01*
X555601Y6185D01*
X555571Y6155D01*
Y3730D01*
X555561Y3605D01*
X555521Y3480D01*
X555461Y3370D01*
X555381Y3270D01*
X555281Y3190D01*
X555171Y3130D01*
X555046Y3090D01*
X554921Y3080D01*
G37*
G36*
G01X550197D02*
X550072Y3090D01*
X549947Y3130D01*
X549837Y3190D01*
X549737Y3270D01*
X549657Y3370D01*
X549597Y3480D01*
X549557Y3605D01*
X549547Y3730D01*
Y6160D01*
X549517Y6190D01*
X549417Y6330D01*
X549397Y6370D01*
X549382Y6405D01*
X549362Y6445D01*
X549347Y6485D01*
X549337Y6525D01*
X549322Y6570D01*
X549317Y6610D01*
X549307Y6650D01*
X549302Y6695D01*
Y6735D01*
X549297Y6780D01*
X549302Y6825D01*
Y6865D01*
X549307Y6910D01*
X549317Y6950D01*
X549322Y6990D01*
X549337Y7035D01*
X549347Y7075D01*
X549362Y7115D01*
X549382Y7155D01*
X549397Y7190D01*
X549417Y7230D01*
X549517Y7370D01*
X549547Y7400D01*
Y9530D01*
X549557Y9655D01*
X549597Y9780D01*
X549657Y9890D01*
X549737Y9990D01*
X549837Y10070D01*
X549947Y10130D01*
X550072Y10170D01*
X550197Y10180D01*
X550322Y10170D01*
X550447Y10130D01*
X550557Y10070D01*
X550657Y9990D01*
X550737Y9890D01*
X550797Y9780D01*
X550837Y9655D01*
X550847Y9530D01*
Y7405D01*
X550877Y7375D01*
X550902Y7340D01*
X550932Y7305D01*
X550952Y7270D01*
X550977Y7235D01*
X551017Y7155D01*
X551062Y7035D01*
X551072Y6995D01*
X551082Y6950D01*
X551087Y6910D01*
X551097Y6865D01*
Y6695D01*
X551087Y6650D01*
X551082Y6610D01*
X551072Y6565D01*
X551062Y6525D01*
X551017Y6405D01*
X550977Y6325D01*
X550952Y6290D01*
X550932Y6255D01*
X550902Y6220D01*
X550877Y6185D01*
X550847Y6155D01*
Y3730D01*
X550837Y3605D01*
X550797Y3480D01*
X550737Y3370D01*
X550657Y3270D01*
X550557Y3190D01*
X550447Y3130D01*
X550322Y3090D01*
X550197Y3080D01*
G37*
G36*
G01X545472D02*
X545347Y3090D01*
X545222Y3130D01*
X545112Y3190D01*
X545012Y3270D01*
X544932Y3370D01*
X544872Y3480D01*
X544832Y3605D01*
X544822Y3730D01*
Y6160D01*
X544792Y6190D01*
X544692Y6330D01*
X544672Y6370D01*
X544657Y6405D01*
X544637Y6445D01*
X544622Y6485D01*
X544612Y6525D01*
X544597Y6570D01*
X544592Y6610D01*
X544582Y6650D01*
X544577Y6695D01*
Y6735D01*
X544572Y6780D01*
X544577Y6825D01*
Y6865D01*
X544582Y6910D01*
X544592Y6950D01*
X544597Y6990D01*
X544612Y7035D01*
X544622Y7075D01*
X544637Y7115D01*
X544657Y7155D01*
X544672Y7190D01*
X544692Y7230D01*
X544792Y7370D01*
X544822Y7400D01*
Y9530D01*
X544832Y9655D01*
X544872Y9780D01*
X544932Y9890D01*
X545012Y9990D01*
X545112Y10070D01*
X545222Y10130D01*
X545347Y10170D01*
X545472Y10180D01*
X545597Y10170D01*
X545722Y10130D01*
X545832Y10070D01*
X545932Y9990D01*
X546012Y9890D01*
X546072Y9780D01*
X546112Y9655D01*
X546122Y9530D01*
Y7405D01*
X546152Y7375D01*
X546177Y7340D01*
X546207Y7305D01*
X546227Y7270D01*
X546252Y7235D01*
X546292Y7155D01*
X546337Y7035D01*
X546347Y6995D01*
X546357Y6950D01*
X546362Y6910D01*
X546372Y6865D01*
Y6695D01*
X546362Y6650D01*
X546357Y6610D01*
X546347Y6565D01*
X546337Y6525D01*
X546292Y6405D01*
X546252Y6325D01*
X546227Y6290D01*
X546207Y6255D01*
X546177Y6220D01*
X546152Y6185D01*
X546122Y6155D01*
Y3730D01*
X546112Y3605D01*
X546072Y3480D01*
X546012Y3370D01*
X545932Y3270D01*
X545832Y3190D01*
X545722Y3130D01*
X545597Y3090D01*
X545472Y3080D01*
G37*
G36*
G01X569094D02*
X568969Y3090D01*
X568844Y3130D01*
X568734Y3190D01*
X568634Y3270D01*
X568554Y3370D01*
X568494Y3480D01*
X568454Y3605D01*
X568444Y3730D01*
Y6160D01*
X568414Y6190D01*
X568314Y6330D01*
X568294Y6370D01*
X568279Y6405D01*
X568259Y6445D01*
X568244Y6485D01*
X568234Y6525D01*
X568219Y6570D01*
X568214Y6610D01*
X568204Y6650D01*
X568199Y6695D01*
Y6735D01*
X568194Y6780D01*
X568199Y6825D01*
Y6865D01*
X568204Y6910D01*
X568214Y6950D01*
X568219Y6990D01*
X568234Y7035D01*
X568244Y7075D01*
X568259Y7115D01*
X568279Y7155D01*
X568294Y7190D01*
X568314Y7230D01*
X568414Y7370D01*
X568444Y7400D01*
Y9530D01*
X568454Y9655D01*
X568494Y9780D01*
X568554Y9890D01*
X568634Y9990D01*
X568734Y10070D01*
X568844Y10130D01*
X568969Y10170D01*
X569094Y10180D01*
X569219Y10170D01*
X569344Y10130D01*
X569454Y10070D01*
X569554Y9990D01*
X569634Y9890D01*
X569694Y9780D01*
X569734Y9655D01*
X569744Y9530D01*
Y7405D01*
X569774Y7375D01*
X569799Y7340D01*
X569829Y7305D01*
X569849Y7270D01*
X569874Y7235D01*
X569914Y7155D01*
X569959Y7035D01*
X569969Y6995D01*
X569979Y6950D01*
X569984Y6910D01*
X569994Y6865D01*
Y6695D01*
X569984Y6650D01*
X569979Y6610D01*
X569969Y6565D01*
X569959Y6525D01*
X569914Y6405D01*
X569874Y6325D01*
X569849Y6290D01*
X569829Y6255D01*
X569799Y6220D01*
X569774Y6185D01*
X569744Y6155D01*
Y3730D01*
X569734Y3605D01*
X569694Y3480D01*
X569634Y3370D01*
X569554Y3270D01*
X569454Y3190D01*
X569344Y3130D01*
X569219Y3090D01*
X569094Y3080D01*
G37*
G36*
G01X564370D02*
X564245Y3090D01*
X564120Y3130D01*
X564010Y3190D01*
X563910Y3270D01*
X563830Y3370D01*
X563770Y3480D01*
X563730Y3605D01*
X563720Y3730D01*
Y6160D01*
X563690Y6190D01*
X563590Y6330D01*
X563570Y6370D01*
X563555Y6405D01*
X563535Y6445D01*
X563520Y6485D01*
X563510Y6525D01*
X563495Y6570D01*
X563490Y6610D01*
X563480Y6650D01*
X563475Y6695D01*
Y6735D01*
X563470Y6780D01*
X563475Y6825D01*
Y6865D01*
X563480Y6910D01*
X563490Y6950D01*
X563495Y6990D01*
X563510Y7035D01*
X563520Y7075D01*
X563535Y7115D01*
X563555Y7155D01*
X563570Y7190D01*
X563590Y7230D01*
X563690Y7370D01*
X563720Y7400D01*
Y9530D01*
X563730Y9655D01*
X563770Y9780D01*
X563830Y9890D01*
X563910Y9990D01*
X564010Y10070D01*
X564120Y10130D01*
X564245Y10170D01*
X564370Y10180D01*
X564495Y10170D01*
X564620Y10130D01*
X564730Y10070D01*
X564830Y9990D01*
X564910Y9890D01*
X564970Y9780D01*
X565010Y9655D01*
X565020Y9530D01*
Y7405D01*
X565050Y7375D01*
X565075Y7340D01*
X565105Y7305D01*
X565125Y7270D01*
X565150Y7235D01*
X565190Y7155D01*
X565235Y7035D01*
X565245Y6995D01*
X565255Y6950D01*
X565260Y6910D01*
X565270Y6865D01*
Y6695D01*
X565260Y6650D01*
X565255Y6610D01*
X565245Y6565D01*
X565235Y6525D01*
X565190Y6405D01*
X565150Y6325D01*
X565125Y6290D01*
X565105Y6255D01*
X565075Y6220D01*
X565050Y6185D01*
X565020Y6155D01*
Y3730D01*
X565010Y3605D01*
X564970Y3480D01*
X564910Y3370D01*
X564830Y3270D01*
X564730Y3190D01*
X564620Y3130D01*
X564495Y3090D01*
X564370Y3080D01*
G37*
G36*
G01X559645D02*
X559520Y3090D01*
X559395Y3130D01*
X559285Y3190D01*
X559185Y3270D01*
X559105Y3370D01*
X559045Y3480D01*
X559005Y3605D01*
X558995Y3730D01*
Y6160D01*
X558965Y6190D01*
X558865Y6330D01*
X558845Y6370D01*
X558830Y6405D01*
X558810Y6445D01*
X558795Y6485D01*
X558785Y6525D01*
X558770Y6570D01*
X558765Y6610D01*
X558755Y6650D01*
X558750Y6695D01*
Y6735D01*
X558745Y6780D01*
X558750Y6825D01*
Y6865D01*
X558755Y6910D01*
X558765Y6950D01*
X558770Y6990D01*
X558785Y7035D01*
X558795Y7075D01*
X558810Y7115D01*
X558830Y7155D01*
X558845Y7190D01*
X558865Y7230D01*
X558965Y7370D01*
X558995Y7400D01*
Y9530D01*
X559005Y9655D01*
X559045Y9780D01*
X559105Y9890D01*
X559185Y9990D01*
X559285Y10070D01*
X559395Y10130D01*
X559520Y10170D01*
X559645Y10180D01*
X559770Y10170D01*
X559895Y10130D01*
X560005Y10070D01*
X560105Y9990D01*
X560185Y9890D01*
X560245Y9780D01*
X560285Y9655D01*
X560295Y9530D01*
Y7405D01*
X560325Y7375D01*
X560350Y7340D01*
X560380Y7305D01*
X560400Y7270D01*
X560425Y7235D01*
X560465Y7155D01*
X560510Y7035D01*
X560520Y6995D01*
X560530Y6950D01*
X560535Y6910D01*
X560545Y6865D01*
Y6695D01*
X560535Y6650D01*
X560530Y6610D01*
X560520Y6565D01*
X560510Y6525D01*
X560465Y6405D01*
X560425Y6325D01*
X560400Y6290D01*
X560380Y6255D01*
X560350Y6220D01*
X560325Y6185D01*
X560295Y6155D01*
Y3730D01*
X560285Y3605D01*
X560245Y3480D01*
X560185Y3370D01*
X560105Y3270D01*
X560005Y3190D01*
X559895Y3130D01*
X559770Y3090D01*
X559645Y3080D01*
G37*
G36*
G01X587992D02*
X587867Y3090D01*
X587742Y3130D01*
X587632Y3190D01*
X587532Y3270D01*
X587452Y3370D01*
X587392Y3480D01*
X587352Y3605D01*
X587342Y3730D01*
Y6160D01*
X587312Y6190D01*
X587212Y6330D01*
X587192Y6370D01*
X587177Y6405D01*
X587157Y6445D01*
X587142Y6485D01*
X587132Y6525D01*
X587117Y6570D01*
X587112Y6610D01*
X587102Y6650D01*
X587097Y6695D01*
Y6735D01*
X587092Y6780D01*
X587097Y6825D01*
Y6865D01*
X587102Y6910D01*
X587112Y6950D01*
X587117Y6990D01*
X587132Y7035D01*
X587142Y7075D01*
X587157Y7115D01*
X587177Y7155D01*
X587192Y7190D01*
X587212Y7230D01*
X587312Y7370D01*
X587342Y7400D01*
Y9530D01*
X587352Y9655D01*
X587392Y9780D01*
X587452Y9890D01*
X587532Y9990D01*
X587632Y10070D01*
X587742Y10130D01*
X587867Y10170D01*
X587992Y10180D01*
X588117Y10170D01*
X588242Y10130D01*
X588352Y10070D01*
X588452Y9990D01*
X588532Y9890D01*
X588592Y9780D01*
X588632Y9655D01*
X588642Y9530D01*
Y7405D01*
X588672Y7375D01*
X588697Y7340D01*
X588727Y7305D01*
X588747Y7270D01*
X588772Y7235D01*
X588812Y7155D01*
X588857Y7035D01*
X588867Y6995D01*
X588877Y6950D01*
X588882Y6910D01*
X588892Y6865D01*
Y6695D01*
X588882Y6650D01*
X588877Y6610D01*
X588867Y6565D01*
X588857Y6525D01*
X588812Y6405D01*
X588772Y6325D01*
X588747Y6290D01*
X588727Y6255D01*
X588697Y6220D01*
X588672Y6185D01*
X588642Y6155D01*
Y3730D01*
X588632Y3605D01*
X588592Y3480D01*
X588532Y3370D01*
X588452Y3270D01*
X588352Y3190D01*
X588242Y3130D01*
X588117Y3090D01*
X587992Y3080D01*
G37*
G36*
G01X583267D02*
X583142Y3090D01*
X583017Y3130D01*
X582907Y3190D01*
X582807Y3270D01*
X582727Y3370D01*
X582667Y3480D01*
X582627Y3605D01*
X582617Y3730D01*
Y6160D01*
X582587Y6190D01*
X582487Y6330D01*
X582467Y6370D01*
X582452Y6405D01*
X582432Y6445D01*
X582417Y6485D01*
X582407Y6525D01*
X582392Y6570D01*
X582387Y6610D01*
X582377Y6650D01*
X582372Y6695D01*
Y6735D01*
X582367Y6780D01*
X582372Y6825D01*
Y6865D01*
X582377Y6910D01*
X582387Y6950D01*
X582392Y6990D01*
X582407Y7035D01*
X582417Y7075D01*
X582432Y7115D01*
X582452Y7155D01*
X582467Y7190D01*
X582487Y7230D01*
X582587Y7370D01*
X582617Y7400D01*
Y9530D01*
X582627Y9655D01*
X582667Y9780D01*
X582727Y9890D01*
X582807Y9990D01*
X582907Y10070D01*
X583017Y10130D01*
X583142Y10170D01*
X583267Y10180D01*
X583392Y10170D01*
X583517Y10130D01*
X583627Y10070D01*
X583727Y9990D01*
X583807Y9890D01*
X583867Y9780D01*
X583907Y9655D01*
X583917Y9530D01*
Y7405D01*
X583947Y7375D01*
X583972Y7340D01*
X584002Y7305D01*
X584022Y7270D01*
X584047Y7235D01*
X584087Y7155D01*
X584132Y7035D01*
X584142Y6995D01*
X584152Y6950D01*
X584157Y6910D01*
X584167Y6865D01*
Y6695D01*
X584157Y6650D01*
X584152Y6610D01*
X584142Y6565D01*
X584132Y6525D01*
X584087Y6405D01*
X584047Y6325D01*
X584022Y6290D01*
X584002Y6255D01*
X583972Y6220D01*
X583947Y6185D01*
X583917Y6155D01*
Y3730D01*
X583907Y3605D01*
X583867Y3480D01*
X583807Y3370D01*
X583727Y3270D01*
X583627Y3190D01*
X583517Y3130D01*
X583392Y3090D01*
X583267Y3080D01*
G37*
G36*
G01X578543D02*
X578418Y3090D01*
X578293Y3130D01*
X578183Y3190D01*
X578083Y3270D01*
X578003Y3370D01*
X577943Y3480D01*
X577903Y3605D01*
X577893Y3730D01*
Y6160D01*
X577863Y6190D01*
X577763Y6330D01*
X577743Y6370D01*
X577728Y6405D01*
X577708Y6445D01*
X577693Y6485D01*
X577683Y6525D01*
X577668Y6570D01*
X577663Y6610D01*
X577653Y6650D01*
X577648Y6695D01*
Y6735D01*
X577643Y6780D01*
X577648Y6825D01*
Y6865D01*
X577653Y6910D01*
X577663Y6950D01*
X577668Y6990D01*
X577683Y7035D01*
X577693Y7075D01*
X577708Y7115D01*
X577728Y7155D01*
X577743Y7190D01*
X577763Y7230D01*
X577863Y7370D01*
X577893Y7400D01*
Y9530D01*
X577903Y9655D01*
X577943Y9780D01*
X578003Y9890D01*
X578083Y9990D01*
X578183Y10070D01*
X578293Y10130D01*
X578418Y10170D01*
X578543Y10180D01*
X578668Y10170D01*
X578793Y10130D01*
X578903Y10070D01*
X579003Y9990D01*
X579083Y9890D01*
X579143Y9780D01*
X579183Y9655D01*
X579193Y9530D01*
Y7405D01*
X579223Y7375D01*
X579248Y7340D01*
X579278Y7305D01*
X579298Y7270D01*
X579323Y7235D01*
X579363Y7155D01*
X579408Y7035D01*
X579418Y6995D01*
X579428Y6950D01*
X579433Y6910D01*
X579443Y6865D01*
Y6695D01*
X579433Y6650D01*
X579428Y6610D01*
X579418Y6565D01*
X579408Y6525D01*
X579363Y6405D01*
X579323Y6325D01*
X579298Y6290D01*
X579278Y6255D01*
X579248Y6220D01*
X579223Y6185D01*
X579193Y6155D01*
Y3730D01*
X579183Y3605D01*
X579143Y3480D01*
X579083Y3370D01*
X579003Y3270D01*
X578903Y3190D01*
X578793Y3130D01*
X578668Y3090D01*
X578543Y3080D01*
G37*
G36*
G01X573819D02*
X573694Y3090D01*
X573569Y3130D01*
X573459Y3190D01*
X573359Y3270D01*
X573279Y3370D01*
X573219Y3480D01*
X573179Y3605D01*
X573169Y3730D01*
Y6160D01*
X573139Y6190D01*
X573039Y6330D01*
X573019Y6370D01*
X573004Y6405D01*
X572984Y6445D01*
X572969Y6485D01*
X572959Y6525D01*
X572944Y6570D01*
X572939Y6610D01*
X572929Y6650D01*
X572924Y6695D01*
Y6735D01*
X572919Y6780D01*
X572924Y6825D01*
Y6865D01*
X572929Y6910D01*
X572939Y6950D01*
X572944Y6990D01*
X572959Y7035D01*
X572969Y7075D01*
X572984Y7115D01*
X573004Y7155D01*
X573019Y7190D01*
X573039Y7230D01*
X573139Y7370D01*
X573169Y7400D01*
Y9530D01*
X573179Y9655D01*
X573219Y9780D01*
X573279Y9890D01*
X573359Y9990D01*
X573459Y10070D01*
X573569Y10130D01*
X573694Y10170D01*
X573819Y10180D01*
X573944Y10170D01*
X574069Y10130D01*
X574179Y10070D01*
X574279Y9990D01*
X574359Y9890D01*
X574419Y9780D01*
X574459Y9655D01*
X574469Y9530D01*
Y7405D01*
X574499Y7375D01*
X574524Y7340D01*
X574554Y7305D01*
X574574Y7270D01*
X574599Y7235D01*
X574639Y7155D01*
X574684Y7035D01*
X574694Y6995D01*
X574704Y6950D01*
X574709Y6910D01*
X574719Y6865D01*
Y6695D01*
X574709Y6650D01*
X574704Y6610D01*
X574694Y6565D01*
X574684Y6525D01*
X574639Y6405D01*
X574599Y6325D01*
X574574Y6290D01*
X574554Y6255D01*
X574524Y6220D01*
X574499Y6185D01*
X574469Y6155D01*
Y3730D01*
X574459Y3605D01*
X574419Y3480D01*
X574359Y3370D01*
X574279Y3270D01*
X574179Y3190D01*
X574069Y3130D01*
X573944Y3090D01*
X573819Y3080D01*
G37*
G36*
G01X602165D02*
X602040Y3090D01*
X601915Y3130D01*
X601805Y3190D01*
X601705Y3270D01*
X601625Y3370D01*
X601565Y3480D01*
X601525Y3605D01*
X601515Y3730D01*
Y6160D01*
X601485Y6190D01*
X601385Y6330D01*
X601365Y6370D01*
X601350Y6405D01*
X601330Y6445D01*
X601315Y6485D01*
X601305Y6525D01*
X601290Y6570D01*
X601285Y6610D01*
X601275Y6650D01*
X601270Y6695D01*
Y6735D01*
X601265Y6780D01*
X601270Y6825D01*
Y6865D01*
X601275Y6910D01*
X601285Y6950D01*
X601290Y6990D01*
X601305Y7035D01*
X601315Y7075D01*
X601330Y7115D01*
X601350Y7155D01*
X601365Y7190D01*
X601385Y7230D01*
X601485Y7370D01*
X601515Y7400D01*
Y9530D01*
X601525Y9655D01*
X601565Y9780D01*
X601625Y9890D01*
X601705Y9990D01*
X601805Y10070D01*
X601915Y10130D01*
X602040Y10170D01*
X602165Y10180D01*
X602290Y10170D01*
X602415Y10130D01*
X602525Y10070D01*
X602625Y9990D01*
X602705Y9890D01*
X602765Y9780D01*
X602805Y9655D01*
X602815Y9530D01*
Y7405D01*
X602845Y7375D01*
X602870Y7340D01*
X602900Y7305D01*
X602920Y7270D01*
X602945Y7235D01*
X602985Y7155D01*
X603030Y7035D01*
X603040Y6995D01*
X603050Y6950D01*
X603055Y6910D01*
X603065Y6865D01*
Y6695D01*
X603055Y6650D01*
X603050Y6610D01*
X603040Y6565D01*
X603030Y6525D01*
X602985Y6405D01*
X602945Y6325D01*
X602920Y6290D01*
X602900Y6255D01*
X602870Y6220D01*
X602845Y6185D01*
X602815Y6155D01*
Y3730D01*
X602805Y3605D01*
X602765Y3480D01*
X602705Y3370D01*
X602625Y3270D01*
X602525Y3190D01*
X602415Y3130D01*
X602290Y3090D01*
X602165Y3080D01*
G37*
G36*
G01X616338D02*
X616213Y3090D01*
X616088Y3130D01*
X615978Y3190D01*
X615878Y3270D01*
X615798Y3370D01*
X615738Y3480D01*
X615698Y3605D01*
X615688Y3730D01*
Y6160D01*
X615658Y6190D01*
X615558Y6330D01*
X615538Y6370D01*
X615523Y6405D01*
X615503Y6445D01*
X615488Y6485D01*
X615478Y6525D01*
X615463Y6570D01*
X615458Y6610D01*
X615448Y6650D01*
X615443Y6695D01*
Y6735D01*
X615438Y6780D01*
X615443Y6825D01*
Y6865D01*
X615448Y6910D01*
X615458Y6950D01*
X615463Y6990D01*
X615478Y7035D01*
X615488Y7075D01*
X615503Y7115D01*
X615523Y7155D01*
X615538Y7190D01*
X615558Y7230D01*
X615658Y7370D01*
X615688Y7400D01*
Y9530D01*
X615698Y9655D01*
X615738Y9780D01*
X615798Y9890D01*
X615878Y9990D01*
X615978Y10070D01*
X616088Y10130D01*
X616213Y10170D01*
X616338Y10180D01*
X616463Y10170D01*
X616588Y10130D01*
X616698Y10070D01*
X616798Y9990D01*
X616878Y9890D01*
X616938Y9780D01*
X616978Y9655D01*
X616988Y9530D01*
Y7405D01*
X617018Y7375D01*
X617043Y7340D01*
X617073Y7305D01*
X617093Y7270D01*
X617118Y7235D01*
X617158Y7155D01*
X617203Y7035D01*
X617213Y6995D01*
X617223Y6950D01*
X617228Y6910D01*
X617238Y6865D01*
Y6695D01*
X617228Y6650D01*
X617223Y6610D01*
X617213Y6565D01*
X617203Y6525D01*
X617158Y6405D01*
X617118Y6325D01*
X617093Y6290D01*
X617073Y6255D01*
X617043Y6220D01*
X617018Y6185D01*
X616988Y6155D01*
Y3730D01*
X616978Y3605D01*
X616938Y3480D01*
X616878Y3370D01*
X616798Y3270D01*
X616698Y3190D01*
X616588Y3130D01*
X616463Y3090D01*
X616338Y3080D01*
G37*
G36*
G01X611614D02*
X611489Y3090D01*
X611364Y3130D01*
X611254Y3190D01*
X611154Y3270D01*
X611074Y3370D01*
X611014Y3480D01*
X610974Y3605D01*
X610964Y3730D01*
Y6160D01*
X610934Y6190D01*
X610834Y6330D01*
X610814Y6370D01*
X610799Y6405D01*
X610779Y6445D01*
X610764Y6485D01*
X610754Y6525D01*
X610739Y6570D01*
X610734Y6610D01*
X610724Y6650D01*
X610719Y6695D01*
Y6735D01*
X610714Y6780D01*
X610719Y6825D01*
Y6865D01*
X610724Y6910D01*
X610734Y6950D01*
X610739Y6990D01*
X610754Y7035D01*
X610764Y7075D01*
X610779Y7115D01*
X610799Y7155D01*
X610814Y7190D01*
X610834Y7230D01*
X610934Y7370D01*
X610964Y7400D01*
Y9530D01*
X610974Y9655D01*
X611014Y9780D01*
X611074Y9890D01*
X611154Y9990D01*
X611254Y10070D01*
X611364Y10130D01*
X611489Y10170D01*
X611614Y10180D01*
X611739Y10170D01*
X611864Y10130D01*
X611974Y10070D01*
X612074Y9990D01*
X612154Y9890D01*
X612214Y9780D01*
X612254Y9655D01*
X612264Y9530D01*
Y7405D01*
X612294Y7375D01*
X612319Y7340D01*
X612349Y7305D01*
X612369Y7270D01*
X612394Y7235D01*
X612434Y7155D01*
X612479Y7035D01*
X612489Y6995D01*
X612499Y6950D01*
X612504Y6910D01*
X612514Y6865D01*
Y6695D01*
X612504Y6650D01*
X612499Y6610D01*
X612489Y6565D01*
X612479Y6525D01*
X612434Y6405D01*
X612394Y6325D01*
X612369Y6290D01*
X612349Y6255D01*
X612319Y6220D01*
X612294Y6185D01*
X612264Y6155D01*
Y3730D01*
X612254Y3605D01*
X612214Y3480D01*
X612154Y3370D01*
X612074Y3270D01*
X611974Y3190D01*
X611864Y3130D01*
X611739Y3090D01*
X611614Y3080D01*
G37*
G36*
G01X606890D02*
X606765Y3090D01*
X606640Y3130D01*
X606530Y3190D01*
X606430Y3270D01*
X606350Y3370D01*
X606290Y3480D01*
X606250Y3605D01*
X606240Y3730D01*
Y6160D01*
X606210Y6190D01*
X606110Y6330D01*
X606090Y6370D01*
X606075Y6405D01*
X606055Y6445D01*
X606040Y6485D01*
X606030Y6525D01*
X606015Y6570D01*
X606010Y6610D01*
X606000Y6650D01*
X605995Y6695D01*
Y6735D01*
X605990Y6780D01*
X605995Y6825D01*
Y6865D01*
X606000Y6910D01*
X606010Y6950D01*
X606015Y6990D01*
X606030Y7035D01*
X606040Y7075D01*
X606055Y7115D01*
X606075Y7155D01*
X606090Y7190D01*
X606110Y7230D01*
X606210Y7370D01*
X606240Y7400D01*
Y9530D01*
X606250Y9655D01*
X606290Y9780D01*
X606350Y9890D01*
X606430Y9990D01*
X606530Y10070D01*
X606640Y10130D01*
X606765Y10170D01*
X606890Y10180D01*
X607015Y10170D01*
X607140Y10130D01*
X607250Y10070D01*
X607350Y9990D01*
X607430Y9890D01*
X607490Y9780D01*
X607530Y9655D01*
X607540Y9530D01*
Y7405D01*
X607570Y7375D01*
X607595Y7340D01*
X607625Y7305D01*
X607645Y7270D01*
X607670Y7235D01*
X607710Y7155D01*
X607755Y7035D01*
X607765Y6995D01*
X607775Y6950D01*
X607780Y6910D01*
X607790Y6865D01*
Y6695D01*
X607780Y6650D01*
X607775Y6610D01*
X607765Y6565D01*
X607755Y6525D01*
X607710Y6405D01*
X607670Y6325D01*
X607645Y6290D01*
X607625Y6255D01*
X607595Y6220D01*
X607570Y6185D01*
X607540Y6155D01*
Y3730D01*
X607530Y3605D01*
X607490Y3480D01*
X607430Y3370D01*
X607350Y3270D01*
X607250Y3190D01*
X607140Y3130D01*
X607015Y3090D01*
X606890Y3080D01*
G37*
G36*
G01X630512D02*
X630387Y3090D01*
X630262Y3130D01*
X630152Y3190D01*
X630052Y3270D01*
X629972Y3370D01*
X629912Y3480D01*
X629872Y3605D01*
X629862Y3730D01*
Y6160D01*
X629832Y6190D01*
X629732Y6330D01*
X629712Y6370D01*
X629697Y6405D01*
X629677Y6445D01*
X629662Y6485D01*
X629652Y6525D01*
X629637Y6570D01*
X629632Y6610D01*
X629622Y6650D01*
X629617Y6695D01*
Y6735D01*
X629612Y6780D01*
X629617Y6825D01*
Y6865D01*
X629622Y6910D01*
X629632Y6950D01*
X629637Y6990D01*
X629652Y7035D01*
X629662Y7075D01*
X629677Y7115D01*
X629697Y7155D01*
X629712Y7190D01*
X629732Y7230D01*
X629832Y7370D01*
X629862Y7400D01*
Y9530D01*
X629872Y9655D01*
X629912Y9780D01*
X629972Y9890D01*
X630052Y9990D01*
X630152Y10070D01*
X630262Y10130D01*
X630387Y10170D01*
X630512Y10180D01*
X630637Y10170D01*
X630762Y10130D01*
X630872Y10070D01*
X630972Y9990D01*
X631052Y9890D01*
X631112Y9780D01*
X631152Y9655D01*
X631162Y9530D01*
Y7405D01*
X631192Y7375D01*
X631217Y7340D01*
X631247Y7305D01*
X631267Y7270D01*
X631292Y7235D01*
X631332Y7155D01*
X631377Y7035D01*
X631387Y6995D01*
X631397Y6950D01*
X631402Y6910D01*
X631412Y6865D01*
Y6695D01*
X631402Y6650D01*
X631397Y6610D01*
X631387Y6565D01*
X631377Y6525D01*
X631332Y6405D01*
X631292Y6325D01*
X631267Y6290D01*
X631247Y6255D01*
X631217Y6220D01*
X631192Y6185D01*
X631162Y6155D01*
Y3730D01*
X631152Y3605D01*
X631112Y3480D01*
X631052Y3370D01*
X630972Y3270D01*
X630872Y3190D01*
X630762Y3130D01*
X630637Y3090D01*
X630512Y3080D01*
G37*
G36*
G01X625787D02*
X625662Y3090D01*
X625537Y3130D01*
X625427Y3190D01*
X625327Y3270D01*
X625247Y3370D01*
X625187Y3480D01*
X625147Y3605D01*
X625137Y3730D01*
Y6160D01*
X625107Y6190D01*
X625007Y6330D01*
X624987Y6370D01*
X624972Y6405D01*
X624952Y6445D01*
X624937Y6485D01*
X624927Y6525D01*
X624912Y6570D01*
X624907Y6610D01*
X624897Y6650D01*
X624892Y6695D01*
Y6735D01*
X624887Y6780D01*
X624892Y6825D01*
Y6865D01*
X624897Y6910D01*
X624907Y6950D01*
X624912Y6990D01*
X624927Y7035D01*
X624937Y7075D01*
X624952Y7115D01*
X624972Y7155D01*
X624987Y7190D01*
X625007Y7230D01*
X625107Y7370D01*
X625137Y7400D01*
Y9530D01*
X625147Y9655D01*
X625187Y9780D01*
X625247Y9890D01*
X625327Y9990D01*
X625427Y10070D01*
X625537Y10130D01*
X625662Y10170D01*
X625787Y10180D01*
X625912Y10170D01*
X626037Y10130D01*
X626147Y10070D01*
X626247Y9990D01*
X626327Y9890D01*
X626387Y9780D01*
X626427Y9655D01*
X626437Y9530D01*
Y7405D01*
X626467Y7375D01*
X626492Y7340D01*
X626522Y7305D01*
X626542Y7270D01*
X626567Y7235D01*
X626607Y7155D01*
X626652Y7035D01*
X626662Y6995D01*
X626672Y6950D01*
X626677Y6910D01*
X626687Y6865D01*
Y6695D01*
X626677Y6650D01*
X626672Y6610D01*
X626662Y6565D01*
X626652Y6525D01*
X626607Y6405D01*
X626567Y6325D01*
X626542Y6290D01*
X626522Y6255D01*
X626492Y6220D01*
X626467Y6185D01*
X626437Y6155D01*
Y3730D01*
X626427Y3605D01*
X626387Y3480D01*
X626327Y3370D01*
X626247Y3270D01*
X626147Y3190D01*
X626037Y3130D01*
X625912Y3090D01*
X625787Y3080D01*
G37*
G36*
G01X621063D02*
X620938Y3090D01*
X620813Y3130D01*
X620703Y3190D01*
X620603Y3270D01*
X620523Y3370D01*
X620463Y3480D01*
X620423Y3605D01*
X620413Y3730D01*
Y6160D01*
X620383Y6190D01*
X620283Y6330D01*
X620263Y6370D01*
X620248Y6405D01*
X620228Y6445D01*
X620213Y6485D01*
X620203Y6525D01*
X620188Y6570D01*
X620183Y6610D01*
X620173Y6650D01*
X620168Y6695D01*
Y6735D01*
X620163Y6780D01*
X620168Y6825D01*
Y6865D01*
X620173Y6910D01*
X620183Y6950D01*
X620188Y6990D01*
X620203Y7035D01*
X620213Y7075D01*
X620228Y7115D01*
X620248Y7155D01*
X620263Y7190D01*
X620283Y7230D01*
X620383Y7370D01*
X620413Y7400D01*
Y9530D01*
X620423Y9655D01*
X620463Y9780D01*
X620523Y9890D01*
X620603Y9990D01*
X620703Y10070D01*
X620813Y10130D01*
X620938Y10170D01*
X621063Y10180D01*
X621188Y10170D01*
X621313Y10130D01*
X621423Y10070D01*
X621523Y9990D01*
X621603Y9890D01*
X621663Y9780D01*
X621703Y9655D01*
X621713Y9530D01*
Y7405D01*
X621743Y7375D01*
X621768Y7340D01*
X621798Y7305D01*
X621818Y7270D01*
X621843Y7235D01*
X621883Y7155D01*
X621928Y7035D01*
X621938Y6995D01*
X621948Y6950D01*
X621953Y6910D01*
X621963Y6865D01*
Y6695D01*
X621953Y6650D01*
X621948Y6610D01*
X621938Y6565D01*
X621928Y6525D01*
X621883Y6405D01*
X621843Y6325D01*
X621818Y6290D01*
X621798Y6255D01*
X621768Y6220D01*
X621743Y6185D01*
X621713Y6155D01*
Y3730D01*
X621703Y3605D01*
X621663Y3480D01*
X621603Y3370D01*
X621523Y3270D01*
X621423Y3190D01*
X621313Y3130D01*
X621188Y3090D01*
X621063Y3080D01*
G37*
G36*
G01X649409D02*
X649284Y3090D01*
X649159Y3130D01*
X649049Y3190D01*
X648949Y3270D01*
X648869Y3370D01*
X648809Y3480D01*
X648769Y3605D01*
X648759Y3730D01*
Y6160D01*
X648729Y6190D01*
X648629Y6330D01*
X648609Y6370D01*
X648594Y6405D01*
X648574Y6445D01*
X648559Y6485D01*
X648549Y6525D01*
X648534Y6570D01*
X648529Y6610D01*
X648519Y6650D01*
X648514Y6695D01*
Y6735D01*
X648509Y6780D01*
X648514Y6825D01*
Y6865D01*
X648519Y6910D01*
X648529Y6950D01*
X648534Y6990D01*
X648549Y7035D01*
X648559Y7075D01*
X648574Y7115D01*
X648594Y7155D01*
X648609Y7190D01*
X648629Y7230D01*
X648729Y7370D01*
X648759Y7400D01*
Y9530D01*
X648769Y9655D01*
X648809Y9780D01*
X648869Y9890D01*
X648949Y9990D01*
X649049Y10070D01*
X649159Y10130D01*
X649284Y10170D01*
X649409Y10180D01*
X649534Y10170D01*
X649659Y10130D01*
X649769Y10070D01*
X649869Y9990D01*
X649949Y9890D01*
X650009Y9780D01*
X650049Y9655D01*
X650059Y9530D01*
Y7405D01*
X650089Y7375D01*
X650114Y7340D01*
X650144Y7305D01*
X650164Y7270D01*
X650189Y7235D01*
X650229Y7155D01*
X650274Y7035D01*
X650284Y6995D01*
X650294Y6950D01*
X650299Y6910D01*
X650309Y6865D01*
Y6695D01*
X650299Y6650D01*
X650294Y6610D01*
X650284Y6565D01*
X650274Y6525D01*
X650229Y6405D01*
X650189Y6325D01*
X650164Y6290D01*
X650144Y6255D01*
X650114Y6220D01*
X650089Y6185D01*
X650059Y6155D01*
Y3730D01*
X650049Y3605D01*
X650009Y3480D01*
X649949Y3370D01*
X649869Y3270D01*
X649769Y3190D01*
X649659Y3130D01*
X649534Y3090D01*
X649409Y3080D01*
G37*
G36*
G01X644685D02*
X644560Y3090D01*
X644435Y3130D01*
X644325Y3190D01*
X644225Y3270D01*
X644145Y3370D01*
X644085Y3480D01*
X644045Y3605D01*
X644035Y3730D01*
Y6160D01*
X644005Y6190D01*
X643905Y6330D01*
X643885Y6370D01*
X643870Y6405D01*
X643850Y6445D01*
X643835Y6485D01*
X643825Y6525D01*
X643810Y6570D01*
X643805Y6610D01*
X643795Y6650D01*
X643790Y6695D01*
Y6735D01*
X643785Y6780D01*
X643790Y6825D01*
Y6865D01*
X643795Y6910D01*
X643805Y6950D01*
X643810Y6990D01*
X643825Y7035D01*
X643835Y7075D01*
X643850Y7115D01*
X643870Y7155D01*
X643885Y7190D01*
X643905Y7230D01*
X644005Y7370D01*
X644035Y7400D01*
Y9530D01*
X644045Y9655D01*
X644085Y9780D01*
X644145Y9890D01*
X644225Y9990D01*
X644325Y10070D01*
X644435Y10130D01*
X644560Y10170D01*
X644685Y10180D01*
X644810Y10170D01*
X644935Y10130D01*
X645045Y10070D01*
X645145Y9990D01*
X645225Y9890D01*
X645285Y9780D01*
X645325Y9655D01*
X645335Y9530D01*
Y7405D01*
X645365Y7375D01*
X645390Y7340D01*
X645420Y7305D01*
X645440Y7270D01*
X645465Y7235D01*
X645505Y7155D01*
X645550Y7035D01*
X645560Y6995D01*
X645570Y6950D01*
X645575Y6910D01*
X645585Y6865D01*
Y6695D01*
X645575Y6650D01*
X645570Y6610D01*
X645560Y6565D01*
X645550Y6525D01*
X645505Y6405D01*
X645465Y6325D01*
X645440Y6290D01*
X645420Y6255D01*
X645390Y6220D01*
X645365Y6185D01*
X645335Y6155D01*
Y3730D01*
X645325Y3605D01*
X645285Y3480D01*
X645225Y3370D01*
X645145Y3270D01*
X645045Y3190D01*
X644935Y3130D01*
X644810Y3090D01*
X644685Y3080D01*
G37*
G36*
G01X639960D02*
X639835Y3090D01*
X639710Y3130D01*
X639600Y3190D01*
X639500Y3270D01*
X639420Y3370D01*
X639360Y3480D01*
X639320Y3605D01*
X639310Y3730D01*
Y6160D01*
X639280Y6190D01*
X639180Y6330D01*
X639160Y6370D01*
X639145Y6405D01*
X639125Y6445D01*
X639110Y6485D01*
X639100Y6525D01*
X639085Y6570D01*
X639080Y6610D01*
X639070Y6650D01*
X639065Y6695D01*
Y6735D01*
X639060Y6780D01*
X639065Y6825D01*
Y6865D01*
X639070Y6910D01*
X639080Y6950D01*
X639085Y6990D01*
X639100Y7035D01*
X639110Y7075D01*
X639125Y7115D01*
X639145Y7155D01*
X639160Y7190D01*
X639180Y7230D01*
X639280Y7370D01*
X639310Y7400D01*
Y9530D01*
X639320Y9655D01*
X639360Y9780D01*
X639420Y9890D01*
X639500Y9990D01*
X639600Y10070D01*
X639710Y10130D01*
X639835Y10170D01*
X639960Y10180D01*
X640085Y10170D01*
X640210Y10130D01*
X640320Y10070D01*
X640420Y9990D01*
X640500Y9890D01*
X640560Y9780D01*
X640600Y9655D01*
X640610Y9530D01*
Y7405D01*
X640640Y7375D01*
X640665Y7340D01*
X640695Y7305D01*
X640715Y7270D01*
X640740Y7235D01*
X640780Y7155D01*
X640825Y7035D01*
X640835Y6995D01*
X640845Y6950D01*
X640850Y6910D01*
X640860Y6865D01*
Y6695D01*
X640850Y6650D01*
X640845Y6610D01*
X640835Y6565D01*
X640825Y6525D01*
X640780Y6405D01*
X640740Y6325D01*
X640715Y6290D01*
X640695Y6255D01*
X640665Y6220D01*
X640640Y6185D01*
X640610Y6155D01*
Y3730D01*
X640600Y3605D01*
X640560Y3480D01*
X640500Y3370D01*
X640420Y3270D01*
X640320Y3190D01*
X640210Y3130D01*
X640085Y3090D01*
X639960Y3080D01*
G37*
G36*
G01X635236D02*
X635111Y3090D01*
X634986Y3130D01*
X634876Y3190D01*
X634776Y3270D01*
X634696Y3370D01*
X634636Y3480D01*
X634596Y3605D01*
X634586Y3730D01*
Y6160D01*
X634556Y6190D01*
X634456Y6330D01*
X634436Y6370D01*
X634421Y6405D01*
X634401Y6445D01*
X634386Y6485D01*
X634376Y6525D01*
X634361Y6570D01*
X634356Y6610D01*
X634346Y6650D01*
X634341Y6695D01*
Y6735D01*
X634336Y6780D01*
X634341Y6825D01*
Y6865D01*
X634346Y6910D01*
X634356Y6950D01*
X634361Y6990D01*
X634376Y7035D01*
X634386Y7075D01*
X634401Y7115D01*
X634421Y7155D01*
X634436Y7190D01*
X634456Y7230D01*
X634556Y7370D01*
X634586Y7400D01*
Y9530D01*
X634596Y9655D01*
X634636Y9780D01*
X634696Y9890D01*
X634776Y9990D01*
X634876Y10070D01*
X634986Y10130D01*
X635111Y10170D01*
X635236Y10180D01*
X635361Y10170D01*
X635486Y10130D01*
X635596Y10070D01*
X635696Y9990D01*
X635776Y9890D01*
X635836Y9780D01*
X635876Y9655D01*
X635886Y9530D01*
Y7405D01*
X635916Y7375D01*
X635941Y7340D01*
X635971Y7305D01*
X635991Y7270D01*
X636016Y7235D01*
X636056Y7155D01*
X636101Y7035D01*
X636111Y6995D01*
X636121Y6950D01*
X636126Y6910D01*
X636136Y6865D01*
Y6695D01*
X636126Y6650D01*
X636121Y6610D01*
X636111Y6565D01*
X636101Y6525D01*
X636056Y6405D01*
X636016Y6325D01*
X635991Y6290D01*
X635971Y6255D01*
X635941Y6220D01*
X635916Y6185D01*
X635886Y6155D01*
Y3730D01*
X635876Y3605D01*
X635836Y3480D01*
X635776Y3370D01*
X635696Y3270D01*
X635596Y3190D01*
X635486Y3130D01*
X635361Y3090D01*
X635236Y3080D01*
G37*
G36*
G01X663582D02*
X663457Y3090D01*
X663332Y3130D01*
X663222Y3190D01*
X663122Y3270D01*
X663042Y3370D01*
X662982Y3480D01*
X662942Y3605D01*
X662932Y3730D01*
Y6160D01*
X662902Y6190D01*
X662802Y6330D01*
X662782Y6370D01*
X662767Y6405D01*
X662747Y6445D01*
X662732Y6485D01*
X662722Y6525D01*
X662707Y6570D01*
X662702Y6610D01*
X662692Y6650D01*
X662687Y6695D01*
Y6735D01*
X662682Y6780D01*
X662687Y6825D01*
Y6865D01*
X662692Y6910D01*
X662702Y6950D01*
X662707Y6990D01*
X662722Y7035D01*
X662732Y7075D01*
X662747Y7115D01*
X662767Y7155D01*
X662782Y7190D01*
X662802Y7230D01*
X662902Y7370D01*
X662932Y7400D01*
Y9530D01*
X662942Y9655D01*
X662982Y9780D01*
X663042Y9890D01*
X663122Y9990D01*
X663222Y10070D01*
X663332Y10130D01*
X663457Y10170D01*
X663582Y10180D01*
X663707Y10170D01*
X663832Y10130D01*
X663942Y10070D01*
X664042Y9990D01*
X664122Y9890D01*
X664182Y9780D01*
X664222Y9655D01*
X664232Y9530D01*
Y7405D01*
X664262Y7375D01*
X664287Y7340D01*
X664317Y7305D01*
X664337Y7270D01*
X664362Y7235D01*
X664402Y7155D01*
X664447Y7035D01*
X664457Y6995D01*
X664467Y6950D01*
X664472Y6910D01*
X664482Y6865D01*
Y6695D01*
X664472Y6650D01*
X664467Y6610D01*
X664457Y6565D01*
X664447Y6525D01*
X664402Y6405D01*
X664362Y6325D01*
X664337Y6290D01*
X664317Y6255D01*
X664287Y6220D01*
X664262Y6185D01*
X664232Y6155D01*
Y3730D01*
X664222Y3605D01*
X664182Y3480D01*
X664122Y3370D01*
X664042Y3270D01*
X663942Y3190D01*
X663832Y3130D01*
X663707Y3090D01*
X663582Y3080D01*
G37*
G36*
G01X658858D02*
X658733Y3090D01*
X658608Y3130D01*
X658498Y3190D01*
X658398Y3270D01*
X658318Y3370D01*
X658258Y3480D01*
X658218Y3605D01*
X658208Y3730D01*
Y6160D01*
X658178Y6190D01*
X658078Y6330D01*
X658058Y6370D01*
X658043Y6405D01*
X658023Y6445D01*
X658008Y6485D01*
X657998Y6525D01*
X657983Y6570D01*
X657978Y6610D01*
X657968Y6650D01*
X657963Y6695D01*
Y6735D01*
X657958Y6780D01*
X657963Y6825D01*
Y6865D01*
X657968Y6910D01*
X657978Y6950D01*
X657983Y6990D01*
X657998Y7035D01*
X658008Y7075D01*
X658023Y7115D01*
X658043Y7155D01*
X658058Y7190D01*
X658078Y7230D01*
X658178Y7370D01*
X658208Y7400D01*
Y9530D01*
X658218Y9655D01*
X658258Y9780D01*
X658318Y9890D01*
X658398Y9990D01*
X658498Y10070D01*
X658608Y10130D01*
X658733Y10170D01*
X658858Y10180D01*
X658983Y10170D01*
X659108Y10130D01*
X659218Y10070D01*
X659318Y9990D01*
X659398Y9890D01*
X659458Y9780D01*
X659498Y9655D01*
X659508Y9530D01*
Y7405D01*
X659538Y7375D01*
X659563Y7340D01*
X659593Y7305D01*
X659613Y7270D01*
X659638Y7235D01*
X659678Y7155D01*
X659723Y7035D01*
X659733Y6995D01*
X659743Y6950D01*
X659748Y6910D01*
X659758Y6865D01*
Y6695D01*
X659748Y6650D01*
X659743Y6610D01*
X659733Y6565D01*
X659723Y6525D01*
X659678Y6405D01*
X659638Y6325D01*
X659613Y6290D01*
X659593Y6255D01*
X659563Y6220D01*
X659538Y6185D01*
X659508Y6155D01*
Y3730D01*
X659498Y3605D01*
X659458Y3480D01*
X659398Y3370D01*
X659318Y3270D01*
X659218Y3190D01*
X659108Y3130D01*
X658983Y3090D01*
X658858Y3080D01*
G37*
G36*
G01X654134D02*
X654009Y3090D01*
X653884Y3130D01*
X653774Y3190D01*
X653674Y3270D01*
X653594Y3370D01*
X653534Y3480D01*
X653494Y3605D01*
X653484Y3730D01*
Y6160D01*
X653454Y6190D01*
X653354Y6330D01*
X653334Y6370D01*
X653319Y6405D01*
X653299Y6445D01*
X653284Y6485D01*
X653274Y6525D01*
X653259Y6570D01*
X653254Y6610D01*
X653244Y6650D01*
X653239Y6695D01*
Y6735D01*
X653234Y6780D01*
X653239Y6825D01*
Y6865D01*
X653244Y6910D01*
X653254Y6950D01*
X653259Y6990D01*
X653274Y7035D01*
X653284Y7075D01*
X653299Y7115D01*
X653319Y7155D01*
X653334Y7190D01*
X653354Y7230D01*
X653454Y7370D01*
X653484Y7400D01*
Y9530D01*
X653494Y9655D01*
X653534Y9780D01*
X653594Y9890D01*
X653674Y9990D01*
X653774Y10070D01*
X653884Y10130D01*
X654009Y10170D01*
X654134Y10180D01*
X654259Y10170D01*
X654384Y10130D01*
X654494Y10070D01*
X654594Y9990D01*
X654674Y9890D01*
X654734Y9780D01*
X654774Y9655D01*
X654784Y9530D01*
Y7405D01*
X654814Y7375D01*
X654839Y7340D01*
X654869Y7305D01*
X654889Y7270D01*
X654914Y7235D01*
X654954Y7155D01*
X654999Y7035D01*
X655009Y6995D01*
X655019Y6950D01*
X655024Y6910D01*
X655034Y6865D01*
Y6695D01*
X655024Y6650D01*
X655019Y6610D01*
X655009Y6565D01*
X654999Y6525D01*
X654954Y6405D01*
X654914Y6325D01*
X654889Y6290D01*
X654869Y6255D01*
X654839Y6220D01*
X654814Y6185D01*
X654784Y6155D01*
Y3730D01*
X654774Y3605D01*
X654734Y3480D01*
X654674Y3370D01*
X654594Y3270D01*
X654494Y3190D01*
X654384Y3130D01*
X654259Y3090D01*
X654134Y3080D01*
G37*
G36*
G01X677756D02*
X677631Y3090D01*
X677506Y3130D01*
X677396Y3190D01*
X677296Y3270D01*
X677216Y3370D01*
X677156Y3480D01*
X677116Y3605D01*
X677106Y3730D01*
Y6160D01*
X677076Y6190D01*
X676976Y6330D01*
X676956Y6370D01*
X676941Y6405D01*
X676921Y6445D01*
X676906Y6485D01*
X676896Y6525D01*
X676881Y6570D01*
X676876Y6610D01*
X676866Y6650D01*
X676861Y6695D01*
Y6735D01*
X676856Y6780D01*
X676861Y6825D01*
Y6865D01*
X676866Y6910D01*
X676876Y6950D01*
X676881Y6990D01*
X676896Y7035D01*
X676906Y7075D01*
X676921Y7115D01*
X676941Y7155D01*
X676956Y7190D01*
X676976Y7230D01*
X677076Y7370D01*
X677106Y7400D01*
Y9530D01*
X677116Y9655D01*
X677156Y9780D01*
X677216Y9890D01*
X677296Y9990D01*
X677396Y10070D01*
X677506Y10130D01*
X677631Y10170D01*
X677756Y10180D01*
X677881Y10170D01*
X678006Y10130D01*
X678116Y10070D01*
X678216Y9990D01*
X678296Y9890D01*
X678356Y9780D01*
X678396Y9655D01*
X678406Y9530D01*
Y7405D01*
X678436Y7375D01*
X678461Y7340D01*
X678491Y7305D01*
X678511Y7270D01*
X678536Y7235D01*
X678576Y7155D01*
X678621Y7035D01*
X678631Y6995D01*
X678641Y6950D01*
X678646Y6910D01*
X678656Y6865D01*
Y6695D01*
X678646Y6650D01*
X678641Y6610D01*
X678631Y6565D01*
X678621Y6525D01*
X678576Y6405D01*
X678536Y6325D01*
X678511Y6290D01*
X678491Y6255D01*
X678461Y6220D01*
X678436Y6185D01*
X678406Y6155D01*
Y3730D01*
X678396Y3605D01*
X678356Y3480D01*
X678296Y3370D01*
X678216Y3270D01*
X678116Y3190D01*
X678006Y3130D01*
X677881Y3090D01*
X677756Y3080D01*
G37*
G36*
G01X673031D02*
X672906Y3090D01*
X672781Y3130D01*
X672671Y3190D01*
X672571Y3270D01*
X672491Y3370D01*
X672431Y3480D01*
X672391Y3605D01*
X672381Y3730D01*
Y6160D01*
X672351Y6190D01*
X672251Y6330D01*
X672231Y6370D01*
X672216Y6405D01*
X672196Y6445D01*
X672181Y6485D01*
X672171Y6525D01*
X672156Y6570D01*
X672151Y6610D01*
X672141Y6650D01*
X672136Y6695D01*
Y6735D01*
X672131Y6780D01*
X672136Y6825D01*
Y6865D01*
X672141Y6910D01*
X672151Y6950D01*
X672156Y6990D01*
X672171Y7035D01*
X672181Y7075D01*
X672196Y7115D01*
X672216Y7155D01*
X672231Y7190D01*
X672251Y7230D01*
X672351Y7370D01*
X672381Y7400D01*
Y9530D01*
X672391Y9655D01*
X672431Y9780D01*
X672491Y9890D01*
X672571Y9990D01*
X672671Y10070D01*
X672781Y10130D01*
X672906Y10170D01*
X673031Y10180D01*
X673156Y10170D01*
X673281Y10130D01*
X673391Y10070D01*
X673491Y9990D01*
X673571Y9890D01*
X673631Y9780D01*
X673671Y9655D01*
X673681Y9530D01*
Y7405D01*
X673711Y7375D01*
X673736Y7340D01*
X673766Y7305D01*
X673786Y7270D01*
X673811Y7235D01*
X673851Y7155D01*
X673896Y7035D01*
X673906Y6995D01*
X673916Y6950D01*
X673921Y6910D01*
X673931Y6865D01*
Y6695D01*
X673921Y6650D01*
X673916Y6610D01*
X673906Y6565D01*
X673896Y6525D01*
X673851Y6405D01*
X673811Y6325D01*
X673786Y6290D01*
X673766Y6255D01*
X673736Y6220D01*
X673711Y6185D01*
X673681Y6155D01*
Y3730D01*
X673671Y3605D01*
X673631Y3480D01*
X673571Y3370D01*
X673491Y3270D01*
X673391Y3190D01*
X673281Y3130D01*
X673156Y3090D01*
X673031Y3080D01*
G37*
G36*
G01X668307D02*
X668182Y3090D01*
X668057Y3130D01*
X667947Y3190D01*
X667847Y3270D01*
X667767Y3370D01*
X667707Y3480D01*
X667667Y3605D01*
X667657Y3730D01*
Y6160D01*
X667627Y6190D01*
X667527Y6330D01*
X667507Y6370D01*
X667492Y6405D01*
X667472Y6445D01*
X667457Y6485D01*
X667447Y6525D01*
X667432Y6570D01*
X667427Y6610D01*
X667417Y6650D01*
X667412Y6695D01*
Y6735D01*
X667407Y6780D01*
X667412Y6825D01*
Y6865D01*
X667417Y6910D01*
X667427Y6950D01*
X667432Y6990D01*
X667447Y7035D01*
X667457Y7075D01*
X667472Y7115D01*
X667492Y7155D01*
X667507Y7190D01*
X667527Y7230D01*
X667627Y7370D01*
X667657Y7400D01*
Y9530D01*
X667667Y9655D01*
X667707Y9780D01*
X667767Y9890D01*
X667847Y9990D01*
X667947Y10070D01*
X668057Y10130D01*
X668182Y10170D01*
X668307Y10180D01*
X668432Y10170D01*
X668557Y10130D01*
X668667Y10070D01*
X668767Y9990D01*
X668847Y9890D01*
X668907Y9780D01*
X668947Y9655D01*
X668957Y9530D01*
Y7405D01*
X668987Y7375D01*
X669012Y7340D01*
X669042Y7305D01*
X669062Y7270D01*
X669087Y7235D01*
X669127Y7155D01*
X669172Y7035D01*
X669182Y6995D01*
X669192Y6950D01*
X669197Y6910D01*
X669207Y6865D01*
Y6695D01*
X669197Y6650D01*
X669192Y6610D01*
X669182Y6565D01*
X669172Y6525D01*
X669127Y6405D01*
X669087Y6325D01*
X669062Y6290D01*
X669042Y6255D01*
X669012Y6220D01*
X668987Y6185D01*
X668957Y6155D01*
Y3730D01*
X668947Y3605D01*
X668907Y3480D01*
X668847Y3370D01*
X668767Y3270D01*
X668667Y3190D01*
X668557Y3130D01*
X668432Y3090D01*
X668307Y3080D01*
G37*
G36*
G01X691929D02*
X691804Y3090D01*
X691679Y3130D01*
X691569Y3190D01*
X691469Y3270D01*
X691389Y3370D01*
X691329Y3480D01*
X691289Y3605D01*
X691279Y3730D01*
Y6160D01*
X691249Y6190D01*
X691149Y6330D01*
X691129Y6370D01*
X691114Y6405D01*
X691094Y6445D01*
X691079Y6485D01*
X691069Y6525D01*
X691054Y6570D01*
X691049Y6610D01*
X691039Y6650D01*
X691034Y6695D01*
Y6735D01*
X691029Y6780D01*
X691034Y6825D01*
Y6865D01*
X691039Y6910D01*
X691049Y6950D01*
X691054Y6990D01*
X691069Y7035D01*
X691079Y7075D01*
X691094Y7115D01*
X691114Y7155D01*
X691129Y7190D01*
X691149Y7230D01*
X691249Y7370D01*
X691279Y7400D01*
Y9530D01*
X691289Y9655D01*
X691329Y9780D01*
X691389Y9890D01*
X691469Y9990D01*
X691569Y10070D01*
X691679Y10130D01*
X691804Y10170D01*
X691929Y10180D01*
X692054Y10170D01*
X692179Y10130D01*
X692289Y10070D01*
X692389Y9990D01*
X692469Y9890D01*
X692529Y9780D01*
X692569Y9655D01*
X692579Y9530D01*
Y7405D01*
X692609Y7375D01*
X692634Y7340D01*
X692664Y7305D01*
X692684Y7270D01*
X692709Y7235D01*
X692749Y7155D01*
X692794Y7035D01*
X692804Y6995D01*
X692814Y6950D01*
X692819Y6910D01*
X692829Y6865D01*
Y6695D01*
X692819Y6650D01*
X692814Y6610D01*
X692804Y6565D01*
X692794Y6525D01*
X692749Y6405D01*
X692709Y6325D01*
X692684Y6290D01*
X692664Y6255D01*
X692634Y6220D01*
X692609Y6185D01*
X692579Y6155D01*
Y3730D01*
X692569Y3605D01*
X692529Y3480D01*
X692469Y3370D01*
X692389Y3270D01*
X692289Y3190D01*
X692179Y3130D01*
X692054Y3090D01*
X691929Y3080D01*
G37*
G36*
G01X687204D02*
X687079Y3090D01*
X686954Y3130D01*
X686844Y3190D01*
X686744Y3270D01*
X686664Y3370D01*
X686604Y3480D01*
X686564Y3605D01*
X686554Y3730D01*
Y6160D01*
X686524Y6190D01*
X686424Y6330D01*
X686404Y6370D01*
X686389Y6405D01*
X686369Y6445D01*
X686354Y6485D01*
X686344Y6525D01*
X686329Y6570D01*
X686324Y6610D01*
X686314Y6650D01*
X686309Y6695D01*
Y6735D01*
X686304Y6780D01*
X686309Y6825D01*
Y6865D01*
X686314Y6910D01*
X686324Y6950D01*
X686329Y6990D01*
X686344Y7035D01*
X686354Y7075D01*
X686369Y7115D01*
X686389Y7155D01*
X686404Y7190D01*
X686424Y7230D01*
X686524Y7370D01*
X686554Y7400D01*
Y9530D01*
X686564Y9655D01*
X686604Y9780D01*
X686664Y9890D01*
X686744Y9990D01*
X686844Y10070D01*
X686954Y10130D01*
X687079Y10170D01*
X687204Y10180D01*
X687329Y10170D01*
X687454Y10130D01*
X687564Y10070D01*
X687664Y9990D01*
X687744Y9890D01*
X687804Y9780D01*
X687844Y9655D01*
X687854Y9530D01*
Y7405D01*
X687884Y7375D01*
X687909Y7340D01*
X687939Y7305D01*
X687959Y7270D01*
X687984Y7235D01*
X688024Y7155D01*
X688069Y7035D01*
X688079Y6995D01*
X688089Y6950D01*
X688094Y6910D01*
X688104Y6865D01*
Y6695D01*
X688094Y6650D01*
X688089Y6610D01*
X688079Y6565D01*
X688069Y6525D01*
X688024Y6405D01*
X687984Y6325D01*
X687959Y6290D01*
X687939Y6255D01*
X687909Y6220D01*
X687884Y6185D01*
X687854Y6155D01*
Y3730D01*
X687844Y3605D01*
X687804Y3480D01*
X687744Y3370D01*
X687664Y3270D01*
X687564Y3190D01*
X687454Y3130D01*
X687329Y3090D01*
X687204Y3080D01*
G37*
G36*
G01X682480D02*
X682355Y3090D01*
X682230Y3130D01*
X682120Y3190D01*
X682020Y3270D01*
X681940Y3370D01*
X681880Y3480D01*
X681840Y3605D01*
X681830Y3730D01*
Y6160D01*
X681800Y6190D01*
X681700Y6330D01*
X681680Y6370D01*
X681665Y6405D01*
X681645Y6445D01*
X681630Y6485D01*
X681620Y6525D01*
X681605Y6570D01*
X681600Y6610D01*
X681590Y6650D01*
X681585Y6695D01*
Y6735D01*
X681580Y6780D01*
X681585Y6825D01*
Y6865D01*
X681590Y6910D01*
X681600Y6950D01*
X681605Y6990D01*
X681620Y7035D01*
X681630Y7075D01*
X681645Y7115D01*
X681665Y7155D01*
X681680Y7190D01*
X681700Y7230D01*
X681800Y7370D01*
X681830Y7400D01*
Y9530D01*
X681840Y9655D01*
X681880Y9780D01*
X681940Y9890D01*
X682020Y9990D01*
X682120Y10070D01*
X682230Y10130D01*
X682355Y10170D01*
X682480Y10180D01*
X682605Y10170D01*
X682730Y10130D01*
X682840Y10070D01*
X682940Y9990D01*
X683020Y9890D01*
X683080Y9780D01*
X683120Y9655D01*
X683130Y9530D01*
Y7405D01*
X683160Y7375D01*
X683185Y7340D01*
X683215Y7305D01*
X683235Y7270D01*
X683260Y7235D01*
X683300Y7155D01*
X683345Y7035D01*
X683355Y6995D01*
X683365Y6950D01*
X683370Y6910D01*
X683380Y6865D01*
Y6695D01*
X683370Y6650D01*
X683365Y6610D01*
X683355Y6565D01*
X683345Y6525D01*
X683300Y6405D01*
X683260Y6325D01*
X683235Y6290D01*
X683215Y6255D01*
X683185Y6220D01*
X683160Y6185D01*
X683130Y6155D01*
Y3730D01*
X683120Y3605D01*
X683080Y3480D01*
X683020Y3370D01*
X682940Y3270D01*
X682840Y3190D01*
X682730Y3130D01*
X682605Y3090D01*
X682480Y3080D01*
G37*
G36*
G01X710827D02*
X710702Y3090D01*
X710577Y3130D01*
X710467Y3190D01*
X710367Y3270D01*
X710287Y3370D01*
X710227Y3480D01*
X710187Y3605D01*
X710177Y3730D01*
Y6160D01*
X710147Y6190D01*
X710047Y6330D01*
X710027Y6370D01*
X710012Y6405D01*
X709992Y6445D01*
X709977Y6485D01*
X709967Y6525D01*
X709952Y6570D01*
X709947Y6610D01*
X709937Y6650D01*
X709932Y6695D01*
Y6735D01*
X709927Y6780D01*
X709932Y6825D01*
Y6865D01*
X709937Y6910D01*
X709947Y6950D01*
X709952Y6990D01*
X709967Y7035D01*
X709977Y7075D01*
X709992Y7115D01*
X710012Y7155D01*
X710027Y7190D01*
X710047Y7230D01*
X710147Y7370D01*
X710177Y7400D01*
Y9530D01*
X710187Y9655D01*
X710227Y9780D01*
X710287Y9890D01*
X710367Y9990D01*
X710467Y10070D01*
X710577Y10130D01*
X710702Y10170D01*
X710827Y10180D01*
X710952Y10170D01*
X711077Y10130D01*
X711187Y10070D01*
X711287Y9990D01*
X711367Y9890D01*
X711427Y9780D01*
X711467Y9655D01*
X711477Y9530D01*
Y7405D01*
X711507Y7375D01*
X711532Y7340D01*
X711562Y7305D01*
X711582Y7270D01*
X711607Y7235D01*
X711647Y7155D01*
X711692Y7035D01*
X711702Y6995D01*
X711712Y6950D01*
X711717Y6910D01*
X711727Y6865D01*
Y6695D01*
X711717Y6650D01*
X711712Y6610D01*
X711702Y6565D01*
X711692Y6525D01*
X711647Y6405D01*
X711607Y6325D01*
X711582Y6290D01*
X711562Y6255D01*
X711532Y6220D01*
X711507Y6185D01*
X711477Y6155D01*
Y3730D01*
X711467Y3605D01*
X711427Y3480D01*
X711367Y3370D01*
X711287Y3270D01*
X711187Y3190D01*
X711077Y3130D01*
X710952Y3090D01*
X710827Y3080D01*
G37*
G36*
G01X706102D02*
X705977Y3090D01*
X705852Y3130D01*
X705742Y3190D01*
X705642Y3270D01*
X705562Y3370D01*
X705502Y3480D01*
X705462Y3605D01*
X705452Y3730D01*
Y6160D01*
X705422Y6190D01*
X705322Y6330D01*
X705302Y6370D01*
X705287Y6405D01*
X705267Y6445D01*
X705252Y6485D01*
X705242Y6525D01*
X705227Y6570D01*
X705222Y6610D01*
X705212Y6650D01*
X705207Y6695D01*
Y6735D01*
X705202Y6780D01*
X705207Y6825D01*
Y6865D01*
X705212Y6910D01*
X705222Y6950D01*
X705227Y6990D01*
X705242Y7035D01*
X705252Y7075D01*
X705267Y7115D01*
X705287Y7155D01*
X705302Y7190D01*
X705322Y7230D01*
X705422Y7370D01*
X705452Y7400D01*
Y9530D01*
X705462Y9655D01*
X705502Y9780D01*
X705562Y9890D01*
X705642Y9990D01*
X705742Y10070D01*
X705852Y10130D01*
X705977Y10170D01*
X706102Y10180D01*
X706227Y10170D01*
X706352Y10130D01*
X706462Y10070D01*
X706562Y9990D01*
X706642Y9890D01*
X706702Y9780D01*
X706742Y9655D01*
X706752Y9530D01*
Y7405D01*
X706782Y7375D01*
X706807Y7340D01*
X706837Y7305D01*
X706857Y7270D01*
X706882Y7235D01*
X706922Y7155D01*
X706967Y7035D01*
X706977Y6995D01*
X706987Y6950D01*
X706992Y6910D01*
X707002Y6865D01*
Y6695D01*
X706992Y6650D01*
X706987Y6610D01*
X706977Y6565D01*
X706967Y6525D01*
X706922Y6405D01*
X706882Y6325D01*
X706857Y6290D01*
X706837Y6255D01*
X706807Y6220D01*
X706782Y6185D01*
X706752Y6155D01*
Y3730D01*
X706742Y3605D01*
X706702Y3480D01*
X706642Y3370D01*
X706562Y3270D01*
X706462Y3190D01*
X706352Y3130D01*
X706227Y3090D01*
X706102Y3080D01*
G37*
G36*
G01X701378D02*
X701253Y3090D01*
X701128Y3130D01*
X701018Y3190D01*
X700918Y3270D01*
X700838Y3370D01*
X700778Y3480D01*
X700738Y3605D01*
X700728Y3730D01*
Y6160D01*
X700698Y6190D01*
X700598Y6330D01*
X700578Y6370D01*
X700563Y6405D01*
X700543Y6445D01*
X700528Y6485D01*
X700518Y6525D01*
X700503Y6570D01*
X700498Y6610D01*
X700488Y6650D01*
X700483Y6695D01*
Y6735D01*
X700478Y6780D01*
X700483Y6825D01*
Y6865D01*
X700488Y6910D01*
X700498Y6950D01*
X700503Y6990D01*
X700518Y7035D01*
X700528Y7075D01*
X700543Y7115D01*
X700563Y7155D01*
X700578Y7190D01*
X700598Y7230D01*
X700698Y7370D01*
X700728Y7400D01*
Y9530D01*
X700738Y9655D01*
X700778Y9780D01*
X700838Y9890D01*
X700918Y9990D01*
X701018Y10070D01*
X701128Y10130D01*
X701253Y10170D01*
X701378Y10180D01*
X701503Y10170D01*
X701628Y10130D01*
X701738Y10070D01*
X701838Y9990D01*
X701918Y9890D01*
X701978Y9780D01*
X702018Y9655D01*
X702028Y9530D01*
Y7405D01*
X702058Y7375D01*
X702083Y7340D01*
X702113Y7305D01*
X702133Y7270D01*
X702158Y7235D01*
X702198Y7155D01*
X702243Y7035D01*
X702253Y6995D01*
X702263Y6950D01*
X702268Y6910D01*
X702278Y6865D01*
Y6695D01*
X702268Y6650D01*
X702263Y6610D01*
X702253Y6565D01*
X702243Y6525D01*
X702198Y6405D01*
X702158Y6325D01*
X702133Y6290D01*
X702113Y6255D01*
X702083Y6220D01*
X702058Y6185D01*
X702028Y6155D01*
Y3730D01*
X702018Y3605D01*
X701978Y3480D01*
X701918Y3370D01*
X701838Y3270D01*
X701738Y3190D01*
X701628Y3130D01*
X701503Y3090D01*
X701378Y3080D01*
G37*
G36*
G01X696653D02*
X696528Y3090D01*
X696403Y3130D01*
X696293Y3190D01*
X696193Y3270D01*
X696113Y3370D01*
X696053Y3480D01*
X696013Y3605D01*
X696003Y3730D01*
Y6160D01*
X695973Y6190D01*
X695873Y6330D01*
X695853Y6370D01*
X695838Y6405D01*
X695818Y6445D01*
X695803Y6485D01*
X695793Y6525D01*
X695778Y6570D01*
X695773Y6610D01*
X695763Y6650D01*
X695758Y6695D01*
Y6735D01*
X695753Y6780D01*
X695758Y6825D01*
Y6865D01*
X695763Y6910D01*
X695773Y6950D01*
X695778Y6990D01*
X695793Y7035D01*
X695803Y7075D01*
X695818Y7115D01*
X695838Y7155D01*
X695853Y7190D01*
X695873Y7230D01*
X695973Y7370D01*
X696003Y7400D01*
Y9530D01*
X696013Y9655D01*
X696053Y9780D01*
X696113Y9890D01*
X696193Y9990D01*
X696293Y10070D01*
X696403Y10130D01*
X696528Y10170D01*
X696653Y10180D01*
X696778Y10170D01*
X696903Y10130D01*
X697013Y10070D01*
X697113Y9990D01*
X697193Y9890D01*
X697253Y9780D01*
X697293Y9655D01*
X697303Y9530D01*
Y7405D01*
X697333Y7375D01*
X697358Y7340D01*
X697388Y7305D01*
X697408Y7270D01*
X697433Y7235D01*
X697473Y7155D01*
X697518Y7035D01*
X697528Y6995D01*
X697538Y6950D01*
X697543Y6910D01*
X697553Y6865D01*
Y6695D01*
X697543Y6650D01*
X697538Y6610D01*
X697528Y6565D01*
X697518Y6525D01*
X697473Y6405D01*
X697433Y6325D01*
X697408Y6290D01*
X697388Y6255D01*
X697358Y6220D01*
X697333Y6185D01*
X697303Y6155D01*
Y3730D01*
X697293Y3605D01*
X697253Y3480D01*
X697193Y3370D01*
X697113Y3270D01*
X697013Y3190D01*
X696903Y3130D01*
X696778Y3090D01*
X696653Y3080D01*
G37*
G36*
G01X725000D02*
X724875Y3090D01*
X724750Y3130D01*
X724640Y3190D01*
X724540Y3270D01*
X724460Y3370D01*
X724400Y3480D01*
X724360Y3605D01*
X724350Y3730D01*
Y6160D01*
X724320Y6190D01*
X724220Y6330D01*
X724200Y6370D01*
X724185Y6405D01*
X724165Y6445D01*
X724150Y6485D01*
X724140Y6525D01*
X724125Y6570D01*
X724120Y6610D01*
X724110Y6650D01*
X724105Y6695D01*
Y6735D01*
X724100Y6780D01*
X724105Y6825D01*
Y6865D01*
X724110Y6910D01*
X724120Y6950D01*
X724125Y6990D01*
X724140Y7035D01*
X724150Y7075D01*
X724165Y7115D01*
X724185Y7155D01*
X724200Y7190D01*
X724220Y7230D01*
X724320Y7370D01*
X724350Y7400D01*
Y9530D01*
X724360Y9655D01*
X724400Y9780D01*
X724460Y9890D01*
X724540Y9990D01*
X724640Y10070D01*
X724750Y10130D01*
X724875Y10170D01*
X725000Y10180D01*
X725125Y10170D01*
X725250Y10130D01*
X725360Y10070D01*
X725460Y9990D01*
X725540Y9890D01*
X725600Y9780D01*
X725640Y9655D01*
X725650Y9530D01*
Y7405D01*
X725680Y7375D01*
X725705Y7340D01*
X725735Y7305D01*
X725755Y7270D01*
X725780Y7235D01*
X725820Y7155D01*
X725865Y7035D01*
X725875Y6995D01*
X725885Y6950D01*
X725890Y6910D01*
X725900Y6865D01*
Y6695D01*
X725890Y6650D01*
X725885Y6610D01*
X725875Y6565D01*
X725865Y6525D01*
X725820Y6405D01*
X725780Y6325D01*
X725755Y6290D01*
X725735Y6255D01*
X725705Y6220D01*
X725680Y6185D01*
X725650Y6155D01*
Y3730D01*
X725640Y3605D01*
X725600Y3480D01*
X725540Y3370D01*
X725460Y3270D01*
X725360Y3190D01*
X725250Y3130D01*
X725125Y3090D01*
X725000Y3080D01*
G37*
G36*
G01X720275D02*
X720150Y3090D01*
X720025Y3130D01*
X719915Y3190D01*
X719815Y3270D01*
X719735Y3370D01*
X719675Y3480D01*
X719635Y3605D01*
X719625Y3730D01*
Y6160D01*
X719595Y6190D01*
X719495Y6330D01*
X719475Y6370D01*
X719460Y6405D01*
X719440Y6445D01*
X719425Y6485D01*
X719415Y6525D01*
X719400Y6570D01*
X719395Y6610D01*
X719385Y6650D01*
X719380Y6695D01*
Y6735D01*
X719375Y6780D01*
X719380Y6825D01*
Y6865D01*
X719385Y6910D01*
X719395Y6950D01*
X719400Y6990D01*
X719415Y7035D01*
X719425Y7075D01*
X719440Y7115D01*
X719460Y7155D01*
X719475Y7190D01*
X719495Y7230D01*
X719595Y7370D01*
X719625Y7400D01*
Y9530D01*
X719635Y9655D01*
X719675Y9780D01*
X719735Y9890D01*
X719815Y9990D01*
X719915Y10070D01*
X720025Y10130D01*
X720150Y10170D01*
X720275Y10180D01*
X720400Y10170D01*
X720525Y10130D01*
X720635Y10070D01*
X720735Y9990D01*
X720815Y9890D01*
X720875Y9780D01*
X720915Y9655D01*
X720925Y9530D01*
Y7405D01*
X720955Y7375D01*
X720980Y7340D01*
X721010Y7305D01*
X721030Y7270D01*
X721055Y7235D01*
X721095Y7155D01*
X721140Y7035D01*
X721150Y6995D01*
X721160Y6950D01*
X721165Y6910D01*
X721175Y6865D01*
Y6695D01*
X721165Y6650D01*
X721160Y6610D01*
X721150Y6565D01*
X721140Y6525D01*
X721095Y6405D01*
X721055Y6325D01*
X721030Y6290D01*
X721010Y6255D01*
X720980Y6220D01*
X720955Y6185D01*
X720925Y6155D01*
Y3730D01*
X720915Y3605D01*
X720875Y3480D01*
X720815Y3370D01*
X720735Y3270D01*
X720635Y3190D01*
X720525Y3130D01*
X720400Y3090D01*
X720275Y3080D01*
G37*
G36*
G01X715551D02*
X715426Y3090D01*
X715301Y3130D01*
X715191Y3190D01*
X715091Y3270D01*
X715011Y3370D01*
X714951Y3480D01*
X714911Y3605D01*
X714901Y3730D01*
Y6160D01*
X714871Y6190D01*
X714771Y6330D01*
X714751Y6370D01*
X714736Y6405D01*
X714716Y6445D01*
X714701Y6485D01*
X714691Y6525D01*
X714676Y6570D01*
X714671Y6610D01*
X714661Y6650D01*
X714656Y6695D01*
Y6735D01*
X714651Y6780D01*
X714656Y6825D01*
Y6865D01*
X714661Y6910D01*
X714671Y6950D01*
X714676Y6990D01*
X714691Y7035D01*
X714701Y7075D01*
X714716Y7115D01*
X714736Y7155D01*
X714751Y7190D01*
X714771Y7230D01*
X714871Y7370D01*
X714901Y7400D01*
Y9530D01*
X714911Y9655D01*
X714951Y9780D01*
X715011Y9890D01*
X715091Y9990D01*
X715191Y10070D01*
X715301Y10130D01*
X715426Y10170D01*
X715551Y10180D01*
X715676Y10170D01*
X715801Y10130D01*
X715911Y10070D01*
X716011Y9990D01*
X716091Y9890D01*
X716151Y9780D01*
X716191Y9655D01*
X716201Y9530D01*
Y7405D01*
X716231Y7375D01*
X716256Y7340D01*
X716286Y7305D01*
X716306Y7270D01*
X716331Y7235D01*
X716371Y7155D01*
X716416Y7035D01*
X716426Y6995D01*
X716436Y6950D01*
X716441Y6910D01*
X716451Y6865D01*
Y6695D01*
X716441Y6650D01*
X716436Y6610D01*
X716426Y6565D01*
X716416Y6525D01*
X716371Y6405D01*
X716331Y6325D01*
X716306Y6290D01*
X716286Y6255D01*
X716256Y6220D01*
X716231Y6185D01*
X716201Y6155D01*
Y3730D01*
X716191Y3605D01*
X716151Y3480D01*
X716091Y3370D01*
X716011Y3270D01*
X715911Y3190D01*
X715801Y3130D01*
X715676Y3090D01*
X715551Y3080D01*
G37*
G36*
G01X739173D02*
X739048Y3090D01*
X738923Y3130D01*
X738813Y3190D01*
X738713Y3270D01*
X738633Y3370D01*
X738573Y3480D01*
X738533Y3605D01*
X738523Y3730D01*
Y6160D01*
X738493Y6190D01*
X738393Y6330D01*
X738373Y6370D01*
X738358Y6405D01*
X738338Y6445D01*
X738323Y6485D01*
X738313Y6525D01*
X738298Y6570D01*
X738293Y6610D01*
X738283Y6650D01*
X738278Y6695D01*
Y6735D01*
X738273Y6780D01*
X738278Y6825D01*
Y6865D01*
X738283Y6910D01*
X738293Y6950D01*
X738298Y6990D01*
X738313Y7035D01*
X738323Y7075D01*
X738338Y7115D01*
X738358Y7155D01*
X738373Y7190D01*
X738393Y7230D01*
X738493Y7370D01*
X738523Y7400D01*
Y9530D01*
X738533Y9655D01*
X738573Y9780D01*
X738633Y9890D01*
X738713Y9990D01*
X738813Y10070D01*
X738923Y10130D01*
X739048Y10170D01*
X739173Y10180D01*
X739298Y10170D01*
X739423Y10130D01*
X739533Y10070D01*
X739633Y9990D01*
X739713Y9890D01*
X739773Y9780D01*
X739813Y9655D01*
X739823Y9530D01*
Y7405D01*
X739853Y7375D01*
X739878Y7340D01*
X739908Y7305D01*
X739928Y7270D01*
X739953Y7235D01*
X739993Y7155D01*
X740038Y7035D01*
X740048Y6995D01*
X740058Y6950D01*
X740063Y6910D01*
X740073Y6865D01*
Y6695D01*
X740063Y6650D01*
X740058Y6610D01*
X740048Y6565D01*
X740038Y6525D01*
X739993Y6405D01*
X739953Y6325D01*
X739928Y6290D01*
X739908Y6255D01*
X739878Y6220D01*
X739853Y6185D01*
X739823Y6155D01*
Y3730D01*
X739813Y3605D01*
X739773Y3480D01*
X739713Y3370D01*
X739633Y3270D01*
X739533Y3190D01*
X739423Y3130D01*
X739298Y3090D01*
X739173Y3080D01*
G37*
G36*
G01X734449D02*
X734324Y3090D01*
X734199Y3130D01*
X734089Y3190D01*
X733989Y3270D01*
X733909Y3370D01*
X733849Y3480D01*
X733809Y3605D01*
X733799Y3730D01*
Y6160D01*
X733769Y6190D01*
X733669Y6330D01*
X733649Y6370D01*
X733634Y6405D01*
X733614Y6445D01*
X733599Y6485D01*
X733589Y6525D01*
X733574Y6570D01*
X733569Y6610D01*
X733559Y6650D01*
X733554Y6695D01*
Y6735D01*
X733549Y6780D01*
X733554Y6825D01*
Y6865D01*
X733559Y6910D01*
X733569Y6950D01*
X733574Y6990D01*
X733589Y7035D01*
X733599Y7075D01*
X733614Y7115D01*
X733634Y7155D01*
X733649Y7190D01*
X733669Y7230D01*
X733769Y7370D01*
X733799Y7400D01*
Y9530D01*
X733809Y9655D01*
X733849Y9780D01*
X733909Y9890D01*
X733989Y9990D01*
X734089Y10070D01*
X734199Y10130D01*
X734324Y10170D01*
X734449Y10180D01*
X734574Y10170D01*
X734699Y10130D01*
X734809Y10070D01*
X734909Y9990D01*
X734989Y9890D01*
X735049Y9780D01*
X735089Y9655D01*
X735099Y9530D01*
Y7405D01*
X735129Y7375D01*
X735154Y7340D01*
X735184Y7305D01*
X735204Y7270D01*
X735229Y7235D01*
X735269Y7155D01*
X735314Y7035D01*
X735324Y6995D01*
X735334Y6950D01*
X735339Y6910D01*
X735349Y6865D01*
Y6695D01*
X735339Y6650D01*
X735334Y6610D01*
X735324Y6565D01*
X735314Y6525D01*
X735269Y6405D01*
X735229Y6325D01*
X735204Y6290D01*
X735184Y6255D01*
X735154Y6220D01*
X735129Y6185D01*
X735099Y6155D01*
Y3730D01*
X735089Y3605D01*
X735049Y3480D01*
X734989Y3370D01*
X734909Y3270D01*
X734809Y3190D01*
X734699Y3130D01*
X734574Y3090D01*
X734449Y3080D01*
G37*
G36*
G01X729724D02*
X729599Y3090D01*
X729474Y3130D01*
X729364Y3190D01*
X729264Y3270D01*
X729184Y3370D01*
X729124Y3480D01*
X729084Y3605D01*
X729074Y3730D01*
Y6160D01*
X729044Y6190D01*
X728944Y6330D01*
X728924Y6370D01*
X728909Y6405D01*
X728889Y6445D01*
X728874Y6485D01*
X728864Y6525D01*
X728849Y6570D01*
X728844Y6610D01*
X728834Y6650D01*
X728829Y6695D01*
Y6735D01*
X728824Y6780D01*
X728829Y6825D01*
Y6865D01*
X728834Y6910D01*
X728844Y6950D01*
X728849Y6990D01*
X728864Y7035D01*
X728874Y7075D01*
X728889Y7115D01*
X728909Y7155D01*
X728924Y7190D01*
X728944Y7230D01*
X729044Y7370D01*
X729074Y7400D01*
Y9530D01*
X729084Y9655D01*
X729124Y9780D01*
X729184Y9890D01*
X729264Y9990D01*
X729364Y10070D01*
X729474Y10130D01*
X729599Y10170D01*
X729724Y10180D01*
X729849Y10170D01*
X729974Y10130D01*
X730084Y10070D01*
X730184Y9990D01*
X730264Y9890D01*
X730324Y9780D01*
X730364Y9655D01*
X730374Y9530D01*
Y7405D01*
X730404Y7375D01*
X730429Y7340D01*
X730459Y7305D01*
X730479Y7270D01*
X730504Y7235D01*
X730544Y7155D01*
X730589Y7035D01*
X730599Y6995D01*
X730609Y6950D01*
X730614Y6910D01*
X730624Y6865D01*
Y6695D01*
X730614Y6650D01*
X730609Y6610D01*
X730599Y6565D01*
X730589Y6525D01*
X730544Y6405D01*
X730504Y6325D01*
X730479Y6290D01*
X730459Y6255D01*
X730429Y6220D01*
X730404Y6185D01*
X730374Y6155D01*
Y3730D01*
X730364Y3605D01*
X730324Y3480D01*
X730264Y3370D01*
X730184Y3270D01*
X730084Y3190D01*
X729974Y3130D01*
X729849Y3090D01*
X729724Y3080D01*
G37*
G36*
G01X753346D02*
X753221Y3090D01*
X753096Y3130D01*
X752986Y3190D01*
X752886Y3270D01*
X752806Y3370D01*
X752746Y3480D01*
X752706Y3605D01*
X752696Y3730D01*
Y6160D01*
X752666Y6190D01*
X752566Y6330D01*
X752546Y6370D01*
X752531Y6405D01*
X752511Y6445D01*
X752496Y6485D01*
X752486Y6525D01*
X752471Y6570D01*
X752466Y6610D01*
X752456Y6650D01*
X752451Y6695D01*
Y6735D01*
X752446Y6780D01*
X752451Y6825D01*
Y6865D01*
X752456Y6910D01*
X752466Y6950D01*
X752471Y6990D01*
X752486Y7035D01*
X752496Y7075D01*
X752511Y7115D01*
X752531Y7155D01*
X752546Y7190D01*
X752566Y7230D01*
X752666Y7370D01*
X752696Y7400D01*
Y9530D01*
X752706Y9655D01*
X752746Y9780D01*
X752806Y9890D01*
X752886Y9990D01*
X752986Y10070D01*
X753096Y10130D01*
X753221Y10170D01*
X753346Y10180D01*
X753471Y10170D01*
X753596Y10130D01*
X753706Y10070D01*
X753806Y9990D01*
X753886Y9890D01*
X753946Y9780D01*
X753986Y9655D01*
X753996Y9530D01*
Y7405D01*
X754026Y7375D01*
X754051Y7340D01*
X754081Y7305D01*
X754101Y7270D01*
X754126Y7235D01*
X754166Y7155D01*
X754211Y7035D01*
X754221Y6995D01*
X754231Y6950D01*
X754236Y6910D01*
X754246Y6865D01*
Y6695D01*
X754236Y6650D01*
X754231Y6610D01*
X754221Y6565D01*
X754211Y6525D01*
X754166Y6405D01*
X754126Y6325D01*
X754101Y6290D01*
X754081Y6255D01*
X754051Y6220D01*
X754026Y6185D01*
X753996Y6155D01*
Y3730D01*
X753986Y3605D01*
X753946Y3480D01*
X753886Y3370D01*
X753806Y3270D01*
X753706Y3190D01*
X753596Y3130D01*
X753471Y3090D01*
X753346Y3080D01*
G37*
G36*
G01X748622D02*
X748497Y3090D01*
X748372Y3130D01*
X748262Y3190D01*
X748162Y3270D01*
X748082Y3370D01*
X748022Y3480D01*
X747982Y3605D01*
X747972Y3730D01*
Y6160D01*
X747942Y6190D01*
X747842Y6330D01*
X747822Y6370D01*
X747807Y6405D01*
X747787Y6445D01*
X747772Y6485D01*
X747762Y6525D01*
X747747Y6570D01*
X747742Y6610D01*
X747732Y6650D01*
X747727Y6695D01*
Y6735D01*
X747722Y6780D01*
X747727Y6825D01*
Y6865D01*
X747732Y6910D01*
X747742Y6950D01*
X747747Y6990D01*
X747762Y7035D01*
X747772Y7075D01*
X747787Y7115D01*
X747807Y7155D01*
X747822Y7190D01*
X747842Y7230D01*
X747942Y7370D01*
X747972Y7400D01*
Y9530D01*
X747982Y9655D01*
X748022Y9780D01*
X748082Y9890D01*
X748162Y9990D01*
X748262Y10070D01*
X748372Y10130D01*
X748497Y10170D01*
X748622Y10180D01*
X748747Y10170D01*
X748872Y10130D01*
X748982Y10070D01*
X749082Y9990D01*
X749162Y9890D01*
X749222Y9780D01*
X749262Y9655D01*
X749272Y9530D01*
Y7405D01*
X749302Y7375D01*
X749327Y7340D01*
X749357Y7305D01*
X749377Y7270D01*
X749402Y7235D01*
X749442Y7155D01*
X749487Y7035D01*
X749497Y6995D01*
X749507Y6950D01*
X749512Y6910D01*
X749522Y6865D01*
Y6695D01*
X749512Y6650D01*
X749507Y6610D01*
X749497Y6565D01*
X749487Y6525D01*
X749442Y6405D01*
X749402Y6325D01*
X749377Y6290D01*
X749357Y6255D01*
X749327Y6220D01*
X749302Y6185D01*
X749272Y6155D01*
Y3730D01*
X749262Y3605D01*
X749222Y3480D01*
X749162Y3370D01*
X749082Y3270D01*
X748982Y3190D01*
X748872Y3130D01*
X748747Y3090D01*
X748622Y3080D01*
G37*
G36*
G01X743897D02*
X743772Y3090D01*
X743647Y3130D01*
X743537Y3190D01*
X743437Y3270D01*
X743357Y3370D01*
X743297Y3480D01*
X743257Y3605D01*
X743247Y3730D01*
Y6160D01*
X743217Y6190D01*
X743117Y6330D01*
X743097Y6370D01*
X743082Y6405D01*
X743062Y6445D01*
X743047Y6485D01*
X743037Y6525D01*
X743022Y6570D01*
X743017Y6610D01*
X743007Y6650D01*
X743002Y6695D01*
Y6735D01*
X742997Y6780D01*
X743002Y6825D01*
Y6865D01*
X743007Y6910D01*
X743017Y6950D01*
X743022Y6990D01*
X743037Y7035D01*
X743047Y7075D01*
X743062Y7115D01*
X743082Y7155D01*
X743097Y7190D01*
X743117Y7230D01*
X743217Y7370D01*
X743247Y7400D01*
Y9530D01*
X743257Y9655D01*
X743297Y9780D01*
X743357Y9890D01*
X743437Y9990D01*
X743537Y10070D01*
X743647Y10130D01*
X743772Y10170D01*
X743897Y10180D01*
X744022Y10170D01*
X744147Y10130D01*
X744257Y10070D01*
X744357Y9990D01*
X744437Y9890D01*
X744497Y9780D01*
X744537Y9655D01*
X744547Y9530D01*
Y7405D01*
X744577Y7375D01*
X744602Y7340D01*
X744632Y7305D01*
X744652Y7270D01*
X744677Y7235D01*
X744717Y7155D01*
X744762Y7035D01*
X744772Y6995D01*
X744782Y6950D01*
X744787Y6910D01*
X744797Y6865D01*
Y6695D01*
X744787Y6650D01*
X744782Y6610D01*
X744772Y6565D01*
X744762Y6525D01*
X744717Y6405D01*
X744677Y6325D01*
X744652Y6290D01*
X744632Y6255D01*
X744602Y6220D01*
X744577Y6185D01*
X744547Y6155D01*
Y3730D01*
X744537Y3605D01*
X744497Y3480D01*
X744437Y3370D01*
X744357Y3270D01*
X744257Y3190D01*
X744147Y3130D01*
X744022Y3090D01*
X743897Y3080D01*
G37*
M02*
